(kicad_sch
	(version 20250114)
	(generator "eeschema")
	(generator_version "9.0")
	(paper "A3")
	(title_block
		(title "SO-DIMM DDR5 Tester")
		(date "2025-11-26")
		(rev "1.3.0")
		(company "Antmicro Ltd.")
		(comment 1 "www.antmicro.com")
		(comment 2 "Antmicro Ltd")
	)
	(text "1V2 Low noise"
		(exclude_from_sim no)
		(at 80.645 250.825 0)
		(effects
			(font
				(size 1.27 1.27)
			)
			(justify left bottom)
		)
	)
	(text "Power source"
		(exclude_from_sim no)
		(at 12.7 15.24 0)
		(effects
			(font
				(size 1.27 1.27)
				(thickness 0.254)
				(bold yes)
			)
			(justify left bottom)
		)
	)
	(text "Soft start delay time slot"
		(exclude_from_sim no)
		(at 205.105 220.345 0)
		(effects
			(font
				(size 1.27 1.27)
			)
			(justify left bottom)
		)
	)
	(text "DC-DC IO"
		(exclude_from_sim no)
		(at 213.995 146.685 0)
		(effects
			(font
				(size 1.27 1.27)
				(thickness 0.254)
				(bold yes)
			)
			(justify left bottom)
		)
	)
	(text "X"
		(exclude_from_sim no)
		(at 212.6128 225.425 0)
		(effects
			(font
				(size 1.27 1.27)
			)
			(justify left bottom)
		)
	)
	(text "I2C: 0x68"
		(exclude_from_sim no)
		(at 54.61 215.9 0)
		(effects
			(font
				(size 1.27 1.27)
			)
			(justify left bottom)
		)
	)
	(text "DC-DC INT"
		(exclude_from_sim no)
		(at 13.335 86.36 0)
		(effects
			(font
				(size 1.27 1.27)
				(thickness 0.254)
				(bold yes)
			)
			(justify left bottom)
		)
	)
	(text "NOTE:\noptional \nexternal divider "
		(exclude_from_sim no)
		(at 369.57 219.075 0)
		(effects
			(font
				(size 1.27 1.27)
			)
			(justify left bottom)
		)
	)
	(text "+3V3"
		(exclude_from_sim no)
		(at 203.835 225.425 0)
		(effects
			(font
				(size 1.27 1.27)
			)
			(justify left bottom)
		)
	)
	(text "ICT Testpoints"
		(exclude_from_sim no)
		(at 102.362 271.78 0)
		(effects
			(font
				(size 1.27 1.27)
				(thickness 0.254)
				(bold yes)
			)
			(justify left bottom)
		)
	)
	(text "X"
		(exclude_from_sim no)
		(at 217.17 233.68 0)
		(effects
			(font
				(size 1.27 1.27)
			)
			(justify left bottom)
		)
	)
	(text "7-15V"
		(exclude_from_sim no)
		(at 16.51 31.115 0)
		(effects
			(font
				(size 1.27 1.27)
			)
			(justify left bottom)
		)
	)
	(text "I2C: 0x60"
		(exclude_from_sim no)
		(at 138.43 265.43 0)
		(effects
			(font
				(size 1.27 1.27)
			)
			(justify left bottom)
		)
	)
	(text "1	2	3	4"
		(exclude_from_sim no)
		(at 24.765 223.52 0)
		(effects
			(font
				(size 1.27 1.27)
			)
			(justify left bottom)
		)
	)
	(text "NOTE:\noptional \nexternal divider "
		(exclude_from_sim no)
		(at 369.57 182.88 0)
		(effects
			(font
				(size 1.27 1.27)
			)
			(justify left bottom)
		)
	)
	(text "NOTE:\noptional \nexternal divider "
		(exclude_from_sim no)
		(at 142.875 212.725 0)
		(effects
			(font
				(size 1.27 1.27)
			)
			(justify left bottom)
		)
	)
	(text "1	2	3	4"
		(exclude_from_sim no)
		(at 212.725 222.885 0)
		(effects
			(font
				(size 1.27 1.27)
			)
			(justify left bottom)
		)
	)
	(text "MGTAVCC"
		(exclude_from_sim no)
		(at 13.335 226.06 0)
		(effects
			(font
				(size 1.27 1.27)
			)
			(justify left bottom)
		)
	)
	(text "DC-DC AUX, MGT"
		(exclude_from_sim no)
		(at 15.875 147.32 0)
		(effects
			(font
				(size 1.27 1.27)
				(thickness 0.254)
				(bold yes)
			)
			(justify left bottom)
		)
	)
	(text "I2C: 0x61"
		(exclude_from_sim no)
		(at 46.99 139.7 0)
		(effects
			(font
				(size 1.27 1.27)
			)
			(justify left bottom)
		)
	)
	(text "NOTE:\n1. AUTO ON/ PB-Controller\n2. 8s off/ instant off\n3. PWR I2C MUX input select 1\n4. PWR I2C MUX input select 2\n5. PWR I^{2}C SDA disconnect from 3V3 powered IC's\n6. PWR I^{2}C SCL disconnect from 3V3 powered IC's\n7. Connect QDCDC2 I^{2}C\n8. Disable FTDI JTAG"
		(exclude_from_sim no)
		(at 172.72 138.43 0)
		(effects
			(font
				(size 1.27 1.27)
			)
			(justify left bottom)
		)
	)
	(text "Power supply sequencer"
		(exclude_from_sim no)
		(at 339.09 15.875 0)
		(effects
			(font
				(size 1.27 1.27)
				(thickness 0.254)
				(bold yes)
			)
			(justify left bottom)
		)
	)
	(text "Always-ON +3V3 LDO"
		(exclude_from_sim no)
		(at 105.41 16.51 0)
		(effects
			(font
				(size 1.27 1.27)
				(thickness 0.254)
				(bold yes)
			)
			(justify left bottom)
		)
	)
	(text "Power cycle "
		(exclude_from_sim no)
		(at 249.555 15.24 0)
		(effects
			(font
				(size 1.27 1.27)
				(thickness 0.254)
				(bold yes)
			)
			(justify left bottom)
		)
	)
	(text "Config switch"
		(exclude_from_sim no)
		(at 160.02 86.36 0)
		(effects
			(font
				(size 1.27 1.27)
				(thickness 0.4013)
				(bold yes)
			)
			(justify left bottom)
		)
	)
	(text "MGTAVTT Low noise LDO"
		(exclude_from_sim no)
		(at 12.7 239.395 0)
		(effects
			(font
				(size 1.27 1.27)
				(thickness 0.254)
				(bold yes)
			)
			(justify left bottom)
		)
	)
	(text "140ms delay\nfixed"
		(exclude_from_sim no)
		(at 296.545 64.135 0)
		(effects
			(font
				(size 1.27 1.27)
			)
			(justify left bottom)
		)
	)
	(text "+5V"
		(exclude_from_sim no)
		(at 205.105 227.965 0)
		(effects
			(font
				(size 1.27 1.27)
			)
			(justify left bottom)
		)
	)
	(text "I2C: 0x10"
		(exclude_from_sim no)
		(at 353.06 120.015 0)
		(effects
			(font
				(size 1.27 1.27)
			)
			(justify left bottom)
		)
	)
	(text "X"
		(exclude_from_sim no)
		(at 29.845 228.6 0)
		(effects
			(font
				(size 1.27 1.27)
			)
			(justify left bottom)
		)
	)
	(text "NOTE:\noptional \nexternal divider "
		(exclude_from_sim no)
		(at 142.875 184.785 0)
		(effects
			(font
				(size 1.27 1.27)
			)
			(justify left bottom)
		)
	)
	(text "FAN connector"
		(exclude_from_sim no)
		(at 202.565 240.665 0)
		(effects
			(font
				(size 2.0066 2.0066)
				(thickness 0.4013)
				(bold yes)
			)
			(justify left bottom)
		)
	)
	(text "NOTE:\noptional \nexternal divider "
		(exclude_from_sim no)
		(at 173.355 212.725 0)
		(effects
			(font
				(size 1.27 1.27)
			)
			(justify left bottom)
		)
	)
	(text "X"
		(exclude_from_sim no)
		(at 222.25 230.505 0)
		(effects
			(font
				(size 1.27 1.27)
			)
			(justify left bottom)
		)
	)
	(text "ON/OFF Button controller"
		(exclude_from_sim no)
		(at 162.56 16.51 0)
		(effects
			(font
				(size 1.27 1.27)
				(thickness 0.254)
				(bold yes)
			)
			(justify left bottom)
		)
	)
	(text "I2C: 0x69"
		(exclude_from_sim no)
		(at 253.365 215.9 0)
		(effects
			(font
				(size 1.27 1.27)
			)
			(justify left bottom)
		)
	)
	(text "+1V2"
		(exclude_from_sim no)
		(at 203.835 233.045 0)
		(effects
			(font
				(size 1.27 1.27)
			)
			(justify left bottom)
		)
	)
	(text "NOTE:\noptional \nexternal divider "
		(exclude_from_sim no)
		(at 338.455 182.88 0)
		(effects
			(font
				(size 1.27 1.27)
			)
			(justify left bottom)
		)
	)
	(text "PCIe_PWR"
		(exclude_from_sim no)
		(at 16.51 55.88 0)
		(effects
			(font
				(size 1.27 1.27)
			)
			(justify left bottom)
		)
	)
	(text "Set to ~1V7"
		(exclude_from_sim no)
		(at 73.025 219.075 0)
		(effects
			(font
				(size 1.27 1.27)
			)
			(justify left bottom)
		)
	)
	(text "As both MPM54304GMN have same \naddress (from factory), there is \na need to cut SCL signals\nusing dip switch"
		(exclude_from_sim no)
		(at 203.835 205.74 0)
		(effects
			(font
				(size 1.27 1.27)
			)
			(justify left bottom)
		)
	)
	(text "I2C: 0x1F"
		(exclude_from_sim no)
		(at 289.56 119.38 0)
		(effects
			(font
				(size 1.27 1.27)
			)
			(justify left bottom)
		)
	)
	(text "DC_PWR_AUX"
		(exclude_from_sim no)
		(at 16.51 33.02 0)
		(effects
			(font
				(size 1.27 1.27)
			)
			(justify left bottom)
		)
	)
	(text "MGTAVTT"
		(exclude_from_sim no)
		(at 13.335 233.68 0)
		(effects
			(font
				(size 1.27 1.27)
			)
			(justify left bottom)
		)
	)
	(text "Ground probe pads"
		(exclude_from_sim no)
		(at 301.625 240.665 0)
		(effects
			(font
				(size 2.0066 2.0066)
				(thickness 0.4013)
				(bold yes)
			)
			(justify left bottom)
		)
	)
	(text "NOTE:\noptional \nexternal divider "
		(exclude_from_sim no)
		(at 339.09 219.075 0)
		(effects
			(font
				(size 1.27 1.27)
			)
			(justify left bottom)
		)
	)
	(text "Note:\nPlace on the\nbottom side "
		(exclude_from_sim no)
		(at 281.178 280.416 0)
		(effects
			(font
				(size 1.27 1.27)
			)
			(justify left)
		)
	)
	(text "X"
		(exclude_from_sim no)
		(at 227.33 227.965 0)
		(effects
			(font
				(size 1.27 1.27)
			)
			(justify left bottom)
		)
	)
	(text "+1V8"
		(exclude_from_sim no)
		(at 14.605 228.6 0)
		(effects
			(font
				(size 1.27 1.27)
			)
			(justify left bottom)
		)
	)
	(text "X"
		(exclude_from_sim no)
		(at 24.765 226.06 0)
		(effects
			(font
				(size 1.27 1.27)
			)
			(justify left bottom)
		)
	)
	(text "NOTE:\noptional \nexternal divider "
		(exclude_from_sim no)
		(at 172.72 184.785 0)
		(effects
			(font
				(size 1.27 1.27)
			)
			(justify left bottom)
		)
	)
	(text "VREF DAC"
		(exclude_from_sim no)
		(at 106.045 239.395 0)
		(effects
			(font
				(size 1.27 1.27)
				(thickness 0.4013)
				(bold yes)
			)
			(justify left bottom)
		)
	)
	(text "Soft start delay time slot"
		(exclude_from_sim no)
		(at 17.145 220.98 0)
		(effects
			(font
				(size 1.27 1.27)
			)
			(justify left bottom)
		)
	)
	(text "+1V1"
		(exclude_from_sim no)
		(at 203.835 230.505 0)
		(effects
			(font
				(size 1.27 1.27)
			)
			(justify left bottom)
		)
	)
	(text "Power Monitors"
		(exclude_from_sim no)
		(at 270.51 86.36 0)
		(effects
			(font
				(size 1.27 1.27)
				(thickness 0.4013)
				(bold yes)
			)
			(justify left bottom)
		)
	)
	(text "Power good"
		(exclude_from_sim no)
		(at 261.62 240.665 0)
		(effects
			(font
				(size 2.0066 2.0066)
				(thickness 0.4013)
				(bold yes)
			)
			(justify left bottom)
		)
	)
	(text "X"
		(exclude_from_sim no)
		(at 29.845 233.68 0)
		(effects
			(font
				(size 1.27 1.27)
			)
			(justify left bottom)
		)
	)
	(junction
		(at 305.435 212.725)
		(diameter 0)
		(color 0 0 0 0)
	)
	(junction
		(at 388.62 50.165)
		(diameter 0)
		(color 0 0 0 0)
	)
	(junction
		(at 398.78 52.705)
		(diameter 0)
		(color 0 0 0 0)
	)
	(junction
		(at 160.02 204.47)
		(diameter 0)
		(color 0 0 0 0)
	)
	(junction
		(at 366.395 32.385)
		(diameter 0)
		(color 0 0 0 0)
	)
	(junction
		(at 278.765 256.54)
		(diameter 0)
		(color 0 0 0 0)
	)
	(junction
		(at 86.995 197.485)
		(diameter 0)
		(color 0 0 0 0)
	)
	(junction
		(at 92.71 32.385)
		(diameter 0)
		(color 0 0 0 0)
	)
	(junction
		(at 196.215 57.785)
		(diameter 0)
		(color 0 0 0 0)
	)
	(junction
		(at 285.75 197.485)
		(diameter 0)
		(color 0 0 0 0)
	)
	(junction
		(at 131.445 179.705)
		(diameter 0)
		(color 0 0 0 0)
	)
	(junction
		(at 196.215 71.12)
		(diameter 0)
		(color 0 0 0 0)
	)
	(junction
		(at 66.675 22.225)
		(diameter 0)
		(color 0 0 0 0)
	)
	(junction
		(at 93.345 247.015)
		(diameter 0)
		(color 0 0 0 0)
	)
	(junction
		(at 285.75 216.535)
		(diameter 0)
		(color 0 0 0 0)
	)
	(junction
		(at 146.685 51.435)
		(diameter 0)
		(color 0 0 0 0)
	)
	(junction
		(at 364.49 123.825)
		(diameter 0)
		(color 0 0 0 0)
	)
	(junction
		(at 364.49 118.745)
		(diameter 0)
		(color 0 0 0 0)
	)
	(junction
		(at 163.195 255.27)
		(diameter 0)
		(color 0 0 0 0)
	)
	(junction
		(at 22.86 260.35)
		(diameter 0)
		(color 0 0 0 0)
	)
	(junction
		(at 189.865 176.53)
		(diameter 0)
		(color 0 0 0 0)
	)
	(junction
		(at 86.995 207.645)
		(diameter 0)
		(color 0 0 0 0)
	)
	(junction
		(at 118.745 197.485)
		(diameter 0)
		(color 0 0 0 0)
	)
	(junction
		(at 313.055 158.115)
		(diameter 0)
		(color 0 0 0 0)
	)
	(junction
		(at 226.06 157.48)
		(diameter 0)
		(color 0 0 0 0)
	)
	(junction
		(at 285.75 189.865)
		(diameter 0)
		(color 0 0 0 0)
	)
	(junction
		(at 285.75 207.645)
		(diameter 0)
		(color 0 0 0 0)
	)
	(junction
		(at 98.425 116.84)
		(diameter 0)
		(color 0 0 0 0)
	)
	(junction
		(at 276.86 179.705)
		(diameter 0)
		(color 0 0 0 0)
	)
	(junction
		(at 17.145 95.25)
		(diameter 0)
		(color 0 0 0 0)
	)
	(junction
		(at 358.14 98.425)
		(diameter 0)
		(color 0 0 0 0)
	)
	(junction
		(at 220.345 118.11)
		(diameter 0)
		(color 0 0 0 0)
	)
	(junction
		(at 351.155 32.385)
		(diameter 0)
		(color 0 0 0 0)
	)
	(junction
		(at 379.095 32.385)
		(diameter 0)
		(color 0 0 0 0)
	)
	(junction
		(at 17.145 105.41)
		(diameter 0)
		(color 0 0 0 0)
	)
	(junction
		(at 33.655 22.225)
		(diameter 0)
		(color 0 0 0 0)
	)
	(junction
		(at 66.675 42.545)
		(diameter 0)
		(color 0 0 0 0)
	)
	(junction
		(at 278.765 259.08)
		(diameter 0)
		(color 0 0 0 0)
	)
	(junction
		(at 356.87 210.82)
		(diameter 0)
		(color 0 0 0 0)
	)
	(junction
		(at 76.835 106.68)
		(diameter 0)
		(color 0 0 0 0)
	)
	(junction
		(at 123.825 216.535)
		(diameter 0)
		(color 0 0 0 0)
	)
	(junction
		(at 355.6 174.625)
		(diameter 0)
		(color 0 0 0 0)
	)
	(junction
		(at 304.8 197.485)
		(diameter 0)
		(color 0 0 0 0)
	)
	(junction
		(at 29.21 105.41)
		(diameter 0)
		(color 0 0 0 0)
	)
	(junction
		(at 66.675 65.405)
		(diameter 0)
		(color 0 0 0 0)
	)
	(junction
		(at 326.39 179.705)
		(diameter 0)
		(color 0 0 0 0)
	)
	(junction
		(at 95.885 55.245)
		(diameter 0)
		(color 0 0 0 0)
	)
	(junction
		(at 138.43 106.68)
		(diameter 0)
		(color 0 0 0 0)
	)
	(junction
		(at 364.49 116.205)
		(diameter 0)
		(color 0 0 0 0)
	)
	(junction
		(at 110.49 158.115)
		(diameter 0)
		(color 0 0 0 0)
	)
	(junction
		(at 316.865 197.485)
		(diameter 0)
		(color 0 0 0 0)
	)
	(junction
		(at 109.22 249.555)
		(diameter 0)
		(color 0 0 0 0)
	)
	(junction
		(at 207.01 113.03)
		(diameter 0)
		(color 0 0 0 0)
	)
	(junction
		(at 30.48 27.305)
		(diameter 0)
		(color 0 0 0 0)
	)
	(junction
		(at 298.45 98.425)
		(diameter 0)
		(color 0 0 0 0)
	)
	(junction
		(at 110.49 197.485)
		(diameter 0)
		(color 0 0 0 0)
	)
	(junction
		(at 86.995 216.535)
		(diameter 0)
		(color 0 0 0 0)
	)
	(junction
		(at 276.86 168.275)
		(diameter 0)
		(color 0 0 0 0)
	)
	(junction
		(at 66.675 37.465)
		(diameter 0)
		(color 0 0 0 0)
	)
	(junction
		(at 66.675 55.245)
		(diameter 0)
		(color 0 0 0 0)
	)
	(junction
		(at 66.675 32.385)
		(diameter 0)
		(color 0 0 0 0)
	)
	(junction
		(at 313.055 179.705)
		(diameter 0)
		(color 0 0 0 0)
	)
	(junction
		(at 29.21 95.25)
		(diameter 0)
		(color 0 0 0 0)
	)
	(junction
		(at 316.865 158.115)
		(diameter 0)
		(color 0 0 0 0)
	)
	(junction
		(at 209.55 48.26)
		(diameter 0)
		(color 0 0 0 0)
	)
	(junction
		(at 78.105 168.275)
		(diameter 0)
		(color 0 0 0 0)
	)
	(junction
		(at 236.22 125.73)
		(diameter 0)
		(color 0 0 0 0)
	)
	(junction
		(at 215.9 157.48)
		(diameter 0)
		(color 0 0 0 0)
	)
	(junction
		(at 160.02 176.53)
		(diameter 0)
		(color 0 0 0 0)
	)
	(junction
		(at 40.64 247.015)
		(diameter 0)
		(color 0 0 0 0)
	)
	(junction
		(at 304.8 116.205)
		(diameter 0)
		(color 0 0 0 0)
	)
	(junction
		(at 64.135 135.89)
		(diameter 0)
		(color 0 0 0 0)
	)
	(junction
		(at 118.745 179.705)
		(diameter 0)
		(color 0 0 0 0)
	)
	(junction
		(at 180.34 245.745)
		(diameter 0)
		(color 0 0 0 0)
	)
	(junction
		(at 276.86 158.115)
		(diameter 0)
		(color 0 0 0 0)
	)
	(junction
		(at 86.995 179.705)
		(diameter 0)
		(color 0 0 0 0)
	)
	(junction
		(at 304.8 179.705)
		(diameter 0)
		(color 0 0 0 0)
	)
	(junction
		(at 155.575 260.35)
		(diameter 0)
		(color 0 0 0 0)
	)
	(junction
		(at 248.285 260.985)
		(diameter 0)
		(color 0 0 0 0)
	)
	(junction
		(at 41.91 95.25)
		(diameter 0)
		(color 0 0 0 0)
	)
	(junction
		(at 313.055 197.485)
		(diameter 0)
		(color 0 0 0 0)
	)
	(junction
		(at 190.5 204.47)
		(diameter 0)
		(color 0 0 0 0)
	)
	(junction
		(at 386.715 174.625)
		(diameter 0)
		(color 0 0 0 0)
	)
	(junction
		(at 379.095 47.625)
		(diameter 0)
		(color 0 0 0 0)
	)
	(junction
		(at 118.745 216.535)
		(diameter 0)
		(color 0 0 0 0)
	)
	(junction
		(at 98.425 106.68)
		(diameter 0)
		(color 0 0 0 0)
	)
	(junction
		(at 123.825 158.115)
		(diameter 0)
		(color 0 0 0 0)
	)
	(junction
		(at 118.745 158.115)
		(diameter 0)
		(color 0 0 0 0)
	)
	(junction
		(at 113.03 39.37)
		(diameter 0)
		(color 0 0 0 0)
	)
	(junction
		(at 27.305 157.48)
		(diameter 0)
		(color 0 0 0 0)
	)
	(junction
		(at 114.935 116.84)
		(diameter 0)
		(color 0 0 0 0)
	)
	(junction
		(at 316.865 179.705)
		(diameter 0)
		(color 0 0 0 0)
	)
	(junction
		(at 123.825 179.705)
		(diameter 0)
		(color 0 0 0 0)
	)
	(junction
		(at 30.48 32.385)
		(diameter 0)
		(color 0 0 0 0)
	)
	(junction
		(at 139.065 39.37)
		(diameter 0)
		(color 0 0 0 0)
	)
	(junction
		(at 110.49 179.705)
		(diameter 0)
		(color 0 0 0 0)
	)
	(junction
		(at 236.22 123.19)
		(diameter 0)
		(color 0 0 0 0)
	)
	(junction
		(at 346.71 50.165)
		(diameter 0)
		(color 0 0 0 0)
	)
	(junction
		(at 123.825 127)
		(diameter 0)
		(color 0 0 0 0)
	)
	(junction
		(at 144.145 106.68)
		(diameter 0)
		(color 0 0 0 0)
	)
	(junction
		(at 285.75 168.275)
		(diameter 0)
		(color 0 0 0 0)
	)
	(junction
		(at 132.715 106.68)
		(diameter 0)
		(color 0 0 0 0)
	)
	(junction
		(at 50.165 95.25)
		(diameter 0)
		(color 0 0 0 0)
	)
	(junction
		(at 256.54 53.34)
		(diameter 0)
		(color 0 0 0 0)
	)
	(junction
		(at 123.825 106.68)
		(diameter 0)
		(color 0 0 0 0)
	)
	(junction
		(at 388.62 32.385)
		(diameter 0)
		(color 0 0 0 0)
	)
	(junction
		(at 236.22 113.03)
		(diameter 0)
		(color 0 0 0 0)
	)
	(junction
		(at 30.48 34.925)
		(diameter 0)
		(color 0 0 0 0)
	)
	(junction
		(at 57.785 247.015)
		(diameter 0)
		(color 0 0 0 0)
	)
	(junction
		(at 22.86 247.015)
		(diameter 0)
		(color 0 0 0 0)
	)
	(junction
		(at 86.995 168.275)
		(diameter 0)
		(color 0 0 0 0)
	)
	(junction
		(at 78.105 158.115)
		(diameter 0)
		(color 0 0 0 0)
	)
	(junction
		(at 110.49 216.535)
		(diameter 0)
		(color 0 0 0 0)
	)
	(junction
		(at 317.5 212.725)
		(diameter 0)
		(color 0 0 0 0)
	)
	(junction
		(at 85.725 247.015)
		(diameter 0)
		(color 0 0 0 0)
	)
	(junction
		(at 278.765 261.62)
		(diameter 0)
		(color 0 0 0 0)
	)
	(junction
		(at 86.995 158.115)
		(diameter 0)
		(color 0 0 0 0)
	)
	(junction
		(at 130.81 158.115)
		(diameter 0)
		(color 0 0 0 0)
	)
	(junction
		(at 85.09 158.115)
		(diameter 0)
		(color 0 0 0 0)
	)
	(junction
		(at 89.535 106.68)
		(diameter 0)
		(color 0 0 0 0)
	)
	(junction
		(at 61.595 247.015)
		(diameter 0)
		(color 0 0 0 0)
	)
	(junction
		(at 215.9 166.37)
		(diameter 0)
		(color 0 0 0 0)
	)
	(junction
		(at 171.45 64.135)
		(diameter 0)
		(color 0 0 0 0)
	)
	(junction
		(at 95.885 22.225)
		(diameter 0)
		(color 0 0 0 0)
	)
	(junction
		(at 106.045 106.68)
		(diameter 0)
		(color 0 0 0 0)
	)
	(junction
		(at 212.725 26.035)
		(diameter 0)
		(color 0 0 0 0)
	)
	(junction
		(at 17.145 157.48)
		(diameter 0)
		(color 0 0 0 0)
	)
	(junction
		(at 313.69 212.725)
		(diameter 0)
		(color 0 0 0 0)
	)
	(junction
		(at 204.47 110.49)
		(diameter 0)
		(color 0 0 0 0)
	)
	(junction
		(at 34.29 55.245)
		(diameter 0)
		(color 0 0 0 0)
	)
	(junction
		(at 58.42 65.405)
		(diameter 0)
		(color 0 0 0 0)
	)
	(junction
		(at 114.935 249.555)
		(diameter 0)
		(color 0 0 0 0)
	)
	(junction
		(at 66.675 75.565)
		(diameter 0)
		(color 0 0 0 0)
	)
	(junction
		(at 325.755 158.115)
		(diameter 0)
		(color 0 0 0 0)
	)
	(junction
		(at 123.825 115.57)
		(diameter 0)
		(color 0 0 0 0)
	)
	(junction
		(at 58.42 32.385)
		(diameter 0)
		(color 0 0 0 0)
	)
	(junction
		(at 304.8 123.825)
		(diameter 0)
		(color 0 0 0 0)
	)
	(junction
		(at 238.76 243.205)
		(diameter 0)
		(color 0 0 0 0)
	)
	(junction
		(at 325.755 212.725)
		(diameter 0)
		(color 0 0 0 0)
	)
	(junction
		(at 286.893 32.385)
		(diameter 0)
		(color 0 0 0 0)
	)
	(junction
		(at 285.75 158.115)
		(diameter 0)
		(color 0 0 0 0)
	)
	(junction
		(at 304.8 158.115)
		(diameter 0)
		(color 0 0 0 0)
	)
	(junction
		(at 106.045 116.84)
		(diameter 0)
		(color 0 0 0 0)
	)
	(junction
		(at 95.885 32.385)
		(diameter 0)
		(color 0 0 0 0)
	)
	(junction
		(at 114.935 106.68)
		(diameter 0)
		(color 0 0 0 0)
	)
	(junction
		(at 325.755 197.485)
		(diameter 0)
		(color 0 0 0 0)
	)
	(junction
		(at 61.595 257.175)
		(diameter 0)
		(color 0 0 0 0)
	)
	(junction
		(at 17.145 166.37)
		(diameter 0)
		(color 0 0 0 0)
	)
	(junction
		(at 285.75 179.705)
		(diameter 0)
		(color 0 0 0 0)
	)
	(junction
		(at 111.125 39.37)
		(diameter 0)
		(color 0 0 0 0)
	)
	(junction
		(at 86.995 189.865)
		(diameter 0)
		(color 0 0 0 0)
	)
	(junction
		(at 269.24 42.545)
		(diameter 0)
		(color 0 0 0 0)
	)
	(junction
		(at 78.105 179.705)
		(diameter 0)
		(color 0 0 0 0)
	)
	(junction
		(at 284.48 158.115)
		(diameter 0)
		(color 0 0 0 0)
	)
	(junction
		(at 50.165 22.225)
		(diameter 0)
		(color 0 0 0 0)
	)
	(junction
		(at 146.685 39.37)
		(diameter 0)
		(color 0 0 0 0)
	)
	(junction
		(at 66.675 70.485)
		(diameter 0)
		(color 0 0 0 0)
	)
	(junction
		(at 386.715 210.82)
		(diameter 0)
		(color 0 0 0 0)
	)
	(junction
		(at 227.965 248.285)
		(diameter 0)
		(color 0 0 0 0)
	)
	(junction
		(at 95.885 65.405)
		(diameter 0)
		(color 0 0 0 0)
	)
	(no_connect
		(at 66.675 189.865)
	)
	(no_connect
		(at 249.555 255.905)
	)
	(no_connect
		(at 265.43 177.165)
	)
	(no_connect
		(at 265.43 189.865)
	)
	(no_connect
		(at 85.725 70.485)
	)
	(no_connect
		(at 85.725 37.465)
	)
	(no_connect
		(at 66.675 177.165)
	)
	(bus_entry
		(at 178.435 115.57)
		(size -2.54 -2.54)
		(stroke
			(width 0)
			(type default)
		)
	)
	(bus_entry
		(at 178.435 118.11)
		(size -2.54 -2.54)
		(stroke
			(width 0)
			(type default)
		)
	)
	(wire
		(pts
			(xy 355.6 172.085) (xy 355.6 174.625)
		)
		(stroke
			(width 0)
			(type default)
		)
	)
	(polyline
		(pts
			(xy 203.835 217.805) (xy 203.835 227.965)
		)
		(stroke
			(width 0)
			(type default)
		)
	)
	(wire
		(pts
			(xy 285.75 158.115) (xy 304.8 158.115)
		)
		(stroke
			(width 0)
			(type default)
		)
	)
	(wire
		(pts
			(xy 226.06 166.37) (xy 215.9 166.37)
		)
		(stroke
			(width 0)
			(type default)
		)
	)
	(polyline
		(pts
			(xy 230.505 233.68) (xy 230.505 227.965)
		)
		(stroke
			(width 0)
			(type default)
		)
	)
	(wire
		(pts
			(xy 35.56 124.46) (xy 53.975 124.46)
		)
		(stroke
			(width 0)
			(type default)
		)
	)
	(wire
		(pts
			(xy 288.29 261.62) (xy 294.64 261.62)
		)
		(stroke
			(width 0)
			(type default)
		)
	)
	(wire
		(pts
			(xy 29.21 95.25) (xy 29.21 97.79)
		)
		(stroke
			(width 0)
			(type default)
		)
	)
	(wire
		(pts
			(xy 386.715 172.085) (xy 386.715 174.625)
		)
		(stroke
			(width 0)
			(type default)
		)
	)
	(wire
		(pts
			(xy 131.445 179.705) (xy 132.715 179.705)
		)
		(stroke
			(width 0)
			(type default)
		)
	)
	(wire
		(pts
			(xy 285.75 207.645) (xy 285.75 208.915)
		)
		(stroke
			(width 0)
			(type default)
		)
	)
	(bus
		(pts
			(xy 173.355 111.125) (xy 175.26 111.125)
		)
		(stroke
			(width 0)
			(type default)
		)
	)
	(wire
		(pts
			(xy 118.745 197.485) (xy 130.81 197.485)
		)
		(stroke
			(width 0)
			(type default)
		)
	)
	(wire
		(pts
			(xy 154.94 276.86) (xy 154.94 278.13)
		)
		(stroke
			(width 0)
			(type default)
		)
	)
	(polyline
		(pts
			(xy 13.335 218.44) (xy 13.335 228.6)
		)
		(stroke
			(width 0)
			(type default)
		)
	)
	(wire
		(pts
			(xy 22.86 254.635) (xy 22.86 260.35)
		)
		(stroke
			(width 0)
			(type default)
		)
	)
	(wire
		(pts
			(xy 30.48 27.305) (xy 29.21 27.305)
		)
		(stroke
			(width 0)
			(type default)
		)
	)
	(wire
		(pts
			(xy 351.155 40.005) (xy 351.155 41.91)
		)
		(stroke
			(width 0)
			(type default)
		)
	)
	(wire
		(pts
			(xy 30.48 32.385) (xy 33.655 32.385)
		)
		(stroke
			(width 0)
			(type default)
		)
	)
	(wire
		(pts
			(xy 278.765 250.19) (xy 278.765 248.92)
		)
		(stroke
			(width 0)
			(type default)
		)
	)
	(wire
		(pts
			(xy 67.945 158.115) (xy 67.945 174.625)
		)
		(stroke
			(width 0)
			(type default)
		)
	)
	(wire
		(pts
			(xy 66.675 37.465) (xy 66.675 42.545)
		)
		(stroke
			(width 0)
			(type default)
		)
	)
	(wire
		(pts
			(xy 326.39 179.705) (xy 327.66 179.705)
		)
		(stroke
			(width 0)
			(type default)
		)
	)
	(wire
		(pts
			(xy 196.215 57.785) (xy 196.215 59.69)
		)
		(stroke
			(width 0)
			(type default)
		)
	)
	(wire
		(pts
			(xy 144.145 106.68) (xy 145.415 106.68)
		)
		(stroke
			(width 0)
			(type default)
		)
	)
	(wire
		(pts
			(xy 313.055 184.785) (xy 323.215 184.785)
		)
		(stroke
			(width 0)
			(type default)
		)
	)
	(polyline
		(pts
			(xy 367.03 220.345) (xy 338.455 220.345)
		)
		(stroke
			(width 0)
			(type default)
		)
	)
	(wire
		(pts
			(xy 331.47 100.965) (xy 347.345 100.965)
		)
		(stroke
			(width 0)
			(type default)
		)
	)
	(wire
		(pts
			(xy 85.725 34.925) (xy 88.265 34.925)
		)
		(stroke
			(width 0)
			(type default)
		)
	)
	(wire
		(pts
			(xy 57.785 257.175) (xy 61.595 257.175)
		)
		(stroke
			(width 0)
			(type default)
		)
	)
	(wire
		(pts
			(xy 142.24 276.86) (xy 142.24 278.13)
		)
		(stroke
			(width 0)
			(type default)
		)
	)
	(wire
		(pts
			(xy 364.49 118.745) (xy 364.49 123.825)
		)
		(stroke
			(width 0)
			(type default)
		)
	)
	(wire
		(pts
			(xy 118.745 179.705) (xy 123.825 179.705)
		)
		(stroke
			(width 0)
			(type default)
		)
	)
	(polyline
		(pts
			(xy 230.505 217.805) (xy 203.835 217.805)
		)
		(stroke
			(width 0)
			(type default)
		)
	)
	(wire
		(pts
			(xy 178.435 115.57) (xy 222.25 115.57)
		)
		(stroke
			(width 0)
			(type default)
		)
	)
	(wire
		(pts
			(xy 89.535 114.3) (xy 89.535 116.84)
		)
		(stroke
			(width 0)
			(type default)
		)
	)
	(wire
		(pts
			(xy 313.69 217.17) (xy 313.69 217.805)
		)
		(stroke
			(width 0)
			(type default)
		)
	)
	(wire
		(pts
			(xy 304.8 158.115) (xy 306.07 158.115)
		)
		(stroke
			(width 0)
			(type default)
		)
	)
	(wire
		(pts
			(xy 313.055 198.12) (xy 313.055 197.485)
		)
		(stroke
			(width 0)
			(type default)
		)
	)
	(wire
		(pts
			(xy 246.38 243.205) (xy 246.38 253.365)
		)
		(stroke
			(width 0)
			(type default)
		)
	)
	(wire
		(pts
			(xy 311.15 179.705) (xy 313.055 179.705)
		)
		(stroke
			(width 0)
			(type default)
		)
	)
	(wire
		(pts
			(xy 325.755 197.485) (xy 327.025 197.485)
		)
		(stroke
			(width 0)
			(type default)
		)
	)
	(wire
		(pts
			(xy 231.14 45.72) (xy 232.41 45.72)
		)
		(stroke
			(width 0)
			(type default)
		)
	)
	(polyline
		(pts
			(xy 248.92 26.67) (xy 248.92 82.55)
		)
		(stroke
			(width 0)
			(type default)
		)
	)
	(wire
		(pts
			(xy 285.75 216.535) (xy 290.195 216.535)
		)
		(stroke
			(width 0)
			(type default)
		)
	)
	(wire
		(pts
			(xy 207.01 97.79) (xy 207.01 96.52)
		)
		(stroke
			(width 0)
			(type default)
		)
	)
	(wire
		(pts
			(xy 386.715 200.66) (xy 386.715 203.2)
		)
		(stroke
			(width 0)
			(type default)
		)
	)
	(wire
		(pts
			(xy 118.745 162.56) (xy 118.745 163.195)
		)
		(stroke
			(width 0)
			(type default)
		)
	)
	(wire
		(pts
			(xy 111.125 36.195) (xy 111.125 39.37)
		)
		(stroke
			(width 0)
			(type default)
		)
	)
	(wire
		(pts
			(xy 386.715 210.82) (xy 386.715 213.36)
		)
		(stroke
			(width 0)
			(type default)
		)
	)
	(wire
		(pts
			(xy 273.05 187.325) (xy 273.05 179.705)
		)
		(stroke
			(width 0)
			(type default)
		)
	)
	(wire
		(pts
			(xy 388.62 43.815) (xy 388.62 50.165)
		)
		(stroke
			(width 0)
			(type default)
		)
	)
	(wire
		(pts
			(xy 41.275 249.555) (xy 40.64 249.555)
		)
		(stroke
			(width 0)
			(type default)
		)
	)
	(wire
		(pts
			(xy 391.795 98.425) (xy 405.13 98.425)
		)
		(stroke
			(width 0)
			(type default)
		)
	)
	(wire
		(pts
			(xy 243.84 45.72) (xy 243.84 48.26)
		)
		(stroke
			(width 0)
			(type default)
		)
	)
	(wire
		(pts
			(xy 269.24 42.545) (xy 269.24 44.45)
		)
		(stroke
			(width 0)
			(type default)
		)
	)
	(polyline
		(pts
			(xy 368.935 175.895) (xy 396.24 175.895)
		)
		(stroke
			(width 0)
			(type default)
		)
	)
	(wire
		(pts
			(xy 29.21 105.41) (xy 41.91 105.41)
		)
		(stroke
			(width 0)
			(type default)
		)
	)
	(wire
		(pts
			(xy 313.69 217.805) (xy 325.12 217.805)
		)
		(stroke
			(width 0)
			(type default)
		)
	)
	(wire
		(pts
			(xy 185.42 278.13) (xy 185.42 279.4)
		)
		(stroke
			(width 0)
			(type default)
		)
	)
	(wire
		(pts
			(xy 116.84 179.705) (xy 118.745 179.705)
		)
		(stroke
			(width 0)
			(type default)
		)
	)
	(wire
		(pts
			(xy 92.075 22.225) (xy 95.885 22.225)
		)
		(stroke
			(width 0)
			(type default)
		)
	)
	(wire
		(pts
			(xy 57.785 249.555) (xy 57.785 247.015)
		)
		(stroke
			(width 0)
			(type default)
		)
	)
	(wire
		(pts
			(xy 285.75 179.705) (xy 304.8 179.705)
		)
		(stroke
			(width 0)
			(type default)
		)
	)
	(wire
		(pts
			(xy 391.795 100.965) (xy 405.13 100.965)
		)
		(stroke
			(width 0)
			(type default)
		)
	)
	(wire
		(pts
			(xy 17.145 157.48) (xy 17.145 159.385)
		)
		(stroke
			(width 0)
			(type default)
		)
	)
	(wire
		(pts
			(xy 93.345 247.015) (xy 95.25 247.015)
		)
		(stroke
			(width 0)
			(type default)
		)
	)
	(wire
		(pts
			(xy 207.01 113.03) (xy 222.25 113.03)
		)
		(stroke
			(width 0)
			(type default)
		)
	)
	(wire
		(pts
			(xy 29.21 95.25) (xy 41.91 95.25)
		)
		(stroke
			(width 0)
			(type default)
		)
	)
	(wire
		(pts
			(xy 285.75 128.27) (xy 285.75 128.905)
		)
		(stroke
			(width 0)
			(type default)
		)
	)
	(wire
		(pts
			(xy 160.02 165.735) (xy 160.02 168.91)
		)
		(stroke
			(width 0)
			(type default)
		)
	)
	(wire
		(pts
			(xy 17.145 114.3) (xy 17.145 116.84)
		)
		(stroke
			(width 0)
			(type default)
		)
	)
	(wire
		(pts
			(xy 190.5 204.47) (xy 190.5 207.01)
		)
		(stroke
			(width 0)
			(type default)
		)
	)
	(wire
		(pts
			(xy 316.865 179.705) (xy 326.39 179.705)
		)
		(stroke
			(width 0)
			(type default)
		)
	)
	(wire
		(pts
			(xy 86.995 216.535) (xy 110.49 216.535)
		)
		(stroke
			(width 0)
			(type default)
		)
	)
	(wire
		(pts
			(xy 313.055 158.115) (xy 316.865 158.115)
		)
		(stroke
			(width 0)
			(type default)
		)
	)
	(wire
		(pts
			(xy 316.865 179.07) (xy 316.865 179.705)
		)
		(stroke
			(width 0)
			(type default)
		)
	)
	(wire
		(pts
			(xy 66.675 210.185) (xy 70.485 210.185)
		)
		(stroke
			(width 0)
			(type default)
		)
	)
	(wire
		(pts
			(xy 375.285 243.205) (xy 374.015 243.205)
		)
		(stroke
			(width 0)
			(type default)
		)
	)
	(wire
		(pts
			(xy 276.86 179.705) (xy 285.75 179.705)
		)
		(stroke
			(width 0)
			(type default)
		)
	)
	(wire
		(pts
			(xy 78.105 158.115) (xy 85.09 158.115)
		)
		(stroke
			(width 0)
			(type default)
		)
	)
	(wire
		(pts
			(xy 215.9 177.165) (xy 237.49 177.165)
		)
		(stroke
			(width 0)
			(type default)
		)
	)
	(wire
		(pts
			(xy 306.07 123.825) (xy 304.8 123.825)
		)
		(stroke
			(width 0)
			(type default)
		)
	)
	(wire
		(pts
			(xy 30.48 32.385) (xy 30.48 34.925)
		)
		(stroke
			(width 0)
			(type default)
		)
	)
	(wire
		(pts
			(xy 198.755 113.03) (xy 207.01 113.03)
		)
		(stroke
			(width 0)
			(type default)
		)
	)
	(wire
		(pts
			(xy 73.025 92.71) (xy 76.835 92.71)
		)
		(stroke
			(width 0)
			(type default)
		)
	)
	(wire
		(pts
			(xy 17.145 94.615) (xy 17.145 95.25)
		)
		(stroke
			(width 0)
			(type default)
		)
	)
	(wire
		(pts
			(xy 215.9 157.48) (xy 215.9 159.385)
		)
		(stroke
			(width 0)
			(type default)
		)
	)
	(wire
		(pts
			(xy 66.675 187.325) (xy 75.565 187.325)
		)
		(stroke
			(width 0)
			(type default)
		)
	)
	(polyline
		(pts
			(xy 42.545 218.44) (xy 13.335 218.44)
		)
		(stroke
			(width 0)
			(type default)
		)
	)
	(polyline
		(pts
			(xy 170.18 177.8) (xy 170.18 186.055)
		)
		(stroke
			(width 0)
			(type default)
		)
	)
	(wire
		(pts
			(xy 189.865 176.53) (xy 189.865 179.07)
		)
		(stroke
			(width 0)
			(type default)
		)
	)
	(wire
		(pts
			(xy 123.825 179.705) (xy 131.445 179.705)
		)
		(stroke
			(width 0)
			(type default)
		)
	)
	(wire
		(pts
			(xy 355.6 182.245) (xy 355.6 186.055)
		)
		(stroke
			(width 0)
			(type default)
		)
	)
	(polyline
		(pts
			(xy 13.335 226.06) (xy 42.545 226.06)
		)
		(stroke
			(width 0)
			(type default)
		)
	)
	(wire
		(pts
			(xy 215.9 177.165) (xy 215.9 179.705)
		)
		(stroke
			(width 0)
			(type default)
		)
	)
	(wire
		(pts
			(xy 150.495 194.31) (xy 160.02 194.31)
		)
		(stroke
			(width 0)
			(type default)
		)
	)
	(wire
		(pts
			(xy 171.45 62.23) (xy 171.45 64.135)
		)
		(stroke
			(width 0)
			(type default)
		)
	)
	(wire
		(pts
			(xy 266.7 158.115) (xy 266.7 174.625)
		)
		(stroke
			(width 0)
			(type default)
		)
	)
	(wire
		(pts
			(xy 86.995 168.275) (xy 86.995 169.545)
		)
		(stroke
			(width 0)
			(type default)
		)
	)
	(wire
		(pts
			(xy 110.49 163.195) (xy 94.615 163.195)
		)
		(stroke
			(width 0)
			(type default)
		)
	)
	(polyline
		(pts
			(xy 172.085 177.8) (xy 200.025 177.8)
		)
		(stroke
			(width 0)
			(type default)
		)
	)
	(wire
		(pts
			(xy 146.685 52.705) (xy 146.685 51.435)
		)
		(stroke
			(width 0)
			(type default)
		)
	)
	(wire
		(pts
			(xy 189.865 184.15) (xy 189.865 186.69)
		)
		(stroke
			(width 0)
			(type default)
		)
	)
	(wire
		(pts
			(xy 234.95 123.19) (xy 236.22 123.19)
		)
		(stroke
			(width 0)
			(type default)
		)
	)
	(wire
		(pts
			(xy 364.49 113.665) (xy 364.49 116.205)
		)
		(stroke
			(width 0)
			(type default)
		)
	)
	(wire
		(pts
			(xy 304.8 100.965) (xy 306.07 100.965)
		)
		(stroke
			(width 0)
			(type default)
		)
	)
	(wire
		(pts
			(xy 346.71 57.15) (xy 346.71 58.42)
		)
		(stroke
			(width 0)
			(type default)
		)
	)
	(wire
		(pts
			(xy 236.22 210.185) (xy 236.22 211.455)
		)
		(stroke
			(width 0)
			(type default)
		)
	)
	(wire
		(pts
			(xy 163.195 255.27) (xy 170.815 255.27)
		)
		(stroke
			(width 0)
			(type default)
		)
	)
	(wire
		(pts
			(xy 78.105 179.705) (xy 78.105 182.245)
		)
		(stroke
			(width 0)
			(type default)
		)
	)
	(polyline
		(pts
			(xy 220.345 220.345) (xy 220.345 233.68)
		)
		(stroke
			(width 0)
			(type default)
		)
	)
	(polyline
		(pts
			(xy 13.335 233.68) (xy 42.545 233.68)
		)
		(stroke
			(width 0)
			(type default)
		)
	)
	(wire
		(pts
			(xy 95.885 73.025) (xy 95.885 76.835)
		)
		(stroke
			(width 0)
			(type default)
		)
	)
	(wire
		(pts
			(xy 350.52 174.625) (xy 355.6 174.625)
		)
		(stroke
			(width 0)
			(type default)
		)
	)
	(wire
		(pts
			(xy 240.03 278.13) (xy 248.92 278.13)
		)
		(stroke
			(width 0)
			(type default)
		)
	)
	(wire
		(pts
			(xy 226.06 164.465) (xy 226.06 166.37)
		)
		(stroke
			(width 0)
			(type default)
		)
	)
	(wire
		(pts
			(xy 304.8 198.12) (xy 304.8 197.485)
		)
		(stroke
			(width 0)
			(type default)
		)
	)
	(polyline
		(pts
			(xy 170.18 186.055) (xy 142.24 186.055)
		)
		(stroke
			(width 0)
			(type default)
		)
	)
	(wire
		(pts
			(xy 139.065 39.37) (xy 146.685 39.37)
		)
		(stroke
			(width 0)
			(type default)
		)
	)
	(polyline
		(pts
			(xy 142.24 177.8) (xy 142.24 186.055)
		)
		(stroke
			(width 0)
			(type default)
		)
	)
	(wire
		(pts
			(xy 78.105 179.705) (xy 86.995 179.705)
		)
		(stroke
			(width 0)
			(type default)
		)
	)
	(wire
		(pts
			(xy 66.675 22.225) (xy 79.375 22.225)
		)
		(stroke
			(width 0)
			(type default)
		)
	)
	(polyline
		(pts
			(xy 203.835 231.14) (xy 230.505 231.14)
		)
		(stroke
			(width 0)
			(type default)
		)
	)
	(wire
		(pts
			(xy 85.725 106.68) (xy 89.535 106.68)
		)
		(stroke
			(width 0)
			(type default)
		)
	)
	(wire
		(pts
			(xy 304.8 113.665) (xy 304.8 116.205)
		)
		(stroke
			(width 0)
			(type default)
		)
	)
	(wire
		(pts
			(xy 21.59 184.15) (xy 21.59 186.055)
		)
		(stroke
			(width 0)
			(type default)
		)
	)
	(wire
		(pts
			(xy 346.075 121.285) (xy 331.47 121.285)
		)
		(stroke
			(width 0)
			(type default)
		)
	)
	(wire
		(pts
			(xy 345.44 200.66) (xy 356.87 200.66)
		)
		(stroke
			(width 0)
			(type default)
		)
	)
	(wire
		(pts
			(xy 391.795 113.665) (xy 405.13 113.665)
		)
		(stroke
			(width 0)
			(type default)
		)
	)
	(wire
		(pts
			(xy 58.42 73.025) (xy 58.42 75.565)
		)
		(stroke
			(width 0)
			(type default)
		)
	)
	(wire
		(pts
			(xy 89.535 116.84) (xy 98.425 116.84)
		)
		(stroke
			(width 0)
			(type default)
		)
	)
	(wire
		(pts
			(xy 259.08 278.13) (xy 267.97 278.13)
		)
		(stroke
			(width 0)
			(type default)
		)
	)
	(wire
		(pts
			(xy 351.155 32.385) (xy 351.155 34.925)
		)
		(stroke
			(width 0)
			(type default)
		)
	)
	(wire
		(pts
			(xy 220.98 123.19) (xy 222.25 123.19)
		)
		(stroke
			(width 0)
			(type default)
		)
	)
	(wire
		(pts
			(xy 114.935 106.68) (xy 123.825 106.68)
		)
		(stroke
			(width 0)
			(type default)
		)
	)
	(polyline
		(pts
			(xy 200.025 186.055) (xy 172.085 186.055)
		)
		(stroke
			(width 0)
			(type default)
		)
	)
	(wire
		(pts
			(xy 111.125 50.165) (xy 111.125 52.705)
		)
		(stroke
			(width 0)
			(type default)
		)
	)
	(wire
		(pts
			(xy 95.885 32.385) (xy 95.885 55.245)
		)
		(stroke
			(width 0)
			(type default)
		)
	)
	(wire
		(pts
			(xy 285.75 216.535) (xy 285.75 220.98)
		)
		(stroke
			(width 0)
			(type default)
		)
	)
	(wire
		(pts
			(xy 265.43 187.325) (xy 273.05 187.325)
		)
		(stroke
			(width 0)
			(type default)
		)
	)
	(wire
		(pts
			(xy 160.02 194.31) (xy 160.02 196.85)
		)
		(stroke
			(width 0)
			(type default)
		)
	)
	(wire
		(pts
			(xy 292.735 60.325) (xy 292.735 57.15)
		)
		(stroke
			(width 0)
			(type default)
		)
	)
	(polyline
		(pts
			(xy 169.545 213.995) (xy 142.24 213.995)
		)
		(stroke
			(width 0)
			(type default)
		)
	)
	(polyline
		(pts
			(xy 13.335 228.6) (xy 42.545 228.6)
		)
		(stroke
			(width 0)
			(type default)
		)
	)
	(wire
		(pts
			(xy 163.195 255.27) (xy 163.195 257.175)
		)
		(stroke
			(width 0)
			(type default)
		)
	)
	(wire
		(pts
			(xy 256.54 53.34) (xy 256.54 54.61)
		)
		(stroke
			(width 0)
			(type default)
		)
	)
	(wire
		(pts
			(xy 66.675 22.225) (xy 66.675 32.385)
		)
		(stroke
			(width 0)
			(type default)
		)
	)
	(wire
		(pts
			(xy 379.095 43.815) (xy 379.095 47.625)
		)
		(stroke
			(width 0)
			(type default)
		)
	)
	(wire
		(pts
			(xy 64.135 92.71) (xy 67.945 92.71)
		)
		(stroke
			(width 0)
			(type default)
		)
	)
	(wire
		(pts
			(xy 40.64 247.015) (xy 41.275 247.015)
		)
		(stroke
			(width 0)
			(type default)
		)
	)
	(wire
		(pts
			(xy 35.56 127) (xy 53.975 127)
		)
		(stroke
			(width 0)
			(type default)
		)
	)
	(wire
		(pts
			(xy 190.5 194.31) (xy 190.5 196.85)
		)
		(stroke
			(width 0)
			(type default)
		)
	)
	(polyline
		(pts
			(xy 101.6 235.585) (xy 101.6 285.115)
		)
		(stroke
			(width 0)
			(type default)
		)
	)
	(wire
		(pts
			(xy 196.215 50.8) (xy 196.215 57.785)
		)
		(stroke
			(width 0)
			(type default)
		)
	)
	(wire
		(pts
			(xy 218.44 26.035) (xy 218.44 27.94)
		)
		(stroke
			(width 0)
			(type default)
		)
	)
	(wire
		(pts
			(xy 64.135 92.71) (xy 64.135 101.6)
		)
		(stroke
			(width 0)
			(type default)
		)
	)
	(wire
		(pts
			(xy 256.54 53.34) (xy 261.62 53.34)
		)
		(stroke
			(width 0)
			(type default)
		)
	)
	(polyline
		(pts
			(xy 337.82 175.895) (xy 365.76 175.895)
		)
		(stroke
			(width 0)
			(type default)
		)
	)
	(wire
		(pts
			(xy 243.84 38.735) (xy 243.84 40.64)
		)
		(stroke
			(width 0)
			(type default)
		)
	)
	(wire
		(pts
			(xy 118.745 201.93) (xy 118.745 202.565)
		)
		(stroke
			(width 0)
			(type default)
		)
	)
	(wire
		(pts
			(xy 110.49 201.93) (xy 110.49 202.565)
		)
		(stroke
			(width 0)
			(type default)
		)
	)
	(wire
		(pts
			(xy 34.29 55.245) (xy 34.29 57.785)
		)
		(stroke
			(width 0)
			(type default)
		)
	)
	(polyline
		(pts
			(xy 13.335 231.14) (xy 42.545 231.14)
		)
		(stroke
			(width 0)
			(type default)
		)
	)
	(wire
		(pts
			(xy 236.22 258.445) (xy 249.555 258.445)
		)
		(stroke
			(width 0)
			(type default)
		)
	)
	(wire
		(pts
			(xy 271.78 182.245) (xy 271.78 168.275)
		)
		(stroke
			(width 0)
			(type default)
		)
	)
	(wire
		(pts
			(xy 123.825 106.68) (xy 125.73 106.68)
		)
		(stroke
			(width 0)
			(type default)
		)
	)
	(wire
		(pts
			(xy 278.13 276.86) (xy 290.83 276.86)
		)
		(stroke
			(width 0)
			(type default)
		)
	)
	(wire
		(pts
			(xy 304.8 163.195) (xy 294.005 163.195)
		)
		(stroke
			(width 0)
			(type default)
		)
	)
	(wire
		(pts
			(xy 284.48 42.545) (xy 269.24 42.545)
		)
		(stroke
			(width 0)
			(type default)
		)
	)
	(wire
		(pts
			(xy 259.08 281.94) (xy 267.97 281.94)
		)
		(stroke
			(width 0)
			(type default)
		)
	)
	(wire
		(pts
			(xy 325.755 212.725) (xy 327.025 212.725)
		)
		(stroke
			(width 0)
			(type default)
		)
	)
	(wire
		(pts
			(xy 21.59 177.165) (xy 21.59 179.07)
		)
		(stroke
			(width 0)
			(type default)
		)
	)
	(wire
		(pts
			(xy 130.81 106.68) (xy 132.715 106.68)
		)
		(stroke
			(width 0)
			(type default)
		)
	)
	(wire
		(pts
			(xy 196.215 71.12) (xy 196.215 72.39)
		)
		(stroke
			(width 0)
			(type default)
		)
	)
	(wire
		(pts
			(xy 114.935 256.54) (xy 114.935 257.81)
		)
		(stroke
			(width 0)
			(type default)
		)
	)
	(wire
		(pts
			(xy 215.9 156.21) (xy 215.9 157.48)
		)
		(stroke
			(width 0)
			(type default)
		)
	)
	(wire
		(pts
			(xy 180.34 165.735) (xy 189.865 165.735)
		)
		(stroke
			(width 0)
			(type default)
		)
	)
	(wire
		(pts
			(xy 304.8 179.705) (xy 304.8 180.34)
		)
		(stroke
			(width 0)
			(type default)
		)
	)
	(wire
		(pts
			(xy 391.795 106.045) (xy 405.13 106.045)
		)
		(stroke
			(width 0)
			(type default)
		)
	)
	(wire
		(pts
			(xy 37.465 157.48) (xy 37.465 174.625)
		)
		(stroke
			(width 0)
			(type default)
		)
	)
	(wire
		(pts
			(xy 123.825 115.57) (xy 123.825 119.38)
		)
		(stroke
			(width 0)
			(type default)
		)
	)
	(wire
		(pts
			(xy 98.425 106.68) (xy 98.425 109.22)
		)
		(stroke
			(width 0)
			(type default)
		)
	)
	(wire
		(pts
			(xy 265.43 197.485) (xy 285.75 197.485)
		)
		(stroke
			(width 0)
			(type default)
		)
	)
	(wire
		(pts
			(xy 286.893 39.37) (xy 286.893 40.005)
		)
		(stroke
			(width 0)
			(type default)
		)
	)
	(wire
		(pts
			(xy 29.21 196.215) (xy 38.735 196.215)
		)
		(stroke
			(width 0)
			(type default)
		)
	)
	(wire
		(pts
			(xy 93.345 243.205) (xy 93.345 247.015)
		)
		(stroke
			(width 0)
			(type default)
		)
	)
	(wire
		(pts
			(xy 130.81 102.235) (xy 132.715 102.235)
		)
		(stroke
			(width 0)
			(type default)
		)
	)
	(wire
		(pts
			(xy 358.14 97.155) (xy 358.14 98.425)
		)
		(stroke
			(width 0)
			(type default)
		)
	)
	(wire
		(pts
			(xy 313.69 213.36) (xy 313.69 212.725)
		)
		(stroke
			(width 0)
			(type default)
		)
	)
	(wire
		(pts
			(xy 290.195 212.725) (xy 290.195 216.535)
		)
		(stroke
			(width 0)
			(type default)
		)
	)
	(wire
		(pts
			(xy 238.76 245.11) (xy 238.76 243.205)
		)
		(stroke
			(width 0)
			(type default)
		)
	)
	(wire
		(pts
			(xy 86.995 158.115) (xy 110.49 158.115)
		)
		(stroke
			(width 0)
			(type default)
		)
	)
	(wire
		(pts
			(xy 398.78 32.385) (xy 398.78 38.735)
		)
		(stroke
			(width 0)
			(type default)
		)
	)
	(wire
		(pts
			(xy 34.29 53.975) (xy 34.29 55.245)
		)
		(stroke
			(width 0)
			(type default)
		)
	)
	(wire
		(pts
			(xy 66.675 192.405) (xy 70.485 192.405)
		)
		(stroke
			(width 0)
			(type default)
		)
	)
	(wire
		(pts
			(xy 85.725 129.54) (xy 85.725 130.81)
		)
		(stroke
			(width 0)
			(type default)
		)
	)
	(wire
		(pts
			(xy 227.965 240.665) (xy 227.965 241.935)
		)
		(stroke
			(width 0)
			(type default)
		)
	)
	(wire
		(pts
			(xy 379.095 32.385) (xy 379.095 38.735)
		)
		(stroke
			(width 0)
			(type default)
		)
	)
	(wire
		(pts
			(xy 286.893 31.115) (xy 286.893 32.385)
		)
		(stroke
			(width 0)
			(type default)
		)
	)
	(wire
		(pts
			(xy 163.195 262.255) (xy 163.195 263.525)
		)
		(stroke
			(width 0)
			(type default)
		)
	)
	(wire
		(pts
			(xy 135.255 124.46) (xy 135.255 127)
		)
		(stroke
			(width 0)
			(type default)
		)
	)
	(wire
		(pts
			(xy 110.49 221.615) (xy 99.06 221.615)
		)
		(stroke
			(width 0)
			(type default)
		)
	)
	(wire
		(pts
			(xy 109.22 249.555) (xy 114.935 249.555)
		)
		(stroke
			(width 0)
			(type default)
		)
	)
	(polyline
		(pts
			(xy 248.92 12.7) (xy 248.92 26.67)
		)
		(stroke
			(width 0)
			(type default)
		)
	)
	(polyline
		(pts
			(xy 367.03 212.09) (xy 367.03 220.345)
		)
		(stroke
			(width 0)
			(type default)
		)
	)
	(wire
		(pts
			(xy 313.055 201.93) (xy 313.055 202.565)
		)
		(stroke
			(width 0)
			(type default)
		)
	)
	(wire
		(pts
			(xy 269.24 40.005) (xy 269.24 42.545)
		)
		(stroke
			(width 0)
			(type default)
		)
	)
	(wire
		(pts
			(xy 86.995 179.705) (xy 86.995 182.245)
		)
		(stroke
			(width 0)
			(type default)
		)
	)
	(wire
		(pts
			(xy 86.995 158.115) (xy 86.995 160.655)
		)
		(stroke
			(width 0)
			(type default)
		)
	)
	(polyline
		(pts
			(xy 230.505 225.425) (xy 230.505 217.805)
		)
		(stroke
			(width 0)
			(type default)
		)
	)
	(polyline
		(pts
			(xy 365.76 184.15) (xy 337.82 184.15)
		)
		(stroke
			(width 0)
			(type default)
		)
	)
	(wire
		(pts
			(xy 276.86 168.275) (xy 285.75 168.275)
		)
		(stroke
			(width 0)
			(type default)
		)
	)
	(wire
		(pts
			(xy 160.02 276.86) (xy 160.02 278.13)
		)
		(stroke
			(width 0)
			(type default)
		)
	)
	(wire
		(pts
			(xy 236.22 174.625) (xy 237.49 174.625)
		)
		(stroke
			(width 0)
			(type default)
		)
	)
	(wire
		(pts
			(xy 234.95 118.11) (xy 250.19 118.11)
		)
		(stroke
			(width 0)
			(type default)
		)
	)
	(polyline
		(pts
			(xy 260.35 235.585) (xy 260.35 269.24)
		)
		(stroke
			(width 0)
			(type default)
		)
	)
	(wire
		(pts
			(xy 17.145 166.37) (xy 17.145 167.64)
		)
		(stroke
			(width 0)
			(type default)
		)
	)
	(wire
		(pts
			(xy 398.78 52.705) (xy 405.13 52.705)
		)
		(stroke
			(width 0)
			(type default)
		)
	)
	(wire
		(pts
			(xy 299.72 100.965) (xy 298.45 100.965)
		)
		(stroke
			(width 0)
			(type default)
		)
	)
	(wire
		(pts
			(xy 29.21 22.225) (xy 33.655 22.225)
		)
		(stroke
			(width 0)
			(type default)
		)
	)
	(wire
		(pts
			(xy 279.4 216.535) (xy 285.75 216.535)
		)
		(stroke
			(width 0)
			(type default)
		)
	)
	(wire
		(pts
			(xy 285.75 179.705) (xy 285.75 182.245)
		)
		(stroke
			(width 0)
			(type default)
		)
	)
	(wire
		(pts
			(xy 313.055 202.565) (xy 324.485 202.565)
		)
		(stroke
			(width 0)
			(type default)
		)
	)
	(wire
		(pts
			(xy 146.685 48.895) (xy 146.685 51.435)
		)
		(stroke
			(width 0)
			(type default)
		)
	)
	(wire
		(pts
			(xy 106.045 106.68) (xy 106.045 109.22)
		)
		(stroke
			(width 0)
			(type default)
		)
	)
	(wire
		(pts
			(xy 89.535 106.68) (xy 89.535 109.22)
		)
		(stroke
			(width 0)
			(type default)
		)
	)
	(wire
		(pts
			(xy 40.64 249.555) (xy 40.64 247.015)
		)
		(stroke
			(width 0)
			(type default)
		)
	)
	(wire
		(pts
			(xy 238.76 250.19) (xy 238.76 251.46)
		)
		(stroke
			(width 0)
			(type default)
		)
	)
	(wire
		(pts
			(xy 29.21 24.765) (xy 30.48 24.765)
		)
		(stroke
			(width 0)
			(type default)
		)
	)
	(wire
		(pts
			(xy 388.62 50.165) (xy 405.13 50.165)
		)
		(stroke
			(width 0)
			(type default)
		)
	)
	(wire
		(pts
			(xy 269.24 179.705) (xy 265.43 179.705)
		)
		(stroke
			(width 0)
			(type default)
		)
	)
	(wire
		(pts
			(xy 290.703 32.385) (xy 290.703 52.07)
		)
		(stroke
			(width 0)
			(type default)
		)
	)
	(wire
		(pts
			(xy 118.745 216.535) (xy 123.825 216.535)
		)
		(stroke
			(width 0)
			(type default)
		)
	)
	(wire
		(pts
			(xy 22.86 260.35) (xy 22.86 261.62)
		)
		(stroke
			(width 0)
			(type default)
		)
	)
	(wire
		(pts
			(xy 236.22 123.19) (xy 236.22 113.03)
		)
		(stroke
			(width 0)
			(type default)
		)
	)
	(wire
		(pts
			(xy 351.155 210.82) (xy 356.87 210.82)
		)
		(stroke
			(width 0)
			(type default)
		)
	)
	(wire
		(pts
			(xy 358.14 98.425) (xy 366.395 98.425)
		)
		(stroke
			(width 0)
			(type default)
		)
	)
	(wire
		(pts
			(xy 21.59 177.165) (xy 38.735 177.165)
		)
		(stroke
			(width 0)
			(type default)
		)
	)
	(wire
		(pts
			(xy 276.86 187.325) (xy 276.86 189.865)
		)
		(stroke
			(width 0)
			(type default)
		)
	)
	(polyline
		(pts
			(xy 368.935 212.09) (xy 396.24 212.09)
		)
		(stroke
			(width 0)
			(type default)
		)
	)
	(polyline
		(pts
			(xy 158.75 82.55) (xy 158.75 142.875)
		)
		(stroke
			(width 0)
			(type default)
		)
	)
	(wire
		(pts
			(xy 170.815 255.27) (xy 170.815 257.175)
		)
		(stroke
			(width 0)
			(type default)
		)
	)
	(wire
		(pts
			(xy 66.675 32.385) (xy 67.945 32.385)
		)
		(stroke
			(width 0)
			(type default)
		)
	)
	(wire
		(pts
			(xy 66.675 65.405) (xy 58.42 65.405)
		)
		(stroke
			(width 0)
			(type default)
		)
	)
	(wire
		(pts
			(xy 220.345 120.65) (xy 222.25 120.65)
		)
		(stroke
			(width 0)
			(type default)
		)
	)
	(wire
		(pts
			(xy 65.405 134.62) (xy 65.405 135.89)
		)
		(stroke
			(width 0)
			(type default)
		)
	)
	(wire
		(pts
			(xy 95.885 55.245) (xy 95.885 65.405)
		)
		(stroke
			(width 0)
			(type default)
		)
	)
	(wire
		(pts
			(xy 118.745 184.785) (xy 130.175 184.785)
		)
		(stroke
			(width 0)
			(type default)
		)
	)
	(wire
		(pts
			(xy 304.8 184.15) (xy 304.8 184.785)
		)
		(stroke
			(width 0)
			(type default)
		)
	)
	(wire
		(pts
			(xy 278.765 259.08) (xy 278.765 261.62)
		)
		(stroke
			(width 0)
			(type default)
		)
	)
	(wire
		(pts
			(xy 236.22 125.73) (xy 236.22 127)
		)
		(stroke
			(width 0)
			(type default)
		)
	)
	(wire
		(pts
			(xy 66.675 37.465) (xy 67.945 37.465)
		)
		(stroke
			(width 0)
			(type default)
		)
	)
	(wire
		(pts
			(xy 111.125 39.37) (xy 113.03 39.37)
		)
		(stroke
			(width 0)
			(type default)
		)
	)
	(polyline
		(pts
			(xy 338.455 43.18) (xy 338.455 82.55)
		)
		(stroke
			(width 0)
			(type default)
		)
	)
	(wire
		(pts
			(xy 79.375 247.015) (xy 85.725 247.015)
		)
		(stroke
			(width 0)
			(type default)
		)
	)
	(wire
		(pts
			(xy 110.49 216.535) (xy 111.76 216.535)
		)
		(stroke
			(width 0)
			(type default)
		)
	)
	(wire
		(pts
			(xy 98.425 114.3) (xy 98.425 116.84)
		)
		(stroke
			(width 0)
			(type default)
		)
	)
	(wire
		(pts
			(xy 66.675 182.245) (xy 73.025 182.245)
		)
		(stroke
			(width 0)
			(type default)
		)
	)
	(wire
		(pts
			(xy 351.155 31.115) (xy 351.155 32.385)
		)
		(stroke
			(width 0)
			(type default)
		)
	)
	(polyline
		(pts
			(xy 185.42 278.13) (xy 185.42 278.13)
		)
		(stroke
			(width 0)
			(type default)
		)
	)
	(wire
		(pts
			(xy 155.575 257.81) (xy 155.575 260.35)
		)
		(stroke
			(width 0)
			(type default)
		)
	)
	(wire
		(pts
			(xy 285.75 187.325) (xy 285.75 189.865)
		)
		(stroke
			(width 0)
			(type default)
		)
	)
	(wire
		(pts
			(xy 304.8 162.56) (xy 304.8 163.195)
		)
		(stroke
			(width 0)
			(type default)
		)
	)
	(wire
		(pts
			(xy 283.21 261.62) (xy 278.765 261.62)
		)
		(stroke
			(width 0)
			(type default)
		)
	)
	(wire
		(pts
			(xy 282.575 108.585) (xy 306.07 108.585)
		)
		(stroke
			(width 0)
			(type default)
		)
	)
	(wire
		(pts
			(xy 212.725 26.035) (xy 212.725 45.72)
		)
		(stroke
			(width 0)
			(type default)
		)
	)
	(polyline
		(pts
			(xy 337.82 175.895) (xy 337.82 184.15)
		)
		(stroke
			(width 0)
			(type default)
		)
	)
	(wire
		(pts
			(xy 196.215 50.8) (xy 213.36 50.8)
		)
		(stroke
			(width 0)
			(type default)
		)
	)
	(wire
		(pts
			(xy 313.055 197.485) (xy 316.865 197.485)
		)
		(stroke
			(width 0)
			(type default)
		)
	)
	(wire
		(pts
			(xy 155.575 260.35) (xy 155.575 264.16)
		)
		(stroke
			(width 0)
			(type default)
		)
	)
	(polyline
		(pts
			(xy 396.24 175.895) (xy 396.24 184.15)
		)
		(stroke
			(width 0)
			(type default)
		)
	)
	(wire
		(pts
			(xy 113.03 276.86) (xy 113.03 278.13)
		)
		(stroke
			(width 0)
			(type default)
		)
	)
	(wire
		(pts
			(xy 62.865 134.62) (xy 62.865 135.89)
		)
		(stroke
			(width 0)
			(type default)
		)
	)
	(wire
		(pts
			(xy 278.765 259.08) (xy 283.21 259.08)
		)
		(stroke
			(width 0)
			(type default)
		)
	)
	(wire
		(pts
			(xy 89.535 106.68) (xy 98.425 106.68)
		)
		(stroke
			(width 0)
			(type default)
		)
	)
	(wire
		(pts
			(xy 286.893 32.385) (xy 286.893 34.29)
		)
		(stroke
			(width 0)
			(type default)
		)
	)
	(polyline
		(pts
			(xy 13.335 228.6) (xy 13.335 233.68)
		)
		(stroke
			(width 0)
			(type default)
		)
	)
	(wire
		(pts
			(xy 193.675 57.785) (xy 193.675 59.69)
		)
		(stroke
			(width 0)
			(type default)
		)
	)
	(wire
		(pts
			(xy 30.48 34.925) (xy 50.165 34.925)
		)
		(stroke
			(width 0)
			(type default)
		)
	)
	(wire
		(pts
			(xy 232.41 38.735) (xy 232.41 45.72)
		)
		(stroke
			(width 0)
			(type default)
		)
	)
	(polyline
		(pts
			(xy 230.505 225.425) (xy 230.505 227.965)
		)
		(stroke
			(width 0)
			(type default)
		)
	)
	(wire
		(pts
			(xy 66.675 174.625) (xy 67.945 174.625)
		)
		(stroke
			(width 0)
			(type default)
		)
	)
	(wire
		(pts
			(xy 226.06 157.48) (xy 236.22 157.48)
		)
		(stroke
			(width 0)
			(type default)
		)
	)
	(wire
		(pts
			(xy 240.03 281.94) (xy 248.92 281.94)
		)
		(stroke
			(width 0)
			(type default)
		)
	)
	(wire
		(pts
			(xy 347.98 108.585) (xy 366.395 108.585)
		)
		(stroke
			(width 0)
			(type default)
		)
	)
	(wire
		(pts
			(xy 66.675 55.245) (xy 79.375 55.245)
		)
		(stroke
			(width 0)
			(type default)
		)
	)
	(wire
		(pts
			(xy 240.03 274.32) (xy 248.92 274.32)
		)
		(stroke
			(width 0)
			(type default)
		)
	)
	(wire
		(pts
			(xy 56.515 249.555) (xy 57.785 249.555)
		)
		(stroke
			(width 0)
			(type default)
		)
	)
	(wire
		(pts
			(xy 232.41 38.735) (xy 243.84 38.735)
		)
		(stroke
			(width 0)
			(type default)
		)
	)
	(wire
		(pts
			(xy 331.47 108.585) (xy 344.805 108.585)
		)
		(stroke
			(width 0)
			(type default)
		)
	)
	(wire
		(pts
			(xy 318.77 59.69) (xy 318.77 58.42)
		)
		(stroke
			(width 0)
			(type default)
		)
	)
	(polyline
		(pts
			(xy 27.305 220.98) (xy 27.305 233.68)
		)
		(stroke
			(width 0)
			(type default)
		)
	)
	(wire
		(pts
			(xy 235.585 50.8) (xy 235.585 53.34)
		)
		(stroke
			(width 0)
			(type default)
		)
	)
	(wire
		(pts
			(xy 41.91 95.25) (xy 41.91 97.79)
		)
		(stroke
			(width 0)
			(type default)
		)
	)
	(wire
		(pts
			(xy 386.715 182.245) (xy 386.715 184.785)
		)
		(stroke
			(width 0)
			(type default)
		)
	)
	(wire
		(pts
			(xy 135.89 51.435) (xy 135.89 41.91)
		)
		(stroke
			(width 0)
			(type default)
		)
	)
	(wire
		(pts
			(xy 56.515 247.015) (xy 57.785 247.015)
		)
		(stroke
			(width 0)
			(type default)
		)
	)
	(wire
		(pts
			(xy 61.595 255.27) (xy 61.595 257.175)
		)
		(stroke
			(width 0)
			(type default)
		)
	)
	(wire
		(pts
			(xy 67.945 67.945) (xy 66.675 67.945)
		)
		(stroke
			(width 0)
			(type default)
		)
	)
	(wire
		(pts
			(xy 108.585 121.92) (xy 108.585 127)
		)
		(stroke
			(width 0)
			(type default)
		)
	)
	(wire
		(pts
			(xy 123.825 178.435) (xy 123.825 179.705)
		)
		(stroke
			(width 0)
			(type default)
		)
	)
	(polyline
		(pts
			(xy 32.385 220.98) (xy 32.385 233.68)
		)
		(stroke
			(width 0)
			(type default)
		)
	)
	(wire
		(pts
			(xy 190.5 281.94) (xy 200.66 281.94)
		)
		(stroke
			(width 0)
			(type default)
		)
	)
	(wire
		(pts
			(xy 193.675 71.12) (xy 196.215 71.12)
		)
		(stroke
			(width 0)
			(type default)
		)
	)
	(wire
		(pts
			(xy 227.965 248.285) (xy 227.965 249.555)
		)
		(stroke
			(width 0)
			(type default)
		)
	)
	(wire
		(pts
			(xy 135.255 115.57) (xy 135.255 119.38)
		)
		(stroke
			(width 0)
			(type default)
		)
	)
	(wire
		(pts
			(xy 185.42 204.47) (xy 190.5 204.47)
		)
		(stroke
			(width 0)
			(type default)
		)
	)
	(polyline
		(pts
			(xy 172.72 205.74) (xy 200.025 205.74)
		)
		(stroke
			(width 0)
			(type default)
		)
	)
	(polyline
		(pts
			(xy 200.025 205.74) (xy 200.025 213.995)
		)
		(stroke
			(width 0)
			(type default)
		)
	)
	(wire
		(pts
			(xy 285.75 197.485) (xy 285.75 200.025)
		)
		(stroke
			(width 0)
			(type default)
		)
	)
	(wire
		(pts
			(xy 50.165 22.225) (xy 66.675 22.225)
		)
		(stroke
			(width 0)
			(type default)
		)
	)
	(wire
		(pts
			(xy 276.86 261.62) (xy 278.765 261.62)
		)
		(stroke
			(width 0)
			(type default)
		)
	)
	(wire
		(pts
			(xy 178.435 118.11) (xy 220.345 118.11)
		)
		(stroke
			(width 0)
			(type default)
		)
	)
	(wire
		(pts
			(xy 249.555 105.41) (xy 234.95 105.41)
		)
		(stroke
			(width 0)
			(type default)
		)
	)
	(wire
		(pts
			(xy 198.755 110.49) (xy 204.47 110.49)
		)
		(stroke
			(width 0)
			(type default)
		)
	)
	(wire
		(pts
			(xy 209.55 48.26) (xy 213.36 48.26)
		)
		(stroke
			(width 0)
			(type default)
		)
	)
	(wire
		(pts
			(xy 304.8 179.705) (xy 306.07 179.705)
		)
		(stroke
			(width 0)
			(type default)
		)
	)
	(wire
		(pts
			(xy 304.8 184.785) (xy 294.64 184.785)
		)
		(stroke
			(width 0)
			(type default)
		)
	)
	(wire
		(pts
			(xy 118.745 158.75) (xy 118.745 158.115)
		)
		(stroke
			(width 0)
			(type default)
		)
	)
	(wire
		(pts
			(xy 22.86 247.015) (xy 40.64 247.015)
		)
		(stroke
			(width 0)
			(type default)
		)
	)
	(wire
		(pts
			(xy 234.95 113.03) (xy 236.22 113.03)
		)
		(stroke
			(width 0)
			(type default)
		)
	)
	(wire
		(pts
			(xy 58.42 31.115) (xy 58.42 32.385)
		)
		(stroke
			(width 0)
			(type default)
		)
	)
	(wire
		(pts
			(xy 269.24 210.185) (xy 265.43 210.185)
		)
		(stroke
			(width 0)
			(type default)
		)
	)
	(wire
		(pts
			(xy 236.22 110.49) (xy 234.95 110.49)
		)
		(stroke
			(width 0)
			(type default)
		)
	)
	(wire
		(pts
			(xy 123.825 106.68) (xy 123.825 102.235)
		)
		(stroke
			(width 0)
			(type default)
		)
	)
	(wire
		(pts
			(xy 331.47 116.205) (xy 344.805 116.205)
		)
		(stroke
			(width 0)
			(type default)
		)
	)
	(wire
		(pts
			(xy 123.825 127) (xy 123.825 129.54)
		)
		(stroke
			(width 0)
			(type default)
		)
	)
	(wire
		(pts
			(xy 355.6 174.625) (xy 355.6 177.165)
		)
		(stroke
			(width 0)
			(type default)
		)
	)
	(wire
		(pts
			(xy 74.295 129.54) (xy 85.725 129.54)
		)
		(stroke
			(width 0)
			(type default)
		)
	)
	(wire
		(pts
			(xy 325.755 158.115) (xy 327.66 158.115)
		)
		(stroke
			(width 0)
			(type default)
		)
	)
	(wire
		(pts
			(xy 388.62 32.385) (xy 388.62 38.735)
		)
		(stroke
			(width 0)
			(type default)
		)
	)
	(wire
		(pts
			(xy 381.635 210.82) (xy 386.715 210.82)
		)
		(stroke
			(width 0)
			(type default)
		)
	)
	(bus
		(pts
			(xy 175.26 111.125) (xy 175.895 111.76)
		)
		(stroke
			(width 0)
			(type default)
		)
	)
	(wire
		(pts
			(xy 37.465 210.185) (xy 38.735 210.185)
		)
		(stroke
			(width 0)
			(type default)
		)
	)
	(wire
		(pts
			(xy 381.635 174.625) (xy 386.715 174.625)
		)
		(stroke
			(width 0)
			(type default)
		)
	)
	(polyline
		(pts
			(xy 12.065 235.585) (xy 299.72 235.585)
		)
		(stroke
			(width 0)
			(type default)
		)
	)
	(wire
		(pts
			(xy 135.89 51.435) (xy 146.685 51.435)
		)
		(stroke
			(width 0)
			(type default)
		)
	)
	(wire
		(pts
			(xy 339.09 243.205) (xy 337.82 243.205)
		)
		(stroke
			(width 0)
			(type default)
		)
	)
	(wire
		(pts
			(xy 154.94 255.27) (xy 163.195 255.27)
		)
		(stroke
			(width 0)
			(type default)
		)
	)
	(wire
		(pts
			(xy 281.94 207.645) (xy 285.75 207.645)
		)
		(stroke
			(width 0)
			(type default)
		)
	)
	(wire
		(pts
			(xy 110.49 184.785) (xy 99.06 184.785)
		)
		(stroke
			(width 0)
			(type default)
		)
	)
	(wire
		(pts
			(xy 360.045 100.965) (xy 358.14 100.965)
		)
		(stroke
			(width 0)
			(type default)
		)
	)
	(wire
		(pts
			(xy 210.185 107.95) (xy 222.25 107.95)
		)
		(stroke
			(width 0)
			(type default)
		)
	)
	(wire
		(pts
			(xy 294.005 54.61) (xy 284.48 54.61)
		)
		(stroke
			(width 0)
			(type default)
		)
	)
	(wire
		(pts
			(xy 163.195 253.365) (xy 163.195 255.27)
		)
		(stroke
			(width 0)
			(type default)
		)
	)
	(wire
		(pts
			(xy 379.095 32.385) (xy 388.62 32.385)
		)
		(stroke
			(width 0)
			(type default)
		)
	)
	(wire
		(pts
			(xy 276.86 189.865) (xy 285.75 189.865)
		)
		(stroke
			(width 0)
			(type default)
		)
	)
	(wire
		(pts
			(xy 331.47 98.425) (xy 347.345 98.425)
		)
		(stroke
			(width 0)
			(type default)
		)
	)
	(wire
		(pts
			(xy 50.165 93.98) (xy 50.165 95.25)
		)
		(stroke
			(width 0)
			(type default)
		)
	)
	(bus
		(pts
			(xy 175.895 113.03) (xy 175.895 115.57)
		)
		(stroke
			(width 0)
			(type default)
		)
	)
	(wire
		(pts
			(xy 29.21 193.675) (xy 38.735 193.675)
		)
		(stroke
			(width 0)
			(type default)
		)
	)
	(wire
		(pts
			(xy 131.445 178.435) (xy 131.445 179.705)
		)
		(stroke
			(width 0)
			(type default)
		)
	)
	(wire
		(pts
			(xy 184.15 48.26) (xy 209.55 48.26)
		)
		(stroke
			(width 0)
			(type default)
		)
	)
	(wire
		(pts
			(xy 85.725 247.015) (xy 93.345 247.015)
		)
		(stroke
			(width 0)
			(type default)
		)
	)
	(wire
		(pts
			(xy 86.995 179.705) (xy 110.49 179.705)
		)
		(stroke
			(width 0)
			(type default)
		)
	)
	(wire
		(pts
			(xy 17.145 121.92) (xy 17.145 124.46)
		)
		(stroke
			(width 0)
			(type default)
		)
	)
	(wire
		(pts
			(xy 27.305 157.48) (xy 37.465 157.48)
		)
		(stroke
			(width 0)
			(type default)
		)
	)
	(wire
		(pts
			(xy 184.15 55.245) (xy 184.15 48.26)
		)
		(stroke
			(width 0)
			(type default)
		)
	)
	(polyline
		(pts
			(xy 215.265 220.345) (xy 215.265 233.68)
		)
		(stroke
			(width 0)
			(type default)
		)
	)
	(wire
		(pts
			(xy 106.045 116.84) (xy 114.935 116.84)
		)
		(stroke
			(width 0)
			(type default)
		)
	)
	(wire
		(pts
			(xy 52.705 55.245) (xy 66.675 55.245)
		)
		(stroke
			(width 0)
			(type default)
		)
	)
	(wire
		(pts
			(xy 284.48 157.48) (xy 284.48 158.115)
		)
		(stroke
			(width 0)
			(type default)
		)
	)
	(polyline
		(pts
			(xy 396.24 212.09) (xy 396.24 220.345)
		)
		(stroke
			(width 0)
			(type default)
		)
	)
	(wire
		(pts
			(xy 313.055 158.75) (xy 313.055 158.115)
		)
		(stroke
			(width 0)
			(type default)
		)
	)
	(wire
		(pts
			(xy 78.105 189.865) (xy 86.995 189.865)
		)
		(stroke
			(width 0)
			(type default)
		)
	)
	(wire
		(pts
			(xy 50.165 130.81) (xy 50.165 129.54)
		)
		(stroke
			(width 0)
			(type default)
		)
	)
	(wire
		(pts
			(xy 98.425 106.68) (xy 106.045 106.68)
		)
		(stroke
			(width 0)
			(type default)
		)
	)
	(wire
		(pts
			(xy 316.865 157.48) (xy 316.865 158.115)
		)
		(stroke
			(width 0)
			(type default)
		)
	)
	(wire
		(pts
			(xy 86.995 205.105) (xy 86.995 207.645)
		)
		(stroke
			(width 0)
			(type default)
		)
	)
	(wire
		(pts
			(xy 215.9 278.13) (xy 229.87 278.13)
		)
		(stroke
			(width 0)
			(type default)
		)
	)
	(wire
		(pts
			(xy 227.965 263.525) (xy 227.965 262.255)
		)
		(stroke
			(width 0)
			(type default)
		)
	)
	(wire
		(pts
			(xy 346.71 50.165) (xy 341.63 50.165)
		)
		(stroke
			(width 0)
			(type default)
		)
	)
	(wire
		(pts
			(xy 70.485 179.705) (xy 66.675 179.705)
		)
		(stroke
			(width 0)
			(type default)
		)
	)
	(wire
		(pts
			(xy 184.785 176.53) (xy 189.865 176.53)
		)
		(stroke
			(width 0)
			(type default)
		)
	)
	(wire
		(pts
			(xy 386.715 208.28) (xy 386.715 210.82)
		)
		(stroke
			(width 0)
			(type default)
		)
	)
	(wire
		(pts
			(xy 285.75 197.485) (xy 304.8 197.485)
		)
		(stroke
			(width 0)
			(type default)
		)
	)
	(wire
		(pts
			(xy 358.14 100.965) (xy 358.14 98.425)
		)
		(stroke
			(width 0)
			(type default)
		)
	)
	(polyline
		(pts
			(xy 201.295 235.585) (xy 201.295 269.24)
		)
		(stroke
			(width 0)
			(type default)
		)
	)
	(wire
		(pts
			(xy 236.22 248.285) (xy 236.22 258.445)
		)
		(stroke
			(width 0)
			(type default)
		)
	)
	(wire
		(pts
			(xy 97.79 121.92) (xy 108.585 121.92)
		)
		(stroke
			(width 0)
			(type default)
		)
	)
	(wire
		(pts
			(xy 123.825 115.57) (xy 135.255 115.57)
		)
		(stroke
			(width 0)
			(type default)
		)
	)
	(wire
		(pts
			(xy 171.45 64.135) (xy 171.45 65.405)
		)
		(stroke
			(width 0)
			(type default)
		)
	)
	(wire
		(pts
			(xy 249.555 107.95) (xy 234.95 107.95)
		)
		(stroke
			(width 0)
			(type default)
		)
	)
	(wire
		(pts
			(xy 50.165 106.68) (xy 53.975 106.68)
		)
		(stroke
			(width 0)
			(type default)
		)
	)
	(wire
		(pts
			(xy 288.29 256.54) (xy 294.64 256.54)
		)
		(stroke
			(width 0)
			(type default)
		)
	)
	(wire
		(pts
			(xy 313.055 179.705) (xy 316.865 179.705)
		)
		(stroke
			(width 0)
			(type default)
		)
	)
	(wire
		(pts
			(xy 180.34 252.73) (xy 180.34 254)
		)
		(stroke
			(width 0)
			(type default)
		)
	)
	(wire
		(pts
			(xy 58.42 75.565) (xy 66.675 75.565)
		)
		(stroke
			(width 0)
			(type default)
		)
	)
	(wire
		(pts
			(xy 331.47 106.045) (xy 344.805 106.045)
		)
		(stroke
			(width 0)
			(type default)
		)
	)
	(wire
		(pts
			(xy 366.395 32.385) (xy 379.095 32.385)
		)
		(stroke
			(width 0)
			(type default)
		)
	)
	(wire
		(pts
			(xy 204.47 110.49) (xy 222.25 110.49)
		)
		(stroke
			(width 0)
			(type default)
		)
	)
	(wire
		(pts
			(xy 95.885 22.225) (xy 98.425 22.225)
		)
		(stroke
			(width 0)
			(type default)
		)
	)
	(wire
		(pts
			(xy 193.675 71.12) (xy 193.675 69.85)
		)
		(stroke
			(width 0)
			(type default)
		)
	)
	(wire
		(pts
			(xy 76.835 92.71) (xy 76.835 106.68)
		)
		(stroke
			(width 0)
			(type default)
		)
	)
	(wire
		(pts
			(xy 86.995 207.645) (xy 86.995 208.915)
		)
		(stroke
			(width 0)
			(type default)
		)
	)
	(wire
		(pts
			(xy 209.55 26.67) (xy 209.55 39.37)
		)
		(stroke
			(width 0)
			(type default)
		)
	)
	(wire
		(pts
			(xy 58.42 40.005) (xy 58.42 42.545)
		)
		(stroke
			(width 0)
			(type default)
		)
	)
	(wire
		(pts
			(xy 316.865 196.85) (xy 316.865 197.485)
		)
		(stroke
			(width 0)
			(type default)
		)
	)
	(wire
		(pts
			(xy 346.71 50.165) (xy 356.235 50.165)
		)
		(stroke
			(width 0)
			(type default)
		)
	)
	(polyline
		(pts
			(xy 172.085 177.8) (xy 172.085 186.055)
		)
		(stroke
			(width 0)
			(type default)
		)
	)
	(wire
		(pts
			(xy 58.42 65.405) (xy 58.42 67.945)
		)
		(stroke
			(width 0)
			(type default)
		)
	)
	(polyline
		(pts
			(xy 203.835 222.885) (xy 230.505 222.885)
		)
		(stroke
			(width 0)
			(type default)
		)
	)
	(wire
		(pts
			(xy 171.45 72.39) (xy 171.45 70.485)
		)
		(stroke
			(width 0)
			(type default)
		)
	)
	(wire
		(pts
			(xy 85.725 65.405) (xy 95.885 65.405)
		)
		(stroke
			(width 0)
			(type default)
		)
	)
	(wire
		(pts
			(xy 325.755 211.455) (xy 325.755 212.725)
		)
		(stroke
			(width 0)
			(type default)
		)
	)
	(wire
		(pts
			(xy 57.785 252.095) (xy 57.785 257.175)
		)
		(stroke
			(width 0)
			(type default)
		)
	)
	(wire
		(pts
			(xy 313.055 184.15) (xy 313.055 184.785)
		)
		(stroke
			(width 0)
			(type default)
		)
	)
	(wire
		(pts
			(xy 353.06 127.635) (xy 353.06 128.905)
		)
		(stroke
			(width 0)
			(type default)
		)
	)
	(wire
		(pts
			(xy 276.86 179.705) (xy 276.86 182.245)
		)
		(stroke
			(width 0)
			(type default)
		)
	)
	(wire
		(pts
			(xy 118.745 184.15) (xy 118.745 184.785)
		)
		(stroke
			(width 0)
			(type default)
		)
	)
	(wire
		(pts
			(xy 285.75 158.115) (xy 285.75 160.655)
		)
		(stroke
			(width 0)
			(type default)
		)
	)
	(wire
		(pts
			(xy 37.465 210.185) (xy 37.465 212.09)
		)
		(stroke
			(width 0)
			(type default)
		)
	)
	(wire
		(pts
			(xy 227.965 247.015) (xy 227.965 248.285)
		)
		(stroke
			(width 0)
			(type default)
		)
	)
	(wire
		(pts
			(xy 285.75 165.735) (xy 285.75 168.275)
		)
		(stroke
			(width 0)
			(type default)
		)
	)
	(wire
		(pts
			(xy 75.565 179.705) (xy 78.105 179.705)
		)
		(stroke
			(width 0)
			(type default)
		)
	)
	(wire
		(pts
			(xy 259.08 274.32) (xy 267.97 274.32)
		)
		(stroke
			(width 0)
			(type default)
		)
	)
	(wire
		(pts
			(xy 85.09 157.48) (xy 85.09 158.115)
		)
		(stroke
			(width 0)
			(type default)
		)
	)
	(polyline
		(pts
			(xy 368.935 175.895) (xy 368.935 184.15)
		)
		(stroke
			(width 0)
			(type default)
		)
	)
	(wire
		(pts
			(xy 234.95 120.65) (xy 250.19 120.65)
		)
		(stroke
			(width 0)
			(type default)
		)
	)
	(wire
		(pts
			(xy 88.265 34.925) (xy 88.265 29.845)
		)
		(stroke
			(width 0)
			(type default)
		)
	)
	(wire
		(pts
			(xy 246.38 253.365) (xy 249.555 253.365)
		)
		(stroke
			(width 0)
			(type default)
		)
	)
	(wire
		(pts
			(xy 110.49 158.115) (xy 111.76 158.115)
		)
		(stroke
			(width 0)
			(type default)
		)
	)
	(wire
		(pts
			(xy 86.995 187.325) (xy 86.995 189.865)
		)
		(stroke
			(width 0)
			(type default)
		)
	)
	(wire
		(pts
			(xy 78.105 187.325) (xy 78.105 189.865)
		)
		(stroke
			(width 0)
			(type default)
		)
	)
	(wire
		(pts
			(xy 160.02 173.99) (xy 160.02 176.53)
		)
		(stroke
			(width 0)
			(type default)
		)
	)
	(wire
		(pts
			(xy 146.685 39.37) (xy 147.955 39.37)
		)
		(stroke
			(width 0)
			(type default)
		)
	)
	(wire
		(pts
			(xy 269.24 192.405) (xy 265.43 192.405)
		)
		(stroke
			(width 0)
			(type default)
		)
	)
	(wire
		(pts
			(xy 331.47 113.665) (xy 344.805 113.665)
		)
		(stroke
			(width 0)
			(type default)
		)
	)
	(polyline
		(pts
			(xy 210.185 221.615) (xy 210.185 233.68)
		)
		(stroke
			(width 0)
			(type default)
		)
	)
	(wire
		(pts
			(xy 34.29 55.245) (xy 47.625 55.245)
		)
		(stroke
			(width 0)
			(type default)
		)
	)
	(wire
		(pts
			(xy 160.02 184.15) (xy 160.02 186.69)
		)
		(stroke
			(width 0)
			(type default)
		)
	)
	(polyline
		(pts
			(xy 42.545 226.06) (xy 42.545 228.6)
		)
		(stroke
			(width 0)
			(type default)
		)
	)
	(wire
		(pts
			(xy 61.595 247.015) (xy 61.595 250.19)
		)
		(stroke
			(width 0)
			(type default)
		)
	)
	(wire
		(pts
			(xy 29.21 102.87) (xy 29.21 105.41)
		)
		(stroke
			(width 0)
			(type default)
		)
	)
	(wire
		(pts
			(xy 29.21 105.41) (xy 17.145 105.41)
		)
		(stroke
			(width 0)
			(type default)
		)
	)
	(wire
		(pts
			(xy 118.745 217.17) (xy 118.745 216.535)
		)
		(stroke
			(width 0)
			(type default)
		)
	)
	(wire
		(pts
			(xy 209.55 48.26) (xy 209.55 44.45)
		)
		(stroke
			(width 0)
			(type default)
		)
	)
	(polyline
		(pts
			(xy 299.72 235.585) (xy 299.72 252.73)
		)
		(stroke
			(width 0)
			(type default)
		)
	)
	(wire
		(pts
			(xy 218.44 26.035) (xy 212.725 26.035)
		)
		(stroke
			(width 0)
			(type default)
		)
	)
	(polyline
		(pts
			(xy 338.455 212.09) (xy 367.03 212.09)
		)
		(stroke
			(width 0)
			(type default)
		)
	)
	(wire
		(pts
			(xy 227.965 248.285) (xy 236.22 248.285)
		)
		(stroke
			(width 0)
			(type default)
		)
	)
	(polyline
		(pts
			(xy 203.835 225.425) (xy 230.505 225.425)
		)
		(stroke
			(width 0)
			(type default)
		)
	)
	(wire
		(pts
			(xy 256.54 61.595) (xy 256.54 59.69)
		)
		(stroke
			(width 0)
			(type default)
		)
	)
	(wire
		(pts
			(xy 92.075 55.245) (xy 95.885 55.245)
		)
		(stroke
			(width 0)
			(type default)
		)
	)
	(wire
		(pts
			(xy 238.76 242.57) (xy 238.76 243.205)
		)
		(stroke
			(width 0)
			(type default)
		)
	)
	(polyline
		(pts
			(xy 396.24 184.15) (xy 368.935 184.15)
		)
		(stroke
			(width 0)
			(type default)
		)
	)
	(wire
		(pts
			(xy 33.655 22.225) (xy 38.735 22.225)
		)
		(stroke
			(width 0)
			(type default)
		)
	)
	(wire
		(pts
			(xy 316.865 158.115) (xy 325.755 158.115)
		)
		(stroke
			(width 0)
			(type default)
		)
	)
	(wire
		(pts
			(xy 154.305 204.47) (xy 160.02 204.47)
		)
		(stroke
			(width 0)
			(type default)
		)
	)
	(wire
		(pts
			(xy 132.715 102.235) (xy 132.715 106.68)
		)
		(stroke
			(width 0)
			(type default)
		)
	)
	(wire
		(pts
			(xy 356.87 210.82) (xy 356.87 213.36)
		)
		(stroke
			(width 0)
			(type default)
		)
	)
	(wire
		(pts
			(xy 309.245 54.61) (xy 311.15 54.61)
		)
		(stroke
			(width 0)
			(type default)
		)
	)
	(wire
		(pts
			(xy 110.49 184.15) (xy 110.49 184.785)
		)
		(stroke
			(width 0)
			(type default)
		)
	)
	(wire
		(pts
			(xy 285.75 189.865) (xy 285.75 191.135)
		)
		(stroke
			(width 0)
			(type default)
		)
	)
	(wire
		(pts
			(xy 364.49 116.205) (xy 364.49 118.745)
		)
		(stroke
			(width 0)
			(type default)
		)
	)
	(wire
		(pts
			(xy 305.435 217.17) (xy 305.435 217.805)
		)
		(stroke
			(width 0)
			(type default)
		)
	)
	(wire
		(pts
			(xy 405.13 123.825) (xy 391.795 123.825)
		)
		(stroke
			(width 0)
			(type default)
		)
	)
	(wire
		(pts
			(xy 118.745 163.195) (xy 135.255 163.195)
		)
		(stroke
			(width 0)
			(type default)
		)
	)
	(wire
		(pts
			(xy 376.555 52.705) (xy 398.78 52.705)
		)
		(stroke
			(width 0)
			(type default)
		)
	)
	(wire
		(pts
			(xy 123.825 215.265) (xy 123.825 216.535)
		)
		(stroke
			(width 0)
			(type default)
		)
	)
	(wire
		(pts
			(xy 110.49 197.485) (xy 111.76 197.485)
		)
		(stroke
			(width 0)
			(type default)
		)
	)
	(wire
		(pts
			(xy 17.145 114.3) (xy 53.975 114.3)
		)
		(stroke
			(width 0)
			(type default)
		)
	)
	(polyline
		(pts
			(xy 210.185 220.345) (xy 210.185 221.615)
		)
		(stroke
			(width 0)
			(type default)
		)
	)
	(wire
		(pts
			(xy 122.555 255.27) (xy 135.89 255.27)
		)
		(stroke
			(width 0)
			(type default)
		)
	)
	(wire
		(pts
			(xy 120.65 276.86) (xy 120.65 278.13)
		)
		(stroke
			(width 0)
			(type default)
		)
	)
	(wire
		(pts
			(xy 180.34 245.745) (xy 182.245 245.745)
		)
		(stroke
			(width 0)
			(type default)
		)
	)
	(wire
		(pts
			(xy 98.425 116.84) (xy 106.045 116.84)
		)
		(stroke
			(width 0)
			(type default)
		)
	)
	(wire
		(pts
			(xy 139.065 38.735) (xy 139.065 39.37)
		)
		(stroke
			(width 0)
			(type default)
		)
	)
	(wire
		(pts
			(xy 67.945 34.925) (xy 66.675 34.925)
		)
		(stroke
			(width 0)
			(type default)
		)
	)
	(wire
		(pts
			(xy 92.71 32.385) (xy 95.885 32.385)
		)
		(stroke
			(width 0)
			(type default)
		)
	)
	(wire
		(pts
			(xy 28.575 259.08) (xy 28.575 260.35)
		)
		(stroke
			(width 0)
			(type default)
		)
	)
	(wire
		(pts
			(xy 17.145 105.41) (xy 17.145 106.045)
		)
		(stroke
			(width 0)
			(type default)
		)
	)
	(wire
		(pts
			(xy 313.69 212.725) (xy 317.5 212.725)
		)
		(stroke
			(width 0)
			(type default)
		)
	)
	(wire
		(pts
			(xy 114.3 39.37) (xy 113.03 39.37)
		)
		(stroke
			(width 0)
			(type default)
		)
	)
	(wire
		(pts
			(xy 110.49 180.34) (xy 110.49 179.705)
		)
		(stroke
			(width 0)
			(type default)
		)
	)
	(wire
		(pts
			(xy 66.675 55.245) (xy 66.675 65.405)
		)
		(stroke
			(width 0)
			(type default)
		)
	)
	(polyline
		(pts
			(xy 142.24 205.74) (xy 169.545 205.74)
		)
		(stroke
			(width 0)
			(type default)
		)
	)
	(wire
		(pts
			(xy 210.185 105.41) (xy 222.25 105.41)
		)
		(stroke
			(width 0)
			(type default)
		)
	)
	(wire
		(pts
			(xy 325.755 196.215) (xy 325.755 197.485)
		)
		(stroke
			(width 0)
			(type default)
		)
	)
	(wire
		(pts
			(xy 47.625 111.76) (xy 53.975 111.76)
		)
		(stroke
			(width 0)
			(type default)
		)
	)
	(polyline
		(pts
			(xy 42.545 220.98) (xy 22.225 220.98)
		)
		(stroke
			(width 0)
			(type default)
		)
	)
	(wire
		(pts
			(xy 17.145 156.21) (xy 17.145 157.48)
		)
		(stroke
			(width 0)
			(type default)
		)
	)
	(wire
		(pts
			(xy 171.45 64.135) (xy 176.53 64.135)
		)
		(stroke
			(width 0)
			(type default)
		)
	)
	(wire
		(pts
			(xy 17.78 247.015) (xy 22.86 247.015)
		)
		(stroke
			(width 0)
			(type default)
		)
	)
	(wire
		(pts
			(xy 196.215 71.12) (xy 196.215 69.85)
		)
		(stroke
			(width 0)
			(type default)
		)
	)
	(wire
		(pts
			(xy 74.295 106.68) (xy 76.835 106.68)
		)
		(stroke
			(width 0)
			(type default)
		)
	)
	(wire
		(pts
			(xy 58.42 32.385) (xy 58.42 34.925)
		)
		(stroke
			(width 0)
			(type default)
		)
	)
	(wire
		(pts
			(xy 190.5 274.32) (xy 200.66 274.32)
		)
		(stroke
			(width 0)
			(type default)
		)
	)
	(polyline
		(pts
			(xy 42.545 226.06) (xy 42.545 218.44)
		)
		(stroke
			(width 0)
			(type default)
		)
	)
	(wire
		(pts
			(xy 231.14 50.8) (xy 235.585 50.8)
		)
		(stroke
			(width 0)
			(type default)
		)
	)
	(polyline
		(pts
			(xy 172.72 205.74) (xy 172.72 213.995)
		)
		(stroke
			(width 0)
			(type default)
		)
	)
	(wire
		(pts
			(xy 138.43 106.68) (xy 144.145 106.68)
		)
		(stroke
			(width 0)
			(type default)
		)
	)
	(wire
		(pts
			(xy 81.915 202.565) (xy 81.915 207.645)
		)
		(stroke
			(width 0)
			(type default)
		)
	)
	(wire
		(pts
			(xy 118.745 220.98) (xy 118.745 221.615)
		)
		(stroke
			(width 0)
			(type default)
		)
	)
	(wire
		(pts
			(xy 184.15 72.39) (xy 184.15 67.945)
		)
		(stroke
			(width 0)
			(type default)
		)
	)
	(wire
		(pts
			(xy 34.29 62.865) (xy 34.29 66.675)
		)
		(stroke
			(width 0)
			(type default)
		)
	)
	(polyline
		(pts
			(xy 200.025 213.995) (xy 172.72 213.995)
		)
		(stroke
			(width 0)
			(type default)
		)
	)
	(polyline
		(pts
			(xy 22.225 222.25) (xy 22.225 233.68)
		)
		(stroke
			(width 0)
			(type default)
		)
	)
	(wire
		(pts
			(xy 30.48 34.925) (xy 30.48 36.195)
		)
		(stroke
			(width 0)
			(type default)
		)
	)
	(wire
		(pts
			(xy 204.47 97.79) (xy 204.47 96.52)
		)
		(stroke
			(width 0)
			(type default)
		)
	)
	(wire
		(pts
			(xy 118.745 221.615) (xy 130.175 221.615)
		)
		(stroke
			(width 0)
			(type default)
		)
	)
	(wire
		(pts
			(xy 105.41 276.86) (xy 105.41 278.13)
		)
		(stroke
			(width 0)
			(type default)
		)
	)
	(wire
		(pts
			(xy 122.555 257.81) (xy 135.89 257.81)
		)
		(stroke
			(width 0)
			(type default)
		)
	)
	(wire
		(pts
			(xy 189.865 165.735) (xy 189.865 168.91)
		)
		(stroke
			(width 0)
			(type default)
		)
	)
	(wire
		(pts
			(xy 285.75 205.105) (xy 285.75 207.645)
		)
		(stroke
			(width 0)
			(type default)
		)
	)
	(wire
		(pts
			(xy 154.94 260.35) (xy 155.575 260.35)
		)
		(stroke
			(width 0)
			(type default)
		)
	)
	(wire
		(pts
			(xy 271.78 168.275) (xy 276.86 168.275)
		)
		(stroke
			(width 0)
			(type default)
		)
	)
	(wire
		(pts
			(xy 123.825 216.535) (xy 128.905 216.535)
		)
		(stroke
			(width 0)
			(type default)
		)
	)
	(wire
		(pts
			(xy 305.435 213.36) (xy 305.435 212.725)
		)
		(stroke
			(width 0)
			(type default)
		)
	)
	(wire
		(pts
			(xy 144.145 98.425) (xy 144.145 106.68)
		)
		(stroke
			(width 0)
			(type default)
		)
	)
	(wire
		(pts
			(xy 279.4 207.645) (xy 279.4 216.535)
		)
		(stroke
			(width 0)
			(type default)
		)
	)
	(wire
		(pts
			(xy 110.49 220.98) (xy 110.49 221.615)
		)
		(stroke
			(width 0)
			(type default)
		)
	)
	(polyline
		(pts
			(xy 338.455 212.09) (xy 338.455 220.345)
		)
		(stroke
			(width 0)
			(type default)
		)
	)
	(polyline
		(pts
			(xy 158.75 12.7) (xy 158.75 82.55)
		)
		(stroke
			(width 0)
			(type default)
		)
	)
	(polyline
		(pts
			(xy 102.235 12.065) (xy 102.235 82.55)
		)
		(stroke
			(width 0)
			(type default)
		)
	)
	(polyline
		(pts
			(xy 169.545 205.74) (xy 169.545 213.995)
		)
		(stroke
			(width 0)
			(type default)
		)
	)
	(wire
		(pts
			(xy 290.703 52.07) (xy 294.005 52.07)
		)
		(stroke
			(width 0)
			(type default)
		)
	)
	(wire
		(pts
			(xy 34.925 184.785) (xy 38.735 184.785)
		)
		(stroke
			(width 0)
			(type default)
		)
	)
	(wire
		(pts
			(xy 58.42 64.135) (xy 58.42 65.405)
		)
		(stroke
			(width 0)
			(type default)
		)
	)
	(wire
		(pts
			(xy 114.3 41.91) (xy 113.03 41.91)
		)
		(stroke
			(width 0)
			(type default)
		)
	)
	(wire
		(pts
			(xy 138.43 105.41) (xy 138.43 106.68)
		)
		(stroke
			(width 0)
			(type default)
		)
	)
	(wire
		(pts
			(xy 236.22 210.185) (xy 237.49 210.185)
		)
		(stroke
			(width 0)
			(type default)
		)
	)
	(polyline
		(pts
			(xy 269.24 82.55) (xy 269.24 142.875)
		)
		(stroke
			(width 0)
			(type default)
		)
	)
	(wire
		(pts
			(xy 269.24 61.595) (xy 269.24 57.15)
		)
		(stroke
			(width 0)
			(type default)
		)
	)
	(wire
		(pts
			(xy 17.145 95.25) (xy 17.145 97.79)
		)
		(stroke
			(width 0)
			(type default)
		)
	)
	(polyline
		(pts
			(xy 200.025 177.8) (xy 200.025 186.055)
		)
		(stroke
			(width 0)
			(type default)
		)
	)
	(wire
		(pts
			(xy 281.94 202.565) (xy 281.94 207.645)
		)
		(stroke
			(width 0)
			(type default)
		)
	)
	(wire
		(pts
			(xy 238.76 243.205) (xy 246.38 243.205)
		)
		(stroke
			(width 0)
			(type default)
		)
	)
	(wire
		(pts
			(xy 269.24 200.025) (xy 265.43 200.025)
		)
		(stroke
			(width 0)
			(type default)
		)
	)
	(wire
		(pts
			(xy 316.865 197.485) (xy 325.755 197.485)
		)
		(stroke
			(width 0)
			(type default)
		)
	)
	(wire
		(pts
			(xy 366.395 32.385) (xy 366.395 42.545)
		)
		(stroke
			(width 0)
			(type default)
		)
	)
	(wire
		(pts
			(xy 48.895 120.65) (xy 53.975 120.65)
		)
		(stroke
			(width 0)
			(type default)
		)
	)
	(wire
		(pts
			(xy 113.03 41.91) (xy 113.03 39.37)
		)
		(stroke
			(width 0)
			(type default)
		)
	)
	(wire
		(pts
			(xy 66.675 197.485) (xy 86.995 197.485)
		)
		(stroke
			(width 0)
			(type default)
		)
	)
	(wire
		(pts
			(xy 56.515 252.095) (xy 57.785 252.095)
		)
		(stroke
			(width 0)
			(type default)
		)
	)
	(wire
		(pts
			(xy 27.305 166.37) (xy 17.145 166.37)
		)
		(stroke
			(width 0)
			(type default)
		)
	)
	(wire
		(pts
			(xy 114.935 249.555) (xy 125.095 249.555)
		)
		(stroke
			(width 0)
			(type default)
		)
	)
	(wire
		(pts
			(xy 355.6 163.83) (xy 355.6 167.005)
		)
		(stroke
			(width 0)
			(type default)
		)
	)
	(wire
		(pts
			(xy 73.025 168.275) (xy 78.105 168.275)
		)
		(stroke
			(width 0)
			(type default)
		)
	)
	(wire
		(pts
			(xy 170.18 276.86) (xy 170.18 278.13)
		)
		(stroke
			(width 0)
			(type default)
		)
	)
	(wire
		(pts
			(xy 366.395 59.055) (xy 366.395 57.785)
		)
		(stroke
			(width 0)
			(type default)
		)
	)
	(wire
		(pts
			(xy 234.95 125.73) (xy 236.22 125.73)
		)
		(stroke
			(width 0)
			(type default)
		)
	)
	(wire
		(pts
			(xy 236.22 157.48) (xy 236.22 174.625)
		)
		(stroke
			(width 0)
			(type default)
		)
	)
	(wire
		(pts
			(xy 114.935 116.84) (xy 114.935 118.11)
		)
		(stroke
			(width 0)
			(type default)
		)
	)
	(polyline
		(pts
			(xy 203.835 233.68) (xy 230.505 233.68)
		)
		(stroke
			(width 0)
			(type default)
		)
	)
	(wire
		(pts
			(xy 276.86 158.115) (xy 284.48 158.115)
		)
		(stroke
			(width 0)
			(type default)
		)
	)
	(wire
		(pts
			(xy 356.87 218.44) (xy 356.87 221.615)
		)
		(stroke
			(width 0)
			(type default)
		)
	)
	(wire
		(pts
			(xy 30.48 24.765) (xy 30.48 27.305)
		)
		(stroke
			(width 0)
			(type default)
		)
	)
	(wire
		(pts
			(xy 41.91 95.25) (xy 50.165 95.25)
		)
		(stroke
			(width 0)
			(type default)
		)
	)
	(polyline
		(pts
			(xy 203.835 227.965) (xy 203.835 233.68)
		)
		(stroke
			(width 0)
			(type default)
		)
	)
	(wire
		(pts
			(xy 364.49 116.205) (xy 366.395 116.205)
		)
		(stroke
			(width 0)
			(type default)
		)
	)
	(wire
		(pts
			(xy 157.48 252.73) (xy 157.48 245.745)
		)
		(stroke
			(width 0)
			(type default)
		)
	)
	(wire
		(pts
			(xy 215.9 184.785) (xy 215.9 187.325)
		)
		(stroke
			(width 0)
			(type default)
		)
	)
	(wire
		(pts
			(xy 341.63 41.91) (xy 341.63 50.165)
		)
		(stroke
			(width 0)
			(type default)
		)
	)
	(wire
		(pts
			(xy 304.8 201.93) (xy 304.8 202.565)
		)
		(stroke
			(width 0)
			(type default)
		)
	)
	(wire
		(pts
			(xy 231.14 48.26) (xy 243.84 48.26)
		)
		(stroke
			(width 0)
			(type default)
		)
	)
	(wire
		(pts
			(xy 374.015 243.205) (xy 374.015 244.475)
		)
		(stroke
			(width 0)
			(type default)
		)
	)
	(wire
		(pts
			(xy 85.725 32.385) (xy 92.71 32.385)
		)
		(stroke
			(width 0)
			(type default)
		)
	)
	(wire
		(pts
			(xy 50.165 95.25) (xy 50.165 106.68)
		)
		(stroke
			(width 0)
			(type default)
		)
	)
	(polyline
		(pts
			(xy 365.76 175.895) (xy 365.76 184.15)
		)
		(stroke
			(width 0)
			(type default)
		)
	)
	(wire
		(pts
			(xy 67.945 158.115) (xy 78.105 158.115)
		)
		(stroke
			(width 0)
			(type default)
		)
	)
	(wire
		(pts
			(xy 180.975 194.31) (xy 190.5 194.31)
		)
		(stroke
			(width 0)
			(type default)
		)
	)
	(wire
		(pts
			(xy 313.055 180.34) (xy 313.055 179.705)
		)
		(stroke
			(width 0)
			(type default)
		)
	)
	(wire
		(pts
			(xy 364.49 123.825) (xy 364.49 125.73)
		)
		(stroke
			(width 0)
			(type default)
		)
	)
	(wire
		(pts
			(xy 85.725 67.945) (xy 88.265 67.945)
		)
		(stroke
			(width 0)
			(type default)
		)
	)
	(wire
		(pts
			(xy 123.825 127) (xy 135.255 127)
		)
		(stroke
			(width 0)
			(type default)
		)
	)
	(wire
		(pts
			(xy 95.885 65.405) (xy 95.885 67.945)
		)
		(stroke
			(width 0)
			(type default)
		)
	)
	(wire
		(pts
			(xy 81.915 207.645) (xy 86.995 207.645)
		)
		(stroke
			(width 0)
			(type default)
		)
	)
	(wire
		(pts
			(xy 95.885 22.225) (xy 95.885 32.385)
		)
		(stroke
			(width 0)
			(type default)
		)
	)
	(wire
		(pts
			(xy 125.095 252.73) (xy 125.095 249.555)
		)
		(stroke
			(width 0)
			(type default)
		)
	)
	(wire
		(pts
			(xy 313.055 163.195) (xy 324.485 163.195)
		)
		(stroke
			(width 0)
			(type default)
		)
	)
	(wire
		(pts
			(xy 379.095 47.625) (xy 405.13 47.625)
		)
		(stroke
			(width 0)
			(type default)
		)
	)
	(wire
		(pts
			(xy 110.49 202.565) (xy 99.06 202.565)
		)
		(stroke
			(width 0)
			(type default)
		)
	)
	(wire
		(pts
			(xy 118.745 202.565) (xy 130.175 202.565)
		)
		(stroke
			(width 0)
			(type default)
		)
	)
	(wire
		(pts
			(xy 229.87 281.94) (xy 215.9 281.94)
		)
		(stroke
			(width 0)
			(type default)
		)
	)
	(wire
		(pts
			(xy 43.815 22.225) (xy 50.165 22.225)
		)
		(stroke
			(width 0)
			(type default)
		)
	)
	(wire
		(pts
			(xy 304.8 116.205) (xy 306.07 116.205)
		)
		(stroke
			(width 0)
			(type default)
		)
	)
	(bus
		(pts
			(xy 175.895 111.76) (xy 175.895 113.03)
		)
		(stroke
			(width 0)
			(type default)
		)
	)
	(wire
		(pts
			(xy 248.285 250.825) (xy 248.285 260.985)
		)
		(stroke
			(width 0)
			(type default)
		)
	)
	(wire
		(pts
			(xy 220.345 118.11) (xy 222.25 118.11)
		)
		(stroke
			(width 0)
			(type default)
		)
	)
	(wire
		(pts
			(xy 86.995 224.155) (xy 86.995 226.06)
		)
		(stroke
			(width 0)
			(type default)
		)
	)
	(wire
		(pts
			(xy 160.02 204.47) (xy 160.02 207.01)
		)
		(stroke
			(width 0)
			(type default)
		)
	)
	(wire
		(pts
			(xy 27.305 164.465) (xy 27.305 166.37)
		)
		(stroke
			(width 0)
			(type default)
		)
	)
	(wire
		(pts
			(xy 292.735 57.15) (xy 294.005 57.15)
		)
		(stroke
			(width 0)
			(type default)
		)
	)
	(wire
		(pts
			(xy 224.79 196.215) (xy 237.49 196.215)
		)
		(stroke
			(width 0)
			(type default)
		)
	)
	(wire
		(pts
			(xy 50.165 22.225) (xy 50.165 25.4)
		)
		(stroke
			(width 0)
			(type default)
		)
	)
	(wire
		(pts
			(xy 298.45 100.965) (xy 298.45 98.425)
		)
		(stroke
			(width 0)
			(type default)
		)
	)
	(wire
		(pts
			(xy 160.02 176.53) (xy 160.02 179.07)
		)
		(stroke
			(width 0)
			(type default)
		)
	)
	(wire
		(pts
			(xy 278.765 256.54) (xy 278.765 255.27)
		)
		(stroke
			(width 0)
			(type default)
		)
	)
	(wire
		(pts
			(xy 256.54 51.435) (xy 256.54 53.34)
		)
		(stroke
			(width 0)
			(type default)
		)
	)
	(wire
		(pts
			(xy 66.675 70.485) (xy 67.945 70.485)
		)
		(stroke
			(width 0)
			(type default)
		)
	)
	(wire
		(pts
			(xy 66.675 34.925) (xy 66.675 37.465)
		)
		(stroke
			(width 0)
			(type default)
		)
	)
	(polyline
		(pts
			(xy 142.24 177.8) (xy 170.18 177.8)
		)
		(stroke
			(width 0)
			(type default)
		)
	)
	(wire
		(pts
			(xy 86.995 216.535) (xy 86.995 219.075)
		)
		(stroke
			(width 0)
			(type default)
		)
	)
	(wire
		(pts
			(xy 85.725 135.89) (xy 85.725 137.16)
		)
		(stroke
			(width 0)
			(type default)
		)
	)
	(wire
		(pts
			(xy 405.13 121.285) (xy 391.795 121.285)
		)
		(stroke
			(width 0)
			(type default)
		)
	)
	(wire
		(pts
			(xy 288.29 259.08) (xy 294.64 259.08)
		)
		(stroke
			(width 0)
			(type default)
		)
	)
	(wire
		(pts
			(xy 212.725 45.72) (xy 213.36 45.72)
		)
		(stroke
			(width 0)
			(type default)
		)
	)
	(wire
		(pts
			(xy 236.22 113.03) (xy 236.22 110.49)
		)
		(stroke
			(width 0)
			(type default)
		)
	)
	(wire
		(pts
			(xy 234.95 115.57) (xy 250.19 115.57)
		)
		(stroke
			(width 0)
			(type default)
		)
	)
	(wire
		(pts
			(xy 123.825 158.115) (xy 130.81 158.115)
		)
		(stroke
			(width 0)
			(type default)
		)
	)
	(wire
		(pts
			(xy 278.765 256.54) (xy 283.21 256.54)
		)
		(stroke
			(width 0)
			(type default)
		)
	)
	(wire
		(pts
			(xy 154.94 176.53) (xy 160.02 176.53)
		)
		(stroke
			(width 0)
			(type default)
		)
	)
	(wire
		(pts
			(xy 365.125 100.965) (xy 366.395 100.965)
		)
		(stroke
			(width 0)
			(type default)
		)
	)
	(wire
		(pts
			(xy 276.86 165.735) (xy 276.86 168.275)
		)
		(stroke
			(width 0)
			(type default)
		)
	)
	(wire
		(pts
			(xy 391.795 108.585) (xy 405.13 108.585)
		)
		(stroke
			(width 0)
			(type default)
		)
	)
	(wire
		(pts
			(xy 66.675 200.025) (xy 70.485 200.025)
		)
		(stroke
			(width 0)
			(type default)
		)
	)
	(wire
		(pts
			(xy 29.21 95.25) (xy 17.145 95.25)
		)
		(stroke
			(width 0)
			(type default)
		)
	)
	(wire
		(pts
			(xy 114.935 106.68) (xy 114.935 109.22)
		)
		(stroke
			(width 0)
			(type default)
		)
	)
	(wire
		(pts
			(xy 116.84 197.485) (xy 118.745 197.485)
		)
		(stroke
			(width 0)
			(type default)
		)
	)
	(wire
		(pts
			(xy 22.86 247.015) (xy 22.86 249.555)
		)
		(stroke
			(width 0)
			(type default)
		)
	)
	(wire
		(pts
			(xy 278.13 274.32) (xy 290.83 274.32)
		)
		(stroke
			(width 0)
			(type default)
		)
	)
	(wire
		(pts
			(xy 269.24 31.75) (xy 269.24 34.925)
		)
		(stroke
			(width 0)
			(type default)
		)
	)
	(wire
		(pts
			(xy 66.675 75.565) (xy 66.675 76.835)
		)
		(stroke
			(width 0)
			(type default)
		)
	)
	(wire
		(pts
			(xy 304.8 158.75) (xy 304.8 158.115)
		)
		(stroke
			(width 0)
			(type default)
		)
	)
	(wire
		(pts
			(xy 109.22 247.65) (xy 109.22 249.555)
		)
		(stroke
			(width 0)
			(type default)
		)
	)
	(wire
		(pts
			(xy 265.43 174.625) (xy 266.7 174.625)
		)
		(stroke
			(width 0)
			(type default)
		)
	)
	(wire
		(pts
			(xy 76.835 106.68) (xy 80.645 106.68)
		)
		(stroke
			(width 0)
			(type default)
		)
	)
	(wire
		(pts
			(xy 145.415 165.735) (xy 160.02 165.735)
		)
		(stroke
			(width 0)
			(type default)
		)
	)
	(wire
		(pts
			(xy 311.15 197.485) (xy 313.055 197.485)
		)
		(stroke
			(width 0)
			(type default)
		)
	)
	(wire
		(pts
			(xy 92.71 32.385) (xy 92.71 34.925)
		)
		(stroke
			(width 0)
			(type default)
		)
	)
	(polyline
		(pts
			(xy 225.425 220.345) (xy 225.425 233.68)
		)
		(stroke
			(width 0)
			(type default)
		)
	)
	(wire
		(pts
			(xy 180.34 245.745) (xy 180.34 247.65)
		)
		(stroke
			(width 0)
			(type default)
		)
	)
	(polyline
		(pts
			(xy 12.065 82.55) (xy 407.67 82.55)
		)
		(stroke
			(width 0)
			(type default)
		)
	)
	(wire
		(pts
			(xy 311.15 158.115) (xy 313.055 158.115)
		)
		(stroke
			(width 0)
			(type default)
		)
	)
	(polyline
		(pts
			(xy 203.835 227.965) (xy 230.505 227.965)
		)
		(stroke
			(width 0)
			(type default)
		)
	)
	(wire
		(pts
			(xy 78.105 216.535) (xy 86.995 216.535)
		)
		(stroke
			(width 0)
			(type default)
		)
	)
	(wire
		(pts
			(xy 386.715 218.44) (xy 386.715 220.98)
		)
		(stroke
			(width 0)
			(type default)
		)
	)
	(wire
		(pts
			(xy 154.94 252.73) (xy 157.48 252.73)
		)
		(stroke
			(width 0)
			(type default)
		)
	)
	(wire
		(pts
			(xy 86.995 197.485) (xy 110.49 197.485)
		)
		(stroke
			(width 0)
			(type default)
		)
	)
	(wire
		(pts
			(xy 265.43 207.645) (xy 279.4 207.645)
		)
		(stroke
			(width 0)
			(type default)
		)
	)
	(wire
		(pts
			(xy 284.48 42.545) (xy 284.48 54.61)
		)
		(stroke
			(width 0)
			(type default)
		)
	)
	(polyline
		(pts
			(xy 12.065 142.875) (xy 407.67 142.875)
		)
		(stroke
			(width 0)
			(type default)
		)
	)
	(wire
		(pts
			(xy 66.675 42.545) (xy 66.675 43.815)
		)
		(stroke
			(width 0)
			(type default)
		)
	)
	(wire
		(pts
			(xy 37.465 174.625) (xy 38.735 174.625)
		)
		(stroke
			(width 0)
			(type default)
		)
	)
	(wire
		(pts
			(xy 41.91 102.87) (xy 41.91 105.41)
		)
		(stroke
			(width 0)
			(type default)
		)
	)
	(wire
		(pts
			(xy 22.86 260.35) (xy 28.575 260.35)
		)
		(stroke
			(width 0)
			(type default)
		)
	)
	(wire
		(pts
			(xy 317.5 212.09) (xy 317.5 212.725)
		)
		(stroke
			(width 0)
			(type default)
		)
	)
	(wire
		(pts
			(xy 17.145 157.48) (xy 27.305 157.48)
		)
		(stroke
			(width 0)
			(type default)
		)
	)
	(wire
		(pts
			(xy 313.055 162.56) (xy 313.055 163.195)
		)
		(stroke
			(width 0)
			(type default)
		)
	)
	(wire
		(pts
			(xy 311.785 212.725) (xy 313.69 212.725)
		)
		(stroke
			(width 0)
			(type default)
		)
	)
	(wire
		(pts
			(xy 114.935 114.3) (xy 114.935 116.84)
		)
		(stroke
			(width 0)
			(type default)
		)
	)
	(wire
		(pts
			(xy 249.555 250.825) (xy 248.285 250.825)
		)
		(stroke
			(width 0)
			(type default)
		)
	)
	(wire
		(pts
			(xy 116.84 158.115) (xy 118.745 158.115)
		)
		(stroke
			(width 0)
			(type default)
		)
	)
	(wire
		(pts
			(xy 85.725 246.38) (xy 85.725 247.015)
		)
		(stroke
			(width 0)
			(type default)
		)
	)
	(wire
		(pts
			(xy 375.92 200.66) (xy 386.715 200.66)
		)
		(stroke
			(width 0)
			(type default)
		)
	)
	(wire
		(pts
			(xy 218.44 33.02) (xy 218.44 34.29)
		)
		(stroke
			(width 0)
			(type default)
		)
	)
	(wire
		(pts
			(xy 110.49 179.705) (xy 111.76 179.705)
		)
		(stroke
			(width 0)
			(type default)
		)
	)
	(polyline
		(pts
			(xy 42.545 233.68) (xy 42.545 228.6)
		)
		(stroke
			(width 0)
			(type default)
		)
	)
	(polyline
		(pts
			(xy 101.6 269.24) (xy 299.72 269.24)
		)
		(stroke
			(width 0)
			(type default)
		)
	)
	(wire
		(pts
			(xy 33.655 22.225) (xy 33.655 24.765)
		)
		(stroke
			(width 0)
			(type default)
		)
	)
	(wire
		(pts
			(xy 135.89 41.91) (xy 134.62 41.91)
		)
		(stroke
			(width 0)
			(type default)
		)
	)
	(wire
		(pts
			(xy 61.595 257.175) (xy 61.595 258.445)
		)
		(stroke
			(width 0)
			(type default)
		)
	)
	(wire
		(pts
			(xy 132.715 106.68) (xy 138.43 106.68)
		)
		(stroke
			(width 0)
			(type default)
		)
	)
	(wire
		(pts
			(xy 282.575 106.045) (xy 306.07 106.045)
		)
		(stroke
			(width 0)
			(type default)
		)
	)
	(wire
		(pts
			(xy 298.45 97.155) (xy 298.45 98.425)
		)
		(stroke
			(width 0)
			(type default)
		)
	)
	(wire
		(pts
			(xy 160.02 212.09) (xy 160.02 214.63)
		)
		(stroke
			(width 0)
			(type default)
		)
	)
	(wire
		(pts
			(xy 111.125 39.37) (xy 111.125 45.085)
		)
		(stroke
			(width 0)
			(type default)
		)
	)
	(polyline
		(pts
			(xy 13.335 223.52) (xy 42.545 223.52)
		)
		(stroke
			(width 0)
			(type default)
		)
	)
	(wire
		(pts
			(xy 304.8 202.565) (xy 293.37 202.565)
		)
		(stroke
			(width 0)
			(type default)
		)
	)
	(wire
		(pts
			(xy 92.71 40.005) (xy 92.71 43.815)
		)
		(stroke
			(width 0)
			(type default)
		)
	)
	(wire
		(pts
			(xy 285.75 226.06) (xy 285.75 229.87)
		)
		(stroke
			(width 0)
			(type default)
		)
	)
	(wire
		(pts
			(xy 304.8 123.825) (xy 304.8 126.365)
		)
		(stroke
			(width 0)
			(type default)
		)
	)
	(wire
		(pts
			(xy 364.49 118.745) (xy 366.395 118.745)
		)
		(stroke
			(width 0)
			(type default)
		)
	)
	(wire
		(pts
			(xy 106.045 114.3) (xy 106.045 116.84)
		)
		(stroke
			(width 0)
			(type default)
		)
	)
	(wire
		(pts
			(xy 376.555 47.625) (xy 379.095 47.625)
		)
		(stroke
			(width 0)
			(type default)
		)
	)
	(wire
		(pts
			(xy 78.105 168.275) (xy 86.995 168.275)
		)
		(stroke
			(width 0)
			(type default)
		)
	)
	(wire
		(pts
			(xy 86.995 197.485) (xy 86.995 200.025)
		)
		(stroke
			(width 0)
			(type default)
		)
	)
	(wire
		(pts
			(xy 114.935 249.555) (xy 114.935 251.46)
		)
		(stroke
			(width 0)
			(type default)
		)
	)
	(wire
		(pts
			(xy 95.885 55.245) (xy 98.425 55.245)
		)
		(stroke
			(width 0)
			(type default)
		)
	)
	(wire
		(pts
			(xy 290.195 212.725) (xy 305.435 212.725)
		)
		(stroke
			(width 0)
			(type default)
		)
	)
	(wire
		(pts
			(xy 215.9 157.48) (xy 226.06 157.48)
		)
		(stroke
			(width 0)
			(type default)
		)
	)
	(wire
		(pts
			(xy 346.075 123.825) (xy 331.47 123.825)
		)
		(stroke
			(width 0)
			(type default)
		)
	)
	(wire
		(pts
			(xy 376.555 50.165) (xy 388.62 50.165)
		)
		(stroke
			(width 0)
			(type default)
		)
	)
	(wire
		(pts
			(xy 190.5 278.13) (xy 200.66 278.13)
		)
		(stroke
			(width 0)
			(type default)
		)
	)
	(wire
		(pts
			(xy 170.815 262.255) (xy 170.815 263.525)
		)
		(stroke
			(width 0)
			(type default)
		)
	)
	(wire
		(pts
			(xy 73.025 182.245) (xy 73.025 168.275)
		)
		(stroke
			(width 0)
			(type default)
		)
	)
	(wire
		(pts
			(xy 27.305 157.48) (xy 27.305 159.385)
		)
		(stroke
			(width 0)
			(type default)
		)
	)
	(wire
		(pts
			(xy 351.155 32.385) (xy 366.395 32.385)
		)
		(stroke
			(width 0)
			(type default)
		)
	)
	(wire
		(pts
			(xy 364.49 113.665) (xy 366.395 113.665)
		)
		(stroke
			(width 0)
			(type default)
		)
	)
	(wire
		(pts
			(xy 285.75 168.275) (xy 285.75 169.545)
		)
		(stroke
			(width 0)
			(type default)
		)
	)
	(wire
		(pts
			(xy 66.675 67.945) (xy 66.675 70.485)
		)
		(stroke
			(width 0)
			(type default)
		)
	)
	(wire
		(pts
			(xy 378.46 163.83) (xy 386.715 163.83)
		)
		(stroke
			(width 0)
			(type default)
		)
	)
	(wire
		(pts
			(xy 33.655 29.845) (xy 33.655 32.385)
		)
		(stroke
			(width 0)
			(type default)
		)
	)
	(wire
		(pts
			(xy 318.77 41.91) (xy 318.77 45.72)
		)
		(stroke
			(width 0)
			(type default)
		)
	)
	(wire
		(pts
			(xy 108.585 127) (xy 123.825 127)
		)
		(stroke
			(width 0)
			(type default)
		)
	)
	(wire
		(pts
			(xy 189.865 173.99) (xy 189.865 176.53)
		)
		(stroke
			(width 0)
			(type default)
		)
	)
	(wire
		(pts
			(xy 131.445 158.115) (xy 130.81 158.115)
		)
		(stroke
			(width 0)
			(type default)
		)
	)
	(wire
		(pts
			(xy 278.765 256.54) (xy 278.765 259.08)
		)
		(stroke
			(width 0)
			(type default)
		)
	)
	(wire
		(pts
			(xy 306.07 113.665) (xy 304.8 113.665)
		)
		(stroke
			(width 0)
			(type default)
		)
	)
	(wire
		(pts
			(xy 154.94 257.81) (xy 155.575 257.81)
		)
		(stroke
			(width 0)
			(type default)
		)
	)
	(wire
		(pts
			(xy 305.435 217.805) (xy 294.005 217.805)
		)
		(stroke
			(width 0)
			(type default)
		)
	)
	(wire
		(pts
			(xy 66.675 32.385) (xy 58.42 32.385)
		)
		(stroke
			(width 0)
			(type default)
		)
	)
	(wire
		(pts
			(xy 78.105 165.735) (xy 78.105 168.275)
		)
		(stroke
			(width 0)
			(type default)
		)
	)
	(wire
		(pts
			(xy 326.39 178.435) (xy 326.39 179.705)
		)
		(stroke
			(width 0)
			(type default)
		)
	)
	(wire
		(pts
			(xy 300.355 118.745) (xy 306.07 118.745)
		)
		(stroke
			(width 0)
			(type default)
		)
	)
	(wire
		(pts
			(xy 386.715 163.83) (xy 386.715 167.005)
		)
		(stroke
			(width 0)
			(type default)
		)
	)
	(wire
		(pts
			(xy 146.685 39.37) (xy 146.685 43.815)
		)
		(stroke
			(width 0)
			(type default)
		)
	)
	(wire
		(pts
			(xy 356.87 200.66) (xy 356.87 203.2)
		)
		(stroke
			(width 0)
			(type default)
		)
	)
	(wire
		(pts
			(xy 123.825 124.46) (xy 123.825 127)
		)
		(stroke
			(width 0)
			(type default)
		)
	)
	(wire
		(pts
			(xy 110.49 217.17) (xy 110.49 216.535)
		)
		(stroke
			(width 0)
			(type default)
		)
	)
	(wire
		(pts
			(xy 74.295 114.3) (xy 85.725 114.3)
		)
		(stroke
			(width 0)
			(type default)
		)
	)
	(wire
		(pts
			(xy 388.62 32.385) (xy 398.78 32.385)
		)
		(stroke
			(width 0)
			(type default)
		)
	)
	(wire
		(pts
			(xy 318.77 41.91) (xy 341.63 41.91)
		)
		(stroke
			(width 0)
			(type default)
		)
	)
	(wire
		(pts
			(xy 50.165 30.48) (xy 50.165 34.925)
		)
		(stroke
			(width 0)
			(type default)
		)
	)
	(wire
		(pts
			(xy 286.893 32.385) (xy 290.703 32.385)
		)
		(stroke
			(width 0)
			(type default)
		)
	)
	(wire
		(pts
			(xy 123.825 157.48) (xy 123.825 158.115)
		)
		(stroke
			(width 0)
			(type default)
		)
	)
	(wire
		(pts
			(xy 106.045 106.68) (xy 114.935 106.68)
		)
		(stroke
			(width 0)
			(type default)
		)
	)
	(wire
		(pts
			(xy 215.9 164.465) (xy 215.9 166.37)
		)
		(stroke
			(width 0)
			(type default)
		)
	)
	(wire
		(pts
			(xy 118.745 198.12) (xy 118.745 197.485)
		)
		(stroke
			(width 0)
			(type default)
		)
	)
	(wire
		(pts
			(xy 226.06 157.48) (xy 226.06 159.385)
		)
		(stroke
			(width 0)
			(type default)
		)
	)
	(wire
		(pts
			(xy 248.285 260.985) (xy 248.285 262.255)
		)
		(stroke
			(width 0)
			(type default)
		)
	)
	(polyline
		(pts
			(xy 37.465 220.98) (xy 37.465 233.68)
		)
		(stroke
			(width 0)
			(type default)
		)
	)
	(wire
		(pts
			(xy 233.045 205.105) (xy 237.49 205.105)
		)
		(stroke
			(width 0)
			(type default)
		)
	)
	(wire
		(pts
			(xy 220.345 118.11) (xy 220.345 120.65)
		)
		(stroke
			(width 0)
			(type default)
		)
	)
	(wire
		(pts
			(xy 190.5 201.93) (xy 190.5 204.47)
		)
		(stroke
			(width 0)
			(type default)
		)
	)
	(wire
		(pts
			(xy 88.265 67.945) (xy 88.265 62.865)
		)
		(stroke
			(width 0)
			(type default)
		)
	)
	(wire
		(pts
			(xy 118.745 158.115) (xy 123.825 158.115)
		)
		(stroke
			(width 0)
			(type default)
		)
	)
	(wire
		(pts
			(xy 146.685 36.195) (xy 146.685 39.37)
		)
		(stroke
			(width 0)
			(type default)
		)
	)
	(polyline
		(pts
			(xy 338.455 12.7) (xy 338.455 41.275)
		)
		(stroke
			(width 0)
			(type default)
		)
	)
	(wire
		(pts
			(xy 109.22 256.54) (xy 109.22 257.81)
		)
		(stroke
			(width 0)
			(type default)
		)
	)
	(wire
		(pts
			(xy 207.01 102.87) (xy 207.01 113.03)
		)
		(stroke
			(width 0)
			(type default)
		)
	)
	(wire
		(pts
			(xy 346.71 50.165) (xy 346.71 52.07)
		)
		(stroke
			(width 0)
			(type default)
		)
	)
	(wire
		(pts
			(xy 304.8 197.485) (xy 306.07 197.485)
		)
		(stroke
			(width 0)
			(type default)
		)
	)
	(wire
		(pts
			(xy 134.62 39.37) (xy 139.065 39.37)
		)
		(stroke
			(width 0)
			(type default)
		)
	)
	(wire
		(pts
			(xy 123.825 102.235) (xy 125.73 102.235)
		)
		(stroke
			(width 0)
			(type default)
		)
	)
	(polyline
		(pts
			(xy 368.935 212.09) (xy 368.935 220.345)
		)
		(stroke
			(width 0)
			(type default)
		)
	)
	(wire
		(pts
			(xy 110.49 198.12) (xy 110.49 197.485)
		)
		(stroke
			(width 0)
			(type default)
		)
	)
	(wire
		(pts
			(xy 66.675 70.485) (xy 66.675 75.565)
		)
		(stroke
			(width 0)
			(type default)
		)
	)
	(wire
		(pts
			(xy 64.135 135.89) (xy 65.405 135.89)
		)
		(stroke
			(width 0)
			(type default)
		)
	)
	(wire
		(pts
			(xy 110.49 162.56) (xy 110.49 163.195)
		)
		(stroke
			(width 0)
			(type default)
		)
	)
	(wire
		(pts
			(xy 78.105 207.645) (xy 78.105 216.535)
		)
		(stroke
			(width 0)
			(type default)
		)
	)
	(wire
		(pts
			(xy 85.09 158.115) (xy 86.995 158.115)
		)
		(stroke
			(width 0)
			(type default)
		)
	)
	(wire
		(pts
			(xy 386.715 174.625) (xy 386.715 177.165)
		)
		(stroke
			(width 0)
			(type default)
		)
	)
	(wire
		(pts
			(xy 157.48 245.745) (xy 180.34 245.745)
		)
		(stroke
			(width 0)
			(type default)
		)
	)
	(wire
		(pts
			(xy 300.355 116.84) (xy 300.355 118.745)
		)
		(stroke
			(width 0)
			(type default)
		)
	)
	(wire
		(pts
			(xy 86.995 165.735) (xy 86.995 168.275)
		)
		(stroke
			(width 0)
			(type default)
		)
	)
	(wire
		(pts
			(xy 356.87 208.28) (xy 356.87 210.82)
		)
		(stroke
			(width 0)
			(type default)
		)
	)
	(wire
		(pts
			(xy 66.675 207.645) (xy 78.105 207.645)
		)
		(stroke
			(width 0)
			(type default)
		)
	)
	(polyline
		(pts
			(xy 201.295 142.875) (xy 201.295 235.585)
		)
		(stroke
			(width 0)
			(type default)
		)
	)
	(wire
		(pts
			(xy 57.785 247.015) (xy 61.595 247.015)
		)
		(stroke
			(width 0)
			(type default)
		)
	)
	(wire
		(pts
			(xy 346.075 163.83) (xy 355.6 163.83)
		)
		(stroke
			(width 0)
			(type default)
		)
	)
	(wire
		(pts
			(xy 62.865 135.89) (xy 64.135 135.89)
		)
		(stroke
			(width 0)
			(type default)
		)
	)
	(wire
		(pts
			(xy 86.995 189.865) (xy 86.995 191.135)
		)
		(stroke
			(width 0)
			(type default)
		)
	)
	(wire
		(pts
			(xy 236.22 123.19) (xy 236.22 125.73)
		)
		(stroke
			(width 0)
			(type default)
		)
	)
	(wire
		(pts
			(xy 273.05 179.705) (xy 276.86 179.705)
		)
		(stroke
			(width 0)
			(type default)
		)
	)
	(wire
		(pts
			(xy 123.825 134.62) (xy 123.825 137.16)
		)
		(stroke
			(width 0)
			(type default)
		)
	)
	(wire
		(pts
			(xy 391.795 116.205) (xy 405.13 116.205)
		)
		(stroke
			(width 0)
			(type default)
		)
	)
	(wire
		(pts
			(xy 325.755 158.115) (xy 325.755 156.21)
		)
		(stroke
			(width 0)
			(type default)
		)
	)
	(wire
		(pts
			(xy 110.49 158.75) (xy 110.49 158.115)
		)
		(stroke
			(width 0)
			(type default)
		)
	)
	(wire
		(pts
			(xy 50.165 129.54) (xy 53.975 129.54)
		)
		(stroke
			(width 0)
			(type default)
		)
	)
	(polyline
		(pts
			(xy 230.505 220.345) (xy 210.185 220.345)
		)
		(stroke
			(width 0)
			(type default)
		)
	)
	(wire
		(pts
			(xy 30.48 27.305) (xy 30.48 32.385)
		)
		(stroke
			(width 0)
			(type default)
		)
	)
	(wire
		(pts
			(xy 41.275 252.095) (xy 28.575 252.095)
		)
		(stroke
			(width 0)
			(type default)
		)
	)
	(wire
		(pts
			(xy 265.43 182.245) (xy 271.78 182.245)
		)
		(stroke
			(width 0)
			(type default)
		)
	)
	(wire
		(pts
			(xy 66.675 202.565) (xy 81.915 202.565)
		)
		(stroke
			(width 0)
			(type default)
		)
	)
	(wire
		(pts
			(xy 160.02 201.93) (xy 160.02 204.47)
		)
		(stroke
			(width 0)
			(type default)
		)
	)
	(polyline
		(pts
			(xy 22.225 220.98) (xy 22.225 222.25)
		)
		(stroke
			(width 0)
			(type default)
		)
	)
	(wire
		(pts
			(xy 265.43 202.565) (xy 281.94 202.565)
		)
		(stroke
			(width 0)
			(type default)
		)
	)
	(wire
		(pts
			(xy 304.8 116.205) (xy 304.8 123.825)
		)
		(stroke
			(width 0)
			(type default)
		)
	)
	(wire
		(pts
			(xy 116.84 216.535) (xy 118.745 216.535)
		)
		(stroke
			(width 0)
			(type default)
		)
	)
	(wire
		(pts
			(xy 227.33 274.32) (xy 229.87 274.32)
		)
		(stroke
			(width 0)
			(type default)
		)
	)
	(wire
		(pts
			(xy 17.145 164.465) (xy 17.145 166.37)
		)
		(stroke
			(width 0)
			(type default)
		)
	)
	(wire
		(pts
			(xy 130.81 276.86) (xy 130.81 278.13)
		)
		(stroke
			(width 0)
			(type default)
		)
	)
	(wire
		(pts
			(xy 347.98 106.045) (xy 366.395 106.045)
		)
		(stroke
			(width 0)
			(type default)
		)
	)
	(polyline
		(pts
			(xy 299.085 235.585) (xy 407.67 235.585)
		)
		(stroke
			(width 0)
			(type default)
		)
	)
	(wire
		(pts
			(xy 193.675 57.785) (xy 196.215 57.785)
		)
		(stroke
			(width 0)
			(type default)
		)
	)
	(wire
		(pts
			(xy 337.82 243.205) (xy 337.82 244.475)
		)
		(stroke
			(width 0)
			(type default)
		)
	)
	(wire
		(pts
			(xy 212.725 25.4) (xy 212.725 26.035)
		)
		(stroke
			(width 0)
			(type default)
		)
	)
	(wire
		(pts
			(xy 98.425 22.225) (xy 98.425 20.32)
		)
		(stroke
			(width 0)
			(type default)
		)
	)
	(wire
		(pts
			(xy 17.145 102.87) (xy 17.145 105.41)
		)
		(stroke
			(width 0)
			(type default)
		)
	)
	(wire
		(pts
			(xy 224.79 193.675) (xy 237.49 193.675)
		)
		(stroke
			(width 0)
			(type default)
		)
	)
	(wire
		(pts
			(xy 190.5 212.09) (xy 190.5 215.265)
		)
		(stroke
			(width 0)
			(type default)
		)
	)
	(wire
		(pts
			(xy 78.105 158.115) (xy 78.105 160.655)
		)
		(stroke
			(width 0)
			(type default)
		)
	)
	(wire
		(pts
			(xy 135.89 252.73) (xy 125.095 252.73)
		)
		(stroke
			(width 0)
			(type default)
		)
	)
	(wire
		(pts
			(xy 66.675 65.405) (xy 67.945 65.405)
		)
		(stroke
			(width 0)
			(type default)
		)
	)
	(wire
		(pts
			(xy 28.575 252.095) (xy 28.575 254)
		)
		(stroke
			(width 0)
			(type default)
		)
	)
	(wire
		(pts
			(xy 118.745 180.34) (xy 118.745 179.705)
		)
		(stroke
			(width 0)
			(type default)
		)
	)
	(wire
		(pts
			(xy 284.48 158.115) (xy 285.75 158.115)
		)
		(stroke
			(width 0)
			(type default)
		)
	)
	(wire
		(pts
			(xy 364.49 123.825) (xy 366.395 123.825)
		)
		(stroke
			(width 0)
			(type default)
		)
	)
	(polyline
		(pts
			(xy 396.24 220.345) (xy 368.935 220.345)
		)
		(stroke
			(width 0)
			(type default)
		)
	)
	(wire
		(pts
			(xy 61.595 247.015) (xy 74.295 247.015)
		)
		(stroke
			(width 0)
			(type default)
		)
	)
	(wire
		(pts
			(xy 130.81 158.115) (xy 130.81 153.035)
		)
		(stroke
			(width 0)
			(type default)
		)
	)
	(wire
		(pts
			(xy 64.135 135.89) (xy 64.135 137.16)
		)
		(stroke
			(width 0)
			(type default)
		)
	)
	(wire
		(pts
			(xy 248.285 260.985) (xy 249.555 260.985)
		)
		(stroke
			(width 0)
			(type default)
		)
	)
	(polyline
		(pts
			(xy 142.24 205.74) (xy 142.24 213.995)
		)
		(stroke
			(width 0)
			(type default)
		)
	)
	(wire
		(pts
			(xy 58.42 42.545) (xy 66.675 42.545)
		)
		(stroke
			(width 0)
			(type default)
		)
	)
	(wire
		(pts
			(xy 123.825 106.68) (xy 123.825 115.57)
		)
		(stroke
			(width 0)
			(type default)
		)
	)
	(wire
		(pts
			(xy 215.9 166.37) (xy 215.9 167.005)
		)
		(stroke
			(width 0)
			(type default)
		)
	)
	(wire
		(pts
			(xy 75.565 187.325) (xy 75.565 179.705)
		)
		(stroke
			(width 0)
			(type default)
		)
	)
	(wire
		(pts
			(xy 298.45 98.425) (xy 306.07 98.425)
		)
		(stroke
			(width 0)
			(type default)
		)
	)
	(wire
		(pts
			(xy 204.47 102.87) (xy 204.47 110.49)
		)
		(stroke
			(width 0)
			(type default)
		)
	)
	(wire
		(pts
			(xy 233.68 184.785) (xy 237.49 184.785)
		)
		(stroke
			(width 0)
			(type default)
		)
	)
	(wire
		(pts
			(xy 317.5 212.725) (xy 325.755 212.725)
		)
		(stroke
			(width 0)
			(type default)
		)
	)
	(wire
		(pts
			(xy 109.22 249.555) (xy 109.22 251.46)
		)
		(stroke
			(width 0)
			(type default)
		)
	)
	(wire
		(pts
			(xy 29.21 205.105) (xy 38.735 205.105)
		)
		(stroke
			(width 0)
			(type default)
		)
	)
	(wire
		(pts
			(xy 398.78 43.815) (xy 398.78 52.705)
		)
		(stroke
			(width 0)
			(type default)
		)
	)
	(wire
		(pts
			(xy 305.435 212.725) (xy 306.705 212.725)
		)
		(stroke
			(width 0)
			(type default)
		)
	)
	(wire
		(pts
			(xy 276.86 158.115) (xy 276.86 160.655)
		)
		(stroke
			(width 0)
			(type default)
		)
	)
	(wire
		(pts
			(xy 74.295 121.92) (xy 92.71 121.92)
		)
		(stroke
			(width 0)
			(type default)
		)
	)
	(wire
		(pts
			(xy 180.34 276.86) (xy 180.34 278.13)
		)
		(stroke
			(width 0)
			(type default)
		)
	)
	(wire
		(pts
			(xy 266.7 158.115) (xy 276.86 158.115)
		)
		(stroke
			(width 0)
			(type default)
		)
	)
	(wire
		(pts
			(xy 148.59 276.86) (xy 148.59 278.13)
		)
		(stroke
			(width 0)
			(type default)
		)
	)
	(label "1V1_local"
		(at 240.03 281.94 0)
		(effects
			(font
				(size 1.27 1.27)
			)
			(justify left bottom)
		)
	)
	(label "~{PB_CTRL_IN}"
		(at 196.215 50.8 0)
		(effects
			(font
				(size 1.27 1.27)
			)
			(justify left bottom)
		)
	)
	(label "1V1_SEN_-"
		(at 405.13 116.205 180)
		(effects
			(font
				(size 1.27 1.27)
			)
			(justify right bottom)
		)
	)
	(label "1V2_local"
		(at 270.51 207.645 0)
		(effects
			(font
				(size 1.27 1.27)
			)
			(justify left bottom)
		)
	)
	(label "3V3_local"
		(at 346.075 163.83 0)
		(effects
			(font
				(size 1.27 1.27)
			)
			(justify left bottom)
		)
	)
	(label "MGTAVCC_SEN_-"
		(at 347.345 100.965 180)
		(effects
			(font
				(size 1.27 1.27)
			)
			(justify right bottom)
		)
	)
	(label "FB4"
		(at 185.42 204.47 0)
		(effects
			(font
				(size 1.27 1.27)
			)
			(justify left bottom)
		)
	)
	(label "SEQ_EN"
		(at 318.77 41.91 0)
		(effects
			(font
				(size 1.27 1.27)
			)
			(justify left bottom)
		)
	)
	(label "1V8_SEN_-"
		(at 344.805 108.585 180)
		(effects
			(font
				(size 1.27 1.27)
			)
			(justify right bottom)
		)
	)
	(label "sp_SEN_-"
		(at 344.805 116.205 180)
		(effects
			(font
				(size 1.27 1.27)
			)
			(justify right bottom)
		)
	)
	(label "FB1"
		(at 70.485 179.705 180)
		(effects
			(font
				(size 1.27 1.27)
			)
			(justify right bottom)
		)
	)
	(label "1V1_local"
		(at 378.46 163.83 0)
		(effects
			(font
				(size 1.27 1.27)
			)
			(justify left bottom)
		)
	)
	(label "PWR_SCL_2"
		(at 250.19 118.11 180)
		(effects
			(font
				(size 1.27 1.27)
			)
			(justify right bottom)
		)
	)
	(label "PWR_SDA_2"
		(at 250.19 115.57 180)
		(effects
			(font
				(size 1.27 1.27)
			)
			(justify right bottom)
		)
	)
	(label "MGTAVCC_local"
		(at 145.415 165.735 0)
		(effects
			(font
				(size 1.27 1.27)
			)
			(justify left bottom)
		)
	)
	(label "1V2_SEN_+"
		(at 405.13 121.285 180)
		(effects
			(font
				(size 1.27 1.27)
			)
			(justify right bottom)
		)
	)
	(label "~{PB_CTRL_CLR}"
		(at 249.555 107.95 180)
		(effects
			(font
				(size 1.27 1.27)
			)
			(justify right bottom)
		)
	)
	(label "PWR.SDA"
		(at 178.435 115.57 0)
		(effects
			(font
				(size 1.27 1.27)
			)
			(justify left bottom)
		)
	)
	(label "5V_SEN_-"
		(at 405.13 108.585 180)
		(effects
			(font
				(size 1.27 1.27)
			)
			(justify right bottom)
		)
	)
	(label "PWR_SDA_2"
		(at 347.98 106.045 0)
		(effects
			(font
				(size 1.27 1.27)
			)
			(justify left bottom)
		)
	)
	(label "PWR_SDA_2"
		(at 282.575 106.045 0)
		(effects
			(font
				(size 1.27 1.27)
			)
			(justify left bottom)
		)
	)
	(label "PWR.SCL"
		(at 178.435 118.11 0)
		(effects
			(font
				(size 1.27 1.27)
			)
			(justify left bottom)
		)
	)
	(label "12V_PCIE_fused"
		(at 60.325 55.245 0)
		(effects
			(font
				(size 1.27 1.27)
			)
			(justify left bottom)
		)
	)
	(label "1V0_REG"
		(at 106.68 106.68 0)
		(effects
			(font
				(size 1.27 1.27)
			)
			(justify left bottom)
		)
	)
	(label "MGTAVCC_local"
		(at 67.945 158.115 0)
		(effects
			(font
				(size 1.27 1.27)
			)
			(justify left bottom)
		)
	)
	(label "FB5"
		(at 269.24 179.705 180)
		(effects
			(font
				(size 1.27 1.27)
			)
			(justify right bottom)
		)
	)
	(label "3V3_local"
		(at 259.08 278.13 0)
		(effects
			(font
				(size 1.27 1.27)
			)
			(justify left bottom)
		)
	)
	(label "1V7"
		(at 190.5 281.94 0)
		(effects
			(font
				(size 1.27 1.27)
			)
			(justify left bottom)
		)
	)
	(label "5V_local"
		(at 273.05 179.705 0)
		(effects
			(font
				(size 1.27 1.27)
			)
			(justify left bottom)
		)
	)
	(label "~{PB_CTRL_INT}"
		(at 210.185 107.95 0)
		(effects
			(font
				(size 1.27 1.27)
			)
			(justify left bottom)
		)
	)
	(label "EN3"
		(at 233.68 184.785 0)
		(effects
			(font
				(size 1.27 1.27)
			)
			(justify left bottom)
		)
	)
	(label "FB8"
		(at 269.24 210.185 180)
		(effects
			(font
				(size 1.27 1.27)
			)
			(justify right bottom)
		)
	)
	(label "~{PB_CTRL_CLR}"
		(at 196.215 48.26 0)
		(effects
			(font
				(size 1.27 1.27)
			)
			(justify left bottom)
		)
	)
	(label "MGTAVCC_SEN_+"
		(at 347.345 98.425 180)
		(effects
			(font
				(size 1.27 1.27)
			)
			(justify right bottom)
		)
	)
	(label "FB3"
		(at 70.485 200.025 180)
		(effects
			(font
				(size 1.27 1.27)
			)
			(justify right bottom)
		)
	)
	(label "PG1"
		(at 48.895 120.65 0)
		(effects
			(font
				(size 1.27 1.27)
			)
			(justify left bottom)
		)
	)
	(label "sp_SEN_-"
		(at 130.175 202.565 180)
		(effects
			(font
				(size 1.27 1.27)
			)
			(justify right bottom)
		)
	)
	(label "1V2_SEN_-"
		(at 405.13 123.825 180)
		(effects
			(font
				(size 1.27 1.27)
			)
			(justify right bottom)
		)
	)
	(label "PWR.SDA"
		(at 35.56 124.46 0)
		(effects
			(font
				(size 1.27 1.27)
			)
			(justify left bottom)
		)
	)
	(label "spare_local"
		(at 180.34 165.735 0)
		(effects
			(font
				(size 1.27 1.27)
			)
			(justify left bottom)
		)
	)
	(label "MGTAVCC_local"
		(at 215.9 281.94 0)
		(effects
			(font
				(size 1.27 1.27)
			)
			(justify left bottom)
		)
	)
	(label "PWR_SDA_2"
		(at 190.5 278.13 0)
		(effects
			(font
				(size 1.27 1.27)
			)
			(justify left bottom)
		)
	)
	(label "1V7_SEN_+"
		(at 99.06 221.615 0)
		(effects
			(font
				(size 1.27 1.27)
			)
			(justify left bottom)
		)
	)
	(label "3V3_SEN_-"
		(at 405.13 100.965 180)
		(effects
			(font
				(size 1.27 1.27)
			)
			(justify right bottom)
		)
	)
	(label "1V1_SEN_+"
		(at 405.13 113.665 180)
		(effects
			(font
				(size 1.27 1.27)
			)
			(justify right bottom)
		)
	)
	(label "PWR_SDA_2"
		(at 122.555 257.81 0)
		(effects
			(font
				(size 1.27 1.27)
			)
			(justify left bottom)
		)
	)
	(label "PWR_SCL_2"
		(at 122.555 255.27 0)
		(effects
			(font
				(size 1.27 1.27)
			)
			(justify left bottom)
		)
	)
	(label "sp_SEN_+"
		(at 99.06 202.565 0)
		(effects
			(font
				(size 1.27 1.27)
			)
			(justify left bottom)
		)
	)
	(label "QDCDC1_VCC"
		(at 24.765 177.165 0)
		(effects
			(font
				(size 1.27 1.27)
			)
			(justify left bottom)
		)
	)
	(label "PG3"
		(at 233.045 205.105 0)
		(effects
			(font
				(size 1.27 1.27)
			)
			(justify left bottom)
		)
	)
	(label "FB6"
		(at 351.155 210.82 0)
		(effects
			(font
				(size 1.27 1.27)
			)
			(justify left bottom)
		)
	)
	(label "PB_CTRL_OUT"
		(at 209.55 26.67 270)
		(effects
			(font
				(size 1.27 1.27)
			)
			(justify right bottom)
		)
	)
	(label "1V0_REG"
		(at 85.725 114.3 180)
		(effects
			(font
				(size 1.27 1.27)
			)
			(justify right bottom)
		)
	)
	(label "PB_CTRL_OUT"
		(at 232.41 38.735 0)
		(effects
			(font
				(size 1.27 1.27)
			)
			(justify left bottom)
		)
	)
	(label "1V2_SEN_+"
		(at 294.005 217.805 0)
		(effects
			(font
				(size 1.27 1.27)
			)
			(justify left bottom)
		)
	)
	(label "MGTAVTT_OUT"
		(at 215.9 278.13 0)
		(effects
			(font
				(size 1.27 1.27)
			)
			(justify left bottom)
		)
	)
	(label "MGTAVCC_SEN_+"
		(at 94.615 163.195 0)
		(effects
			(font
				(size 1.27 1.27)
			)
			(justify left bottom)
		)
	)
	(label "FB2"
		(at 154.305 204.47 0)
		(effects
			(font
				(size 1.27 1.27)
			)
			(justify left bottom)
		)
	)
	(label "spare_local"
		(at 70.485 197.485 0)
		(effects
			(font
				(size 1.27 1.27)
			)
			(justify left bottom)
		)
	)
	(label "FB8"
		(at 381.635 210.82 0)
		(effects
			(font
				(size 1.27 1.27)
			)
			(justify left bottom)
		)
	)
	(label "1V1_SEN_+"
		(at 293.37 202.565 0)
		(effects
			(font
				(size 1.27 1.27)
			)
			(justify left bottom)
		)
	)
	(label "3V3_SEN_+"
		(at 294.005 163.195 0)
		(effects
			(font
				(size 1.27 1.27)
			)
			(justify left bottom)
		)
	)
	(label "MGTAVTT_OUT"
		(at 59.055 247.015 0)
		(effects
			(font
				(size 1.27 1.27)
			)
			(justify left bottom)
		)
	)
	(label "1V7_SEN_+"
		(at 346.075 121.285 180)
		(effects
			(font
				(size 1.27 1.27)
			)
			(justify right bottom)
		)
	)
	(label "FB1"
		(at 154.94 176.53 0)
		(effects
			(font
				(size 1.27 1.27)
			)
			(justify left bottom)
		)
	)
	(label "PWR.SCL"
		(at 29.21 196.215 0)
		(effects
			(font
				(size 1.27 1.27)
			)
			(justify left bottom)
		)
	)
	(label "1V0_FB"
		(at 77.47 121.92 0)
		(effects
			(font
				(size 1.27 1.27)
			)
			(justify left bottom)
		)
	)
	(label "EN1"
		(at 47.625 111.76 0)
		(effects
			(font
				(size 1.27 1.27)
			)
			(justify left bottom)
		)
	)
	(label "PWR_SCL_2"
		(at 347.98 108.585 0)
		(effects
			(font
				(size 1.27 1.27)
			)
			(justify left bottom)
		)
	)
	(label "1V7"
		(at 128.27 216.535 180)
		(effects
			(font
				(size 1.27 1.27)
			)
			(justify right bottom)
		)
	)
	(label "PB_CTRL_OUT"
		(at 210.185 105.41 0)
		(effects
			(font
				(size 1.27 1.27)
			)
			(justify left bottom)
		)
	)
	(label "~{PB_CTRL_INT}"
		(at 231.14 48.26 0)
		(effects
			(font
				(size 1.27 1.27)
			)
			(justify left bottom)
		)
	)
	(label "12V_aux_fused"
		(at 50.165 22.225 0)
		(effects
			(font
				(size 1.27 1.27)
			)
			(justify left bottom)
		)
	)
	(label "EN2"
		(at 34.925 184.785 0)
		(effects
			(font
				(size 1.27 1.27)
			)
			(justify left bottom)
		)
	)
	(label "5V_SEN_+"
		(at 405.13 106.045 180)
		(effects
			(font
				(size 1.27 1.27)
			)
			(justify right bottom)
		)
	)
	(label "MGTAVTT_ILIM"
		(at 28.575 252.095 0)
		(effects
			(font
				(size 1.27 1.27)
			)
			(justify left bottom)
		)
	)
	(label "1V8_SEN_+"
		(at 99.06 184.785 0)
		(effects
			(font
				(size 1.27 1.27)
			)
			(justify left bottom)
		)
	)
	(label "1V8_local"
		(at 278.13 274.32 0)
		(effects
			(font
				(size 1.27 1.27)
			)
			(justify left bottom)
		)
	)
	(label "1V7_SEN_-"
		(at 130.175 221.615 180)
		(effects
			(font
				(size 1.27 1.27)
			)
			(justify right bottom)
		)
	)
	(label "1V1_SEN_-"
		(at 324.485 202.565 180)
		(effects
			(font
				(size 1.27 1.27)
			)
			(justify right bottom)
		)
	)
	(label "FB6"
		(at 269.24 192.405 180)
		(effects
			(font
				(size 1.27 1.27)
			)
			(justify right bottom)
		)
	)
	(label "1V2_local"
		(at 375.92 200.66 0)
		(effects
			(font
				(size 1.27 1.27)
			)
			(justify left bottom)
		)
	)
	(label "QDCDC2_SCL"
		(at 250.19 120.65 180)
		(effects
			(font
				(size 1.27 1.27)
			)
			(justify right bottom)
		)
	)
	(label "QDCDC2_SCL"
		(at 278.13 276.86 0)
		(effects
			(font
				(size 1.27 1.27)
			)
			(justify left bottom)
		)
	)
	(label "PG2"
		(at 294.64 259.08 0)
		(effects
			(font
				(size 1.27 1.27)
			)
			(justify left bottom)
		)
	)
	(label "12V_aux"
		(at 29.845 22.225 0)
		(effects
			(font
				(size 1.27 1.27)
			)
			(justify left bottom)
		)
	)
	(label "1V8_SEN_+"
		(at 344.805 106.045 180)
		(effects
			(font
				(size 1.27 1.27)
			)
			(justify right bottom)
		)
	)
	(label "PG1"
		(at 294.64 256.54 0)
		(effects
			(font
				(size 1.27 1.27)
			)
			(justify left bottom)
		)
	)
	(label "QDCDC2_SCL"
		(at 224.79 196.215 0)
		(effects
			(font
				(size 1.27 1.27)
			)
			(justify left bottom)
		)
	)
	(label "1V7_local"
		(at 240.03 274.32 0)
		(effects
			(font
				(size 1.27 1.27)
			)
			(justify left bottom)
		)
	)
	(label "PWR.SDA"
		(at 224.79 193.675 0)
		(effects
			(font
				(size 1.27 1.27)
			)
			(justify left bottom)
		)
	)
	(label "FB4"
		(at 70.485 210.185 180)
		(effects
			(font
				(size 1.27 1.27)
			)
			(justify right bottom)
		)
	)
	(label "QDCDC2_VCC"
		(at 215.9 177.165 0)
		(effects
			(font
				(size 1.27 1.27)
			)
			(justify left bottom)
		)
	)
	(label "5V_local"
		(at 240.03 278.13 0)
		(effects
			(font
				(size 1.27 1.27)
			)
			(justify left bottom)
		)
	)
	(label "5V_SEN_-"
		(at 323.215 184.785 180)
		(effects
			(font
				(size 1.27 1.27)
			)
			(justify right bottom)
		)
	)
	(label "1V8_SEN_-"
		(at 130.175 184.785 180)
		(effects
			(font
				(size 1.27 1.27)
			)
			(justify right bottom)
		)
	)
	(label "1V7"
		(at 17.78 247.015 0)
		(effects
			(font
				(size 1.27 1.27)
			)
			(justify left bottom)
		)
	)
	(label "1V7_local"
		(at 69.215 207.645 0)
		(effects
			(font
				(size 1.27 1.27)
			)
			(justify left bottom)
		)
	)
	(label "SEQ_EN"
		(at 249.555 105.41 180)
		(effects
			(font
				(size 1.27 1.27)
			)
			(justify right bottom)
		)
	)
	(label "1V2_local"
		(at 259.08 274.32 0)
		(effects
			(font
				(size 1.27 1.27)
			)
			(justify left bottom)
		)
	)
	(label "1V0_REG"
		(at 259.08 281.94 0)
		(effects
			(font
				(size 1.27 1.27)
			)
			(justify left bottom)
		)
	)
	(label "MGTAVCC_SEN_-"
		(at 135.255 163.195 180)
		(effects
			(font
				(size 1.27 1.27)
			)
			(justify right bottom)
		)
	)
	(label "PG3"
		(at 294.64 261.62 0)
		(effects
			(font
				(size 1.27 1.27)
			)
			(justify left bottom)
		)
	)
	(label "1V7_SEN_-"
		(at 346.075 123.825 180)
		(effects
			(font
				(size 1.27 1.27)
			)
			(justify right bottom)
		)
	)
	(label "PWR.SDA"
		(at 29.21 193.675 0)
		(effects
			(font
				(size 1.27 1.27)
			)
			(justify left bottom)
		)
	)
	(label "1V2_SEN_-"
		(at 325.12 217.805 180)
		(effects
			(font
				(size 1.27 1.27)
			)
			(justify right bottom)
		)
	)
	(label "3V3_local"
		(at 266.7 158.115 0)
		(effects
			(font
				(size 1.27 1.27)
			)
			(justify left bottom)
		)
	)
	(label "1V0_VCC"
		(at 17.145 114.3 0)
		(effects
			(font
				(size 1.27 1.27)
			)
			(justify left bottom)
		)
	)
	(label "1V1_local"
		(at 270.51 197.485 0)
		(effects
			(font
				(size 1.27 1.27)
			)
			(justify left bottom)
		)
	)
	(label "PWR_SCL_2"
		(at 282.575 108.585 0)
		(effects
			(font
				(size 1.27 1.27)
			)
			(justify left bottom)
		)
	)
	(label "sp_SEN_+"
		(at 344.805 113.665 180)
		(effects
			(font
				(size 1.27 1.27)
			)
			(justify right bottom)
		)
	)
	(label "EN3"
		(at 405.13 52.705 180)
		(effects
			(font
				(size 1.27 1.27)
			)
			(justify right bottom)
		)
	)
	(label "PWR.SCL"
		(at 35.56 127 0)
		(effects
			(font
				(size 1.27 1.27)
			)
			(justify left bottom)
		)
	)
	(label "EN2"
		(at 405.13 50.165 180)
		(effects
			(font
				(size 1.27 1.27)
			)
			(justify right bottom)
		)
	)
	(label "1V0_SS"
		(at 77.47 129.54 0)
		(effects
			(font
				(size 1.27 1.27)
			)
			(justify left bottom)
		)
	)
	(label "5V_local"
		(at 345.44 200.66 0)
		(effects
			(font
				(size 1.27 1.27)
			)
			(justify left bottom)
		)
	)
	(label "EN1"
		(at 405.13 47.625 180)
		(effects
			(font
				(size 1.27 1.27)
			)
			(justify right bottom)
		)
	)
	(label "1V8_local"
		(at 75.565 179.705 0)
		(effects
			(font
				(size 1.27 1.27)
			)
			(justify left bottom)
		)
	)
	(label "1V0_SW"
		(at 76.835 93.98 270)
		(effects
			(font
				(size 1.27 1.27)
			)
			(justify right bottom)
		)
	)
	(label "spare"
		(at 118.745 197.485 0)
		(effects
			(font
				(size 1.27 1.27)
			)
			(justify left bottom)
		)
	)
	(label "FB5"
		(at 350.52 174.625 0)
		(effects
			(font
				(size 1.27 1.27)
			)
			(justify left bottom)
		)
	)
	(label "PWR_SCL_2"
		(at 190.5 274.32 0)
		(effects
			(font
				(size 1.27 1.27)
			)
			(justify left bottom)
		)
	)
	(label "FB7"
		(at 381.635 174.625 0)
		(effects
			(font
				(size 1.27 1.27)
			)
			(justify left bottom)
		)
	)
	(label "FB7"
		(at 269.24 200.025 180)
		(effects
			(font
				(size 1.27 1.27)
			)
			(justify right bottom)
		)
	)
	(label "1V0_BS"
		(at 64.135 93.98 270)
		(effects
			(font
				(size 1.27 1.27)
			)
			(justify right bottom)
		)
	)
	(label "FB3"
		(at 184.785 176.53 0)
		(effects
			(font
				(size 1.27 1.27)
			)
			(justify left bottom)
		)
	)
	(label "3V3_SEN_+"
		(at 405.13 98.425 180)
		(effects
			(font
				(size 1.27 1.27)
			)
			(justify right bottom)
		)
	)
	(label "3V3_SEN_-"
		(at 324.485 163.195 180)
		(effects
			(font
				(size 1.27 1.27)
			)
			(justify right bottom)
		)
	)
	(label "1V8_local"
		(at 150.495 194.31 0)
		(effects
			(font
				(size 1.27 1.27)
			)
			(justify left bottom)
		)
	)
	(label "5V_SEN_+"
		(at 294.64 184.785 0)
		(effects
			(font
				(size 1.27 1.27)
			)
			(justify left bottom)
		)
	)
	(label "PG2"
		(at 29.21 205.105 0)
		(effects
			(font
				(size 1.27 1.27)
			)
			(justify left bottom)
		)
	)
	(label "FB2"
		(at 70.485 192.405 180)
		(effects
			(font
				(size 1.27 1.27)
			)
			(justify right bottom)
		)
	)
	(label "1V7_local"
		(at 180.975 194.31 0)
		(effects
			(font
				(size 1.27 1.27)
			)
			(justify left bottom)
		)
	)
	(global_label "FAN_PWM"
		(shape input)
		(at 220.345 258.445 180)
		(fields_autoplaced yes)
		(effects
			(font
				(size 1.27 1.27)
			)
			(justify right)
		)
		(property "Intersheetrefs" "${INTERSHEET_REFS}"
			(at 209.3727 258.3656 0)
			(effects
				(font
					(size 1.27 1.27)
				)
				(justify right)
			)
		)
	)
	(global_label "FPGA_POWER_CYCLE"
		(shape input)
		(at 256.54 51.435 90)
		(fields_autoplaced yes)
		(effects
			(font
				(size 1.27 1.27)
			)
			(justify left)
		)
		(property "Intersheetrefs" "${INTERSHEET_REFS}"
			(at 256.6194 30.1818 90)
			(effects
				(font
					(size 1.27 1.27)
				)
				(justify left)
			)
		)
	)
	(global_label "DAC_VREF"
		(shape output)
		(at 182.245 245.745 0)
		(fields_autoplaced yes)
		(effects
			(font
				(size 1.27 1.27)
			)
			(justify left)
		)
		(property "Intersheetrefs" "${INTERSHEET_REFS}"
			(at 193.7616 245.6656 0)
			(effects
				(font
					(size 1.27 1.27)
				)
				(justify left)
			)
		)
	)
	(global_label "FPGA_POWER_OFF"
		(shape input)
		(at 171.45 62.23 90)
		(fields_autoplaced yes)
		(effects
			(font
				(size 1.27 1.27)
			)
			(justify left)
		)
		(property "Intersheetrefs" "${INTERSHEET_REFS}"
			(at 171.5294 43.2748 90)
			(effects
				(font
					(size 1.27 1.27)
				)
				(justify left)
			)
		)
	)
	(global_label "FTDI_DIS"
		(shape input)
		(at 220.98 123.19 180)
		(fields_autoplaced yes)
		(effects
			(font
				(size 1.27 1.27)
			)
			(justify right)
		)
		(property "Intersheetrefs" "${INTERSHEET_REFS}"
			(at 210.584 123.1106 0)
			(effects
				(font
					(size 1.27 1.27)
				)
				(justify right)
			)
		)
	)
	(global_label "DAC_VREF"
		(shape output)
		(at 227.33 274.32 180)
		(fields_autoplaced yes)
		(effects
			(font
				(size 1.27 1.27)
			)
			(justify right)
		)
		(property "Intersheetrefs" "${INTERSHEET_REFS}"
			(at 215.8066 274.32 0)
			(effects
				(font
					(size 1.27 1.27)
				)
				(justify right)
			)
		)
	)
	(global_label "POWER"
		(shape input)
		(at 276.86 261.62 180)
		(fields_autoplaced yes)
		(effects
			(font
				(size 1.27 1.27)
			)
			(justify right)
		)
		(property "Intersheetrefs" "${INTERSHEET_REFS}"
			(at 268.0648 261.5406 0)
			(effects
				(font
					(size 1.27 1.27)
				)
				(justify right)
			)
		)
	)
	(global_label "IN1"
		(shape input)
		(at 198.755 110.49 180)
		(fields_autoplaced yes)
		(effects
			(font
				(size 1.27 1.27)
			)
			(justify right)
		)
		(property "Intersheetrefs" "${INTERSHEET_REFS}"
			(at 193.286 110.5694 0)
			(effects
				(font
					(size 1.27 1.27)
				)
				(justify right)
			)
		)
	)
	(global_label "IN2"
		(shape input)
		(at 198.755 113.03 180)
		(fields_autoplaced yes)
		(effects
			(font
				(size 1.27 1.27)
			)
			(justify right)
		)
		(property "Intersheetrefs" "${INTERSHEET_REFS}"
			(at 193.286 112.9506 0)
			(effects
				(font
					(size 1.27 1.27)
				)
				(justify right)
			)
		)
	)
	(hierarchical_label "PWR{I^{2}C}"
		(shape bidirectional)
		(at 173.355 111.125 180)
		(effects
			(font
				(size 1.27 1.27)
			)
			(justify right)
		)
	)
	(symbol
		(lib_id "antmicroTestPoints:TP_1mm_SMD")
		(at 327.66 179.705 0)
		(unit 1)
		(exclude_from_sim no)
		(in_bom yes)
		(on_board yes)
		(dnp no)
		(fields_autoplaced yes)
		(property "Reference" "TP12"
			(at 332.232 180.1388 0)
			(effects
				(font
					(size 1.27 1.27)
				)
				(justify left)
			)
		)
		(property "Value" "TP_1mm_SMD"
			(at 342.9 187.325 0)
			(effects
				(font
					(size 1.27 1.27)
					(thickness 0.15)
				)
				(justify left bottom)
				(hide yes)
			)
		)
		(property "Footprint" "antmicro-footprints:TP_SMD_1mm"
			(at 342.9 189.865 0)
			(effects
				(font
					(size 1.27 1.27)
					(thickness 0.15)
				)
				(justify left bottom)
				(hide yes)
			)
		)
		(property "Datasheet" ""
			(at 342.9 192.405 0)
			(effects
				(font
					(size 1.27 1.27)
					(thickness 0.15)
				)
				(justify left bottom)
				(hide yes)
			)
		)
		(property "Description" ""
			(at 327.66 179.705 0)
			(effects
				(font
					(size 1.27 1.27)
				)
			)
		)
		(property "MPN" ""
			(at 327.66 179.705 0)
			(effects
				(font
					(size 1.27 1.27)
				)
				(hide yes)
			)
		)
		(property "Manufacturer" ""
			(at 327.66 179.705 0)
			(effects
				(font
					(size 1.27 1.27)
				)
				(hide yes)
			)
		)
		(property "Author" "Antmicro"
			(at 342.9 194.945 0)
			(effects
				(font
					(size 1.27 1.27)
					(thickness 0.15)
				)
				(justify left bottom)
				(hide yes)
			)
		)
		(property "License" "Apache-2.0"
			(at 342.9 197.485 0)
			(effects
				(font
					(size 1.27 1.27)
					(thickness 0.15)
				)
				(justify left bottom)
				(hide yes)
			)
		)
		(pin "1"
		)
		(instances
			(project "sodimm-ddr5-tester"
				(path ""
					(reference "TP12")
					(unit 1)
				)
			)
		)
	)
	(symbol
		(lib_id "antmicroTestPoints:TP_1mm_SMD")
		(at 327.025 197.485 0)
		(unit 1)
		(exclude_from_sim no)
		(in_bom yes)
		(on_board yes)
		(dnp no)
		(fields_autoplaced yes)
		(property "Reference" "TP13"
			(at 331.597 197.9188 0)
			(effects
				(font
					(size 1.27 1.27)
				)
				(justify left)
			)
		)
		(property "Value" "TP_1mm_SMD"
			(at 342.265 205.105 0)
			(effects
				(font
					(size 1.27 1.27)
					(thickness 0.15)
				)
				(justify left bottom)
				(hide yes)
			)
		)
		(property "Footprint" "antmicro-footprints:TP_SMD_1mm"
			(at 342.265 207.645 0)
			(effects
				(font
					(size 1.27 1.27)
					(thickness 0.15)
				)
				(justify left bottom)
				(hide yes)
			)
		)
		(property "Datasheet" ""
			(at 342.265 210.185 0)
			(effects
				(font
					(size 1.27 1.27)
					(thickness 0.15)
				)
				(justify left bottom)
				(hide yes)
			)
		)
		(property "Description" ""
			(at 327.025 197.485 0)
			(effects
				(font
					(size 1.27 1.27)
				)
			)
		)
		(property "MPN" ""
			(at 327.025 197.485 0)
			(effects
				(font
					(size 1.27 1.27)
				)
				(hide yes)
			)
		)
		(property "Manufacturer" ""
			(at 327.025 197.485 0)
			(effects
				(font
					(size 1.27 1.27)
				)
				(hide yes)
			)
		)
		(property "Author" "Antmicro"
			(at 342.265 212.725 0)
			(effects
				(font
					(size 1.27 1.27)
					(thickness 0.15)
				)
				(justify left bottom)
				(hide yes)
			)
		)
		(property "License" "Apache-2.0"
			(at 342.265 215.265 0)
			(effects
				(font
					(size 1.27 1.27)
					(thickness 0.15)
				)
				(justify left bottom)
				(hide yes)
			)
		)
		(pin "1"
		)
		(instances
			(project "sodimm-ddr5-tester"
				(path ""
					(reference "TP13")
					(unit 1)
				)
			)
		)
	)
	(symbol
		(lib_id "antmicroTestPoints:TP_1mm_SMD")
		(at 327.025 212.725 0)
		(unit 1)
		(exclude_from_sim no)
		(in_bom yes)
		(on_board yes)
		(dnp no)
		(fields_autoplaced yes)
		(property "Reference" "TP9"
			(at 331.597 213.1588 0)
			(effects
				(font
					(size 1.27 1.27)
				)
				(justify left)
			)
		)
		(property "Value" "TP_1mm_SMD"
			(at 342.265 220.345 0)
			(effects
				(font
					(size 1.27 1.27)
					(thickness 0.15)
				)
				(justify left bottom)
				(hide yes)
			)
		)
		(property "Footprint" "antmicro-footprints:TP_SMD_1mm"
			(at 342.265 222.885 0)
			(effects
				(font
					(size 1.27 1.27)
					(thickness 0.15)
				)
				(justify left bottom)
				(hide yes)
			)
		)
		(property "Datasheet" ""
			(at 342.265 225.425 0)
			(effects
				(font
					(size 1.27 1.27)
					(thickness 0.15)
				)
				(justify left bottom)
				(hide yes)
			)
		)
		(property "Description" ""
			(at 327.025 212.725 0)
			(effects
				(font
					(size 1.27 1.27)
				)
			)
		)
		(property "MPN" ""
			(at 327.025 212.725 0)
			(effects
				(font
					(size 1.27 1.27)
				)
				(hide yes)
			)
		)
		(property "Manufacturer" ""
			(at 327.025 212.725 0)
			(effects
				(font
					(size 1.27 1.27)
				)
				(hide yes)
			)
		)
		(property "Author" "Antmicro"
			(at 342.265 227.965 0)
			(effects
				(font
					(size 1.27 1.27)
					(thickness 0.15)
				)
				(justify left bottom)
				(hide yes)
			)
		)
		(property "License" "Apache-2.0"
			(at 342.265 230.505 0)
			(effects
				(font
					(size 1.27 1.27)
					(thickness 0.15)
				)
				(justify left bottom)
				(hide yes)
			)
		)
		(pin "1"
		)
		(instances
			(project "sodimm-ddr5-tester"
				(path ""
					(reference "TP9")
					(unit 1)
				)
			)
		)
	)
	(symbol
		(lib_id "antmicroTestPoints:TP_1mm_SMD")
		(at 98.425 20.32 90)
		(unit 1)
		(exclude_from_sim no)
		(in_bom yes)
		(on_board yes)
		(dnp no)
		(property "Reference" "TP16"
			(at 98.425 15.3472 90)
			(effects
				(font
					(size 1.27 1.27)
				)
			)
		)
		(property "Value" "TP_1mm_SMD"
			(at 106.045 5.08 0)
			(effects
				(font
					(size 1.27 1.27)
					(thickness 0.15)
				)
				(justify left bottom)
				(hide yes)
			)
		)
		(property "Footprint" "antmicro-footprints:TP_SMD_1mm"
			(at 108.585 5.08 0)
			(effects
				(font
					(size 1.27 1.27)
					(thickness 0.15)
				)
				(justify left bottom)
				(hide yes)
			)
		)
		(property "Datasheet" ""
			(at 111.125 5.08 0)
			(effects
				(font
					(size 1.27 1.27)
					(thickness 0.15)
				)
				(justify left bottom)
				(hide yes)
			)
		)
		(property "Description" ""
			(at 98.425 20.32 0)
			(effects
				(font
					(size 1.27 1.27)
				)
			)
		)
		(property "MPN" ""
			(at 98.425 20.32 0)
			(effects
				(font
					(size 1.27 1.27)
				)
				(hide yes)
			)
		)
		(property "Manufacturer" ""
			(at 98.425 20.32 0)
			(effects
				(font
					(size 1.27 1.27)
				)
				(hide yes)
			)
		)
		(property "Author" "Antmicro"
			(at 113.665 5.08 0)
			(effects
				(font
					(size 1.27 1.27)
					(thickness 0.15)
				)
				(justify left bottom)
				(hide yes)
			)
		)
		(property "License" "Apache-2.0"
			(at 116.205 5.08 0)
			(effects
				(font
					(size 1.27 1.27)
					(thickness 0.15)
				)
				(justify left bottom)
				(hide yes)
			)
		)
		(pin "1"
		)
		(instances
			(project "sodimm-ddr5-tester"
				(path ""
					(reference "TP16")
					(unit 1)
				)
			)
		)
	)
	(symbol
		(lib_id "antmicroTestPoints:TP_1mm_SMD")
		(at 327.66 158.115 0)
		(unit 1)
		(exclude_from_sim no)
		(in_bom yes)
		(on_board yes)
		(dnp no)
		(fields_autoplaced yes)
		(property "Reference" "TP11"
			(at 332.232 158.5488 0)
			(effects
				(font
					(size 1.27 1.27)
				)
				(justify left)
			)
		)
		(property "Value" "TP_1mm_SMD"
			(at 342.9 165.735 0)
			(effects
				(font
					(size 1.27 1.27)
					(thickness 0.15)
				)
				(justify left bottom)
				(hide yes)
			)
		)
		(property "Footprint" "antmicro-footprints:TP_SMD_1mm"
			(at 342.9 168.275 0)
			(effects
				(font
					(size 1.27 1.27)
					(thickness 0.15)
				)
				(justify left bottom)
				(hide yes)
			)
		)
		(property "Datasheet" ""
			(at 342.9 170.815 0)
			(effects
				(font
					(size 1.27 1.27)
					(thickness 0.15)
				)
				(justify left bottom)
				(hide yes)
			)
		)
		(property "Description" ""
			(at 327.66 158.115 0)
			(effects
				(font
					(size 1.27 1.27)
				)
			)
		)
		(property "MPN" ""
			(at 327.66 158.115 0)
			(effects
				(font
					(size 1.27 1.27)
				)
				(hide yes)
			)
		)
		(property "Manufacturer" ""
			(at 327.66 158.115 0)
			(effects
				(font
					(size 1.27 1.27)
				)
				(hide yes)
			)
		)
		(property "Author" "Antmicro"
			(at 342.9 173.355 0)
			(effects
				(font
					(size 1.27 1.27)
					(thickness 0.15)
				)
				(justify left bottom)
				(hide yes)
			)
		)
		(property "License" "Apache-2.0"
			(at 342.9 175.895 0)
			(effects
				(font
					(size 1.27 1.27)
					(thickness 0.15)
				)
				(justify left bottom)
				(hide yes)
			)
		)
		(pin "1"
		)
		(instances
			(project "sodimm-ddr5-tester"
				(path ""
					(reference "TP11")
					(unit 1)
				)
			)
		)
	)
	(symbol
		(lib_id "antmicroTestPoints:TP_1mm_SMD")
		(at 131.445 158.115 0)
		(unit 1)
		(exclude_from_sim no)
		(in_bom yes)
		(on_board yes)
		(dnp no)
		(fields_autoplaced yes)
		(property "Reference" "TP8"
			(at 136.017 158.5488 0)
			(effects
				(font
					(size 1.27 1.27)
				)
				(justify left)
			)
		)
		(property "Value" "TP_1mm_SMD"
			(at 146.685 165.735 0)
			(effects
				(font
					(size 1.27 1.27)
					(thickness 0.15)
				)
				(justify left bottom)
				(hide yes)
			)
		)
		(property "Footprint" "antmicro-footprints:TP_SMD_1mm"
			(at 146.685 168.275 0)
			(effects
				(font
					(size 1.27 1.27)
					(thickness 0.15)
				)
				(justify left bottom)
				(hide yes)
			)
		)
		(property "Datasheet" ""
			(at 146.685 170.815 0)
			(effects
				(font
					(size 1.27 1.27)
					(thickness 0.15)
				)
				(justify left bottom)
				(hide yes)
			)
		)
		(property "Description" ""
			(at 131.445 158.115 0)
			(effects
				(font
					(size 1.27 1.27)
				)
			)
		)
		(property "MPN" ""
			(at 131.445 158.115 0)
			(effects
				(font
					(size 1.27 1.27)
				)
				(hide yes)
			)
		)
		(property "Manufacturer" ""
			(at 131.445 158.115 0)
			(effects
				(font
					(size 1.27 1.27)
				)
				(hide yes)
			)
		)
		(property "Author" "Antmicro"
			(at 146.685 173.355 0)
			(effects
				(font
					(size 1.27 1.27)
					(thickness 0.15)
				)
				(justify left bottom)
				(hide yes)
			)
		)
		(property "License" "Apache-2.0"
			(at 146.685 175.895 0)
			(effects
				(font
					(size 1.27 1.27)
					(thickness 0.15)
				)
				(justify left bottom)
				(hide yes)
			)
		)
		(pin "1"
		)
		(instances
			(project "sodimm-ddr5-tester"
				(path ""
					(reference "TP8")
					(unit 1)
				)
			)
		)
	)
	(symbol
		(lib_id "antmicroTestPoints:TP_1mm_SMD")
		(at 145.415 106.68 0)
		(unit 1)
		(exclude_from_sim no)
		(in_bom yes)
		(on_board yes)
		(dnp no)
		(property "Reference" "TP10"
			(at 144.78 108.585 0)
			(effects
				(font
					(size 1.27 1.27)
				)
				(justify left)
			)
		)
		(property "Value" "TP_1mm_SMD"
			(at 160.655 114.3 0)
			(effects
				(font
					(size 1.27 1.27)
					(thickness 0.15)
				)
				(justify left bottom)
				(hide yes)
			)
		)
		(property "Footprint" "antmicro-footprints:TP_SMD_1mm"
			(at 160.655 116.84 0)
			(effects
				(font
					(size 1.27 1.27)
					(thickness 0.15)
				)
				(justify left bottom)
				(hide yes)
			)
		)
		(property "Datasheet" ""
			(at 160.655 119.38 0)
			(effects
				(font
					(size 1.27 1.27)
					(thickness 0.15)
				)
				(justify left bottom)
				(hide yes)
			)
		)
		(property "Description" ""
			(at 145.415 106.68 0)
			(effects
				(font
					(size 1.27 1.27)
				)
			)
		)
		(property "MPN" ""
			(at 145.415 106.68 0)
			(effects
				(font
					(size 1.27 1.27)
				)
				(hide yes)
			)
		)
		(property "Manufacturer" ""
			(at 145.415 106.68 0)
			(effects
				(font
					(size 1.27 1.27)
				)
				(hide yes)
			)
		)
		(property "Author" "Antmicro"
			(at 160.655 121.92 0)
			(effects
				(font
					(size 1.27 1.27)
					(thickness 0.15)
				)
				(justify left bottom)
				(hide yes)
			)
		)
		(property "License" "Apache-2.0"
			(at 160.655 124.46 0)
			(effects
				(font
					(size 1.27 1.27)
					(thickness 0.15)
				)
				(justify left bottom)
				(hide yes)
			)
		)
		(pin "1"
		)
		(instances
			(project "sodimm-ddr5-tester"
				(path ""
					(reference "TP10")
					(unit 1)
				)
			)
		)
	)
	(symbol
		(lib_id "antmicroResistors0402:R_80k6_0402")
		(at 123.825 124.46 90)
		(unit 1)
		(exclude_from_sim no)
		(in_bom yes)
		(on_board yes)
		(dnp no)
		(fields_autoplaced yes)
		(property "Reference" "R185"
			(at 125.73 120.6499 90)
			(effects
				(font
					(size 1.27 1.27)
				)
				(justify right)
			)
		)
		(property "Value" "R_80k6_0402"
			(at 136.525 104.14 0)
			(effects
				(font
					(size 1.27 1.27)
					(thickness 0.15)
				)
				(justify left bottom)
				(hide yes)
			)
		)
		(property "Footprint" "antmicro-footprints:R_0402_1005Metric"
			(at 139.065 104.14 0)
			(effects
				(font
					(size 1.27 1.27)
					(thickness 0.15)
				)
				(justify left bottom)
				(hide yes)
			)
		)
		(property "Datasheet" "https://www.bourns.com/docs/product-datasheets/cr.pdf"
			(at 141.605 104.14 0)
			(effects
				(font
					(size 1.27 1.27)
					(thickness 0.15)
				)
				(justify left bottom)
				(hide yes)
			)
		)
		(property "Description" ""
			(at 123.825 124.46 0)
			(effects
				(font
					(size 1.27 1.27)
				)
			)
		)
		(property "Manufacturer" "Bourns"
			(at 146.685 104.14 0)
			(effects
				(font
					(size 1.27 1.27)
					(thickness 0.15)
				)
				(justify left bottom)
				(hide yes)
			)
		)
		(property "MPN" "CR0402-FX-8062GLF"
			(at 144.145 104.14 0)
			(effects
				(font
					(size 1.27 1.27)
					(thickness 0.15)
				)
				(justify left bottom)
				(hide yes)
			)
		)
		(property "Val" "80k6"
			(at 125.73 123.1899 90)
			(effects
				(font
					(size 1.27 1.27)
					(thickness 0.15)
				)
				(justify right)
			)
		)
		(property "License" "Apache-2.0"
			(at 149.225 104.14 0)
			(effects
				(font
					(size 1.27 1.27)
					(thickness 0.15)
				)
				(justify left bottom)
				(hide yes)
			)
		)
		(property "Author" "Antmicro"
			(at 151.765 104.14 0)
			(effects
				(font
					(size 1.27 1.27)
					(thickness 0.15)
				)
				(justify left bottom)
				(hide yes)
			)
		)
		(property "Tolerance" "1%"
			(at 133.985 104.14 0)
			(effects
				(font
					(size 1.27 1.27)
				)
				(justify left bottom)
				(hide yes)
			)
		)
		(pin "1"
		)
		(pin "2"
		)
		(instances
			(project "sodimm-ddr5-tester"
				(path ""
					(reference "R185")
					(unit 1)
				)
			)
		)
	)
	(symbol
		(lib_id "antmicroPowerMeasurement:PAC1954T-E_VQFN")
		(at 306.07 98.425 0)
		(unit 1)
		(exclude_from_sim no)
		(in_bom yes)
		(on_board yes)
		(dnp no)
		(fields_autoplaced yes)
		(property "Reference" "U25"
			(at 318.77 92.1934 0)
			(effects
				(font
					(size 1.27 1.27)
				)
			)
		)
		(property "Value" "PAC1954T-E_VQFN"
			(at 318.77 94.7237 0)
			(effects
				(font
					(size 1.27 1.27)
					(thickness 0.15)
				)
			)
		)
		(property "Footprint" "antmicro-footprints:VQFN-16-1EP_3x3mm_P0.5mm_EP1.1x1.1mm"
			(at 344.17 106.045 0)
			(effects
				(font
					(size 1.27 1.27)
					(thickness 0.15)
				)
				(justify left bottom)
				(hide yes)
			)
		)
		(property "Datasheet" "https://ww1.microchip.com/downloads/aemDocuments/documents/MSLD/ProductDocuments/DataSheets/PAC195X-Family-Data-Sheet-DS20006539.pdf"
			(at 344.17 108.585 0)
			(effects
				(font
					(size 1.27 1.27)
					(thickness 0.15)
				)
				(justify left bottom)
				(hide yes)
			)
		)
		(property "Description" ""
			(at 306.07 98.425 0)
			(effects
				(font
					(size 1.27 1.27)
				)
			)
		)
		(property "MPN" "PAC1954T-E/4MX"
			(at 318.77 93.345 0)
			(effects
				(font
					(size 1.27 1.27)
					(thickness 0.15)
				)
				(hide yes)
			)
		)
		(property "Manufacturer" "Microchip Technology"
			(at 344.17 113.665 0)
			(effects
				(font
					(size 1.27 1.27)
					(thickness 0.15)
				)
				(justify left bottom)
				(hide yes)
			)
		)
		(property "Author" "Antmicro"
			(at 344.17 116.205 0)
			(effects
				(font
					(size 1.27 1.27)
					(thickness 0.15)
				)
				(justify left bottom)
				(hide yes)
			)
		)
		(property "License" "Apache-2.0"
			(at 344.17 118.745 0)
			(effects
				(font
					(size 1.27 1.27)
					(thickness 0.15)
				)
				(justify left bottom)
				(hide yes)
			)
		)
		(pin "1"
		)
		(pin "10"
		)
		(pin "11"
		)
		(pin "12"
		)
		(pin "13"
		)
		(pin "14"
		)
		(pin "15"
		)
		(pin "16"
		)
		(pin "17"
		)
		(pin "2"
		)
		(pin "3"
		)
		(pin "4"
		)
		(pin "5"
		)
		(pin "6"
		)
		(pin "7"
		)
		(pin "8"
		)
		(pin "9"
		)
		(instances
			(project "sodimm-ddr5-tester"
				(path ""
					(reference "U25")
					(unit 1)
				)
			)
		)
	)
	(symbol
		(lib_id "antmicroResistors0402:R_0R_0402")
		(at 160.02 173.99 90)
		(unit 1)
		(exclude_from_sim no)
		(in_bom yes)
		(on_board yes)
		(dnp no)
		(fields_autoplaced yes)
		(property "Reference" "R151"
			(at 162.56 170.1799 90)
			(effects
				(font
					(size 1.27 1.27)
				)
				(justify right)
			)
		)
		(property "Value" "R_0R_0402"
			(at 172.72 153.67 0)
			(effects
				(font
					(size 1.27 1.27)
					(thickness 0.15)
				)
				(justify left bottom)
				(hide yes)
			)
		)
		(property "Footprint" "antmicro-footprints:R_0402_1005Metric"
			(at 175.26 153.67 0)
			(effects
				(font
					(size 1.27 1.27)
					(thickness 0.15)
				)
				(justify left bottom)
				(hide yes)
			)
		)
		(property "Datasheet" "https://industrial.panasonic.com/cdbs/www-data/pdf/RDA0000/AOA0000C301.pdf"
			(at 177.8 153.67 0)
			(effects
				(font
					(size 1.27 1.27)
					(thickness 0.15)
				)
				(justify left bottom)
				(hide yes)
			)
		)
		(property "Description" ""
			(at 160.02 173.99 0)
			(effects
				(font
					(size 1.27 1.27)
				)
			)
		)
		(property "Manufacturer" "Panasonic"
			(at 182.88 153.67 0)
			(effects
				(font
					(size 1.27 1.27)
					(thickness 0.15)
				)
				(justify left bottom)
				(hide yes)
			)
		)
		(property "MPN" "ERJ2GE0R00X"
			(at 180.34 153.67 0)
			(effects
				(font
					(size 1.27 1.27)
					(thickness 0.15)
				)
				(justify left bottom)
				(hide yes)
			)
		)
		(property "Val" "0R"
			(at 162.56 172.7199 90)
			(effects
				(font
					(size 1.27 1.27)
					(thickness 0.15)
				)
				(justify right)
			)
		)
		(property "License" "Apache-2.0"
			(at 185.42 153.67 0)
			(effects
				(font
					(size 1.27 1.27)
					(thickness 0.15)
				)
				(justify left bottom)
				(hide yes)
			)
		)
		(property "Author" "Antmicro"
			(at 187.96 153.67 0)
			(effects
				(font
					(size 1.27 1.27)
					(thickness 0.15)
				)
				(justify left bottom)
				(hide yes)
			)
		)
		(property "Tolerance" "~"
			(at 170.18 153.67 0)
			(effects
				(font
					(size 1.27 1.27)
				)
				(justify left bottom)
				(hide yes)
			)
		)
		(property "Current" "1A"
			(at 162.56 173.9899 90)
			(effects
				(font
					(size 1.27 1.27)
					(thickness 0.15)
				)
				(justify right)
				(hide yes)
			)
		)
		(pin "1"
		)
		(pin "2"
		)
		(instances
			(project "sodimm-ddr5-tester"
				(path ""
					(reference "R151")
					(unit 1)
				)
			)
		)
	)
	(symbol
		(lib_id "antmicropower:GND")
		(at 64.135 137.16 0)
		(unit 1)
		(exclude_from_sim no)
		(in_bom yes)
		(on_board yes)
		(dnp no)
		(fields_autoplaced yes)
		(property "Reference" "#PWR0378"
			(at 64.135 143.51 0)
			(effects
				(font
					(size 1.27 1.27)
				)
				(hide yes)
			)
		)
		(property "Value" "GND"
			(at 66.04 138.43 0)
			(effects
				(font
					(size 1.27 1.27)
					(thickness 0.15)
				)
				(justify left)
			)
		)
		(property "Footprint" ""
			(at 73.025 144.78 0)
			(effects
				(font
					(size 1.27 1.27)
					(thickness 0.15)
				)
				(justify left bottom)
				(hide yes)
			)
		)
		(property "Datasheet" ""
			(at 73.025 149.86 0)
			(effects
				(font
					(size 1.27 1.27)
					(thickness 0.15)
				)
				(justify left bottom)
				(hide yes)
			)
		)
		(property "Description" ""
			(at 73.025 152.4 0)
			(effects
				(font
					(size 1.27 1.27)
				)
				(justify left bottom)
				(hide yes)
			)
		)
		(property "Author" "Antmicro"
			(at 73.025 144.78 0)
			(effects
				(font
					(size 1.27 1.27)
					(thickness 0.15)
				)
				(justify left bottom)
				(hide yes)
			)
		)
		(property "License" "Apache-2.0"
			(at 73.025 147.32 0)
			(effects
				(font
					(size 1.27 1.27)
					(thickness 0.15)
				)
				(justify left bottom)
				(hide yes)
			)
		)
		(pin "1"
		)
		(instances
			(project "sodimm-ddr5-tester"
				(path ""
					(reference "#PWR0378")
					(unit 1)
				)
			)
		)
	)
	(symbol
		(lib_id "antmicropower:+3V3")
		(at 142.24 276.86 0)
		(unit 1)
		(exclude_from_sim no)
		(in_bom yes)
		(on_board yes)
		(dnp no)
		(property "Reference" "#PWR025"
			(at 142.24 280.67 0)
			(effects
				(font
					(size 1.27 1.27)
				)
				(hide yes)
			)
		)
		(property "Value" "+3V3"
			(at 139.065 274.32 0)
			(effects
				(font
					(size 1.27 1.27)
					(thickness 0.15)
				)
				(justify left bottom)
			)
		)
		(property "Footprint" ""
			(at 157.48 284.48 0)
			(effects
				(font
					(size 1.27 1.27)
					(thickness 0.15)
				)
				(justify left bottom)
				(hide yes)
			)
		)
		(property "Datasheet" ""
			(at 157.48 287.02 0)
			(effects
				(font
					(size 1.27 1.27)
					(thickness 0.15)
				)
				(justify left bottom)
				(hide yes)
			)
		)
		(property "Description" ""
			(at 142.24 276.86 0)
			(effects
				(font
					(size 1.27 1.27)
				)
			)
		)
		(property "Author" "Antmicro"
			(at 157.48 279.4 0)
			(effects
				(font
					(size 1.27 1.27)
					(thickness 0.15)
				)
				(justify left bottom)
				(hide yes)
			)
		)
		(property "License" "Apache-2.0"
			(at 157.48 281.94 0)
			(effects
				(font
					(size 1.27 1.27)
					(thickness 0.15)
				)
				(justify left bottom)
				(hide yes)
			)
		)
		(pin "1"
		)
		(instances
			(project "sodimm-ddr5-tester"
				(path ""
					(reference "#PWR025")
					(unit 1)
				)
			)
		)
	)
	(symbol
		(lib_id "antmicroResistors0402:R_0R_0402")
		(at 160.02 201.93 90)
		(unit 1)
		(exclude_from_sim no)
		(in_bom yes)
		(on_board yes)
		(dnp no)
		(fields_autoplaced yes)
		(property "Reference" "R153"
			(at 161.925 198.1199 90)
			(effects
				(font
					(size 1.27 1.27)
				)
				(justify right)
			)
		)
		(property "Value" "R_0R_0402"
			(at 172.72 181.61 0)
			(effects
				(font
					(size 1.27 1.27)
					(thickness 0.15)
				)
				(justify left bottom)
				(hide yes)
			)
		)
		(property "Footprint" "antmicro-footprints:R_0402_1005Metric"
			(at 175.26 181.61 0)
			(effects
				(font
					(size 1.27 1.27)
					(thickness 0.15)
				)
				(justify left bottom)
				(hide yes)
			)
		)
		(property "Datasheet" "https://industrial.panasonic.com/cdbs/www-data/pdf/RDA0000/AOA0000C301.pdf"
			(at 177.8 181.61 0)
			(effects
				(font
					(size 1.27 1.27)
					(thickness 0.15)
				)
				(justify left bottom)
				(hide yes)
			)
		)
		(property "Description" ""
			(at 160.02 201.93 0)
			(effects
				(font
					(size 1.27 1.27)
				)
			)
		)
		(property "Manufacturer" "Panasonic"
			(at 182.88 181.61 0)
			(effects
				(font
					(size 1.27 1.27)
					(thickness 0.15)
				)
				(justify left bottom)
				(hide yes)
			)
		)
		(property "MPN" "ERJ2GE0R00X"
			(at 180.34 181.61 0)
			(effects
				(font
					(size 1.27 1.27)
					(thickness 0.15)
				)
				(justify left bottom)
				(hide yes)
			)
		)
		(property "Val" "0R"
			(at 161.925 200.6599 90)
			(effects
				(font
					(size 1.27 1.27)
					(thickness 0.15)
				)
				(justify right)
			)
		)
		(property "License" "Apache-2.0"
			(at 185.42 181.61 0)
			(effects
				(font
					(size 1.27 1.27)
					(thickness 0.15)
				)
				(justify left bottom)
				(hide yes)
			)
		)
		(property "Author" "Antmicro"
			(at 187.96 181.61 0)
			(effects
				(font
					(size 1.27 1.27)
					(thickness 0.15)
				)
				(justify left bottom)
				(hide yes)
			)
		)
		(property "Tolerance" "~"
			(at 170.18 181.61 0)
			(effects
				(font
					(size 1.27 1.27)
				)
				(justify left bottom)
				(hide yes)
			)
		)
		(property "Current" "1A"
			(at 161.925 201.9299 90)
			(effects
				(font
					(size 1.27 1.27)
					(thickness 0.15)
				)
				(justify right)
				(hide yes)
			)
		)
		(pin "1"
		)
		(pin "2"
		)
		(instances
			(project "sodimm-ddr5-tester"
				(path ""
					(reference "R153")
					(unit 1)
				)
			)
		)
	)
	(symbol
		(lib_id "antmicropower:GND")
		(at 155.575 264.16 0)
		(mirror y)
		(unit 1)
		(exclude_from_sim no)
		(in_bom yes)
		(on_board yes)
		(dnp no)
		(property "Reference" "#PWR0387"
			(at 155.575 270.51 0)
			(effects
				(font
					(size 1.27 1.27)
				)
				(hide yes)
			)
		)
		(property "Value" "GND"
			(at 153.416 267.97 0)
			(effects
				(font
					(size 1.27 1.27)
					(thickness 0.15)
				)
				(justify right)
			)
		)
		(property "Footprint" ""
			(at 146.685 271.78 0)
			(effects
				(font
					(size 1.27 1.27)
					(thickness 0.15)
				)
				(justify left bottom)
				(hide yes)
			)
		)
		(property "Datasheet" ""
			(at 146.685 276.86 0)
			(effects
				(font
					(size 1.27 1.27)
					(thickness 0.15)
				)
				(justify left bottom)
				(hide yes)
			)
		)
		(property "Description" ""
			(at 146.685 279.4 0)
			(effects
				(font
					(size 1.27 1.27)
				)
				(justify left bottom)
				(hide yes)
			)
		)
		(property "Author" "Antmicro"
			(at 146.685 271.78 0)
			(effects
				(font
					(size 1.27 1.27)
					(thickness 0.15)
				)
				(justify left bottom)
				(hide yes)
			)
		)
		(property "License" "Apache-2.0"
			(at 146.685 274.32 0)
			(effects
				(font
					(size 1.27 1.27)
					(thickness 0.15)
				)
				(justify left bottom)
				(hide yes)
			)
		)
		(pin "1"
		)
		(instances
			(project "sodimm-ddr5-tester"
				(path ""
					(reference "#PWR0387")
					(unit 1)
				)
			)
		)
	)
	(symbol
		(lib_id "antmicroTransistorsFETsMOSFETsSingle:BSS138PW,115")
		(at 176.53 64.135 0)
		(unit 1)
		(exclude_from_sim no)
		(in_bom yes)
		(on_board yes)
		(dnp no)
		(property "Reference" "Q14"
			(at 176.784 56.769 0)
			(effects
				(font
					(size 1.27 1.27)
					(thickness 0.15)
				)
				(justify left)
			)
		)
		(property "Value" "BSS138PW,115"
			(at 199.39 73.025 0)
			(effects
				(font
					(size 1.27 1.27)
					(thickness 0.15)
				)
				(justify left bottom)
				(hide yes)
			)
		)
		(property "Footprint" "antmicro-footprints:SC70-3"
			(at 199.39 75.565 0)
			(effects
				(font
					(size 1.27 1.27)
					(thickness 0.15)
				)
				(justify left bottom)
				(hide yes)
			)
		)
		(property "Datasheet" "https://assets.nexperia.com/documents/data-sheet/BSS138PW.pdf"
			(at 199.39 78.105 0)
			(effects
				(font
					(size 1.27 1.27)
					(thickness 0.15)
				)
				(justify left bottom)
				(hide yes)
			)
		)
		(property "Description" "Power MOSFET, N Channel, 60 V, 320 mA, 0.9 ohm, SOT-323, Surface Mount"
			(at 199.39 90.805 0)
			(effects
				(font
					(size 1.27 1.27)
				)
				(justify left bottom)
				(hide yes)
			)
		)
		(property "MPN" "BSS138PW,115"
			(at 187.706 68.961 90)
			(effects
				(font
					(size 1.27 1.27)
					(thickness 0.15)
				)
				(justify left)
			)
		)
		(property "Manufacturer" "Nexperia"
			(at 199.39 83.185 0)
			(effects
				(font
					(size 1.27 1.27)
					(thickness 0.15)
				)
				(justify left bottom)
				(hide yes)
			)
		)
		(property "Author" "Antmicro"
			(at 199.39 85.725 0)
			(effects
				(font
					(size 1.27 1.27)
					(thickness 0.15)
				)
				(justify left bottom)
				(hide yes)
			)
		)
		(property "License" "Apache-2.0"
			(at 199.39 88.265 0)
			(effects
				(font
					(size 1.27 1.27)
					(thickness 0.15)
				)
				(justify left bottom)
				(hide yes)
			)
		)
		(pin "3"
		)
		(pin "2"
		)
		(pin "1"
		)
		(instances
			(project "sodimm-ddr5-tester"
				(path ""
					(reference "Q14")
					(unit 1)
				)
			)
		)
	)
	(symbol
		(lib_id "antmicropower:GND")
		(at 346.71 58.42 0)
		(unit 1)
		(exclude_from_sim no)
		(in_bom yes)
		(on_board yes)
		(dnp no)
		(fields_autoplaced yes)
		(property "Reference" "#PWR0379"
			(at 346.71 64.77 0)
			(effects
				(font
					(size 1.27 1.27)
				)
				(hide yes)
			)
		)
		(property "Value" "GND"
			(at 349.25 59.69 0)
			(effects
				(font
					(size 1.27 1.27)
					(thickness 0.15)
				)
				(justify left)
			)
		)
		(property "Footprint" ""
			(at 355.6 66.04 0)
			(effects
				(font
					(size 1.27 1.27)
					(thickness 0.15)
				)
				(justify left bottom)
				(hide yes)
			)
		)
		(property "Datasheet" ""
			(at 355.6 71.12 0)
			(effects
				(font
					(size 1.27 1.27)
					(thickness 0.15)
				)
				(justify left bottom)
				(hide yes)
			)
		)
		(property "Description" ""
			(at 355.6 73.66 0)
			(effects
				(font
					(size 1.27 1.27)
				)
				(justify left bottom)
				(hide yes)
			)
		)
		(property "Author" "Antmicro"
			(at 355.6 66.04 0)
			(effects
				(font
					(size 1.27 1.27)
					(thickness 0.15)
				)
				(justify left bottom)
				(hide yes)
			)
		)
		(property "License" "Apache-2.0"
			(at 355.6 68.58 0)
			(effects
				(font
					(size 1.27 1.27)
					(thickness 0.15)
				)
				(justify left bottom)
				(hide yes)
			)
		)
		(pin "1"
		)
		(instances
			(project "sodimm-ddr5-tester"
				(path ""
					(reference "#PWR0379")
					(unit 1)
				)
			)
		)
	)
	(symbol
		(lib_id "antmicropower:GND")
		(at 34.29 66.675 0)
		(unit 1)
		(exclude_from_sim no)
		(in_bom yes)
		(on_board yes)
		(dnp no)
		(fields_autoplaced yes)
		(property "Reference" "#PWR0284"
			(at 34.29 73.025 0)
			(effects
				(font
					(size 1.27 1.27)
				)
				(hide yes)
			)
		)
		(property "Value" "GND"
			(at 36.83 67.945 0)
			(effects
				(font
					(size 1.27 1.27)
					(thickness 0.15)
				)
				(justify left)
			)
		)
		(property "Footprint" ""
			(at 43.18 74.295 0)
			(effects
				(font
					(size 1.27 1.27)
					(thickness 0.15)
				)
				(justify left bottom)
				(hide yes)
			)
		)
		(property "Datasheet" ""
			(at 43.18 79.375 0)
			(effects
				(font
					(size 1.27 1.27)
					(thickness 0.15)
				)
				(justify left bottom)
				(hide yes)
			)
		)
		(property "Description" ""
			(at 43.18 81.915 0)
			(effects
				(font
					(size 1.27 1.27)
				)
				(justify left bottom)
				(hide yes)
			)
		)
		(property "Author" "Antmicro"
			(at 43.18 74.295 0)
			(effects
				(font
					(size 1.27 1.27)
					(thickness 0.15)
				)
				(justify left bottom)
				(hide yes)
			)
		)
		(property "License" "Apache-2.0"
			(at 43.18 76.835 0)
			(effects
				(font
					(size 1.27 1.27)
					(thickness 0.15)
				)
				(justify left bottom)
				(hide yes)
			)
		)
		(pin "1"
		)
		(instances
			(project "sodimm-ddr5-tester"
				(path ""
					(reference "#PWR0284")
					(unit 1)
				)
			)
		)
	)
	(symbol
		(lib_id "antmicroTestPoints:TP_1mm_SMD")
		(at 248.92 278.13 0)
		(unit 1)
		(exclude_from_sim no)
		(in_bom yes)
		(on_board yes)
		(dnp no)
		(property "Reference" "TP61"
			(at 255.778 278.13 0)
			(effects
				(font
					(size 1.27 1.27)
				)
			)
		)
		(property "Value" "TP_1mm_SMD"
			(at 264.16 285.75 0)
			(effects
				(font
					(size 1.27 1.27)
					(thickness 0.15)
				)
				(justify left bottom)
				(hide yes)
			)
		)
		(property "Footprint" "antmicro-footprints:TP_SMD_1mm"
			(at 264.16 288.29 0)
			(effects
				(font
					(size 1.27 1.27)
					(thickness 0.15)
				)
				(justify left bottom)
				(hide yes)
			)
		)
		(property "Datasheet" ""
			(at 264.16 290.83 0)
			(effects
				(font
					(size 1.27 1.27)
					(thickness 0.15)
				)
				(justify left bottom)
				(hide yes)
			)
		)
		(property "Description" ""
			(at 248.92 278.13 0)
			(effects
				(font
					(size 1.27 1.27)
				)
			)
		)
		(property "MPN" ""
			(at 248.92 278.13 0)
			(effects
				(font
					(size 1.27 1.27)
				)
				(hide yes)
			)
		)
		(property "Manufacturer" ""
			(at 248.92 278.13 0)
			(effects
				(font
					(size 1.27 1.27)
				)
				(hide yes)
			)
		)
		(property "Author" "Antmicro"
			(at 264.16 293.37 0)
			(effects
				(font
					(size 1.27 1.27)
					(thickness 0.15)
				)
				(justify left bottom)
				(hide yes)
			)
		)
		(property "License" "Apache-2.0"
			(at 264.16 295.91 0)
			(effects
				(font
					(size 1.27 1.27)
					(thickness 0.15)
				)
				(justify left bottom)
				(hide yes)
			)
		)
		(pin "1"
		)
		(instances
			(project "sodimm-ddr5-tester"
				(path ""
					(reference "TP61")
					(unit 1)
				)
			)
		)
	)
	(symbol
		(lib_id "antmicropower:+3V3")
		(at 285.75 128.27 0)
		(unit 1)
		(exclude_from_sim no)
		(in_bom yes)
		(on_board yes)
		(dnp no)
		(fields_autoplaced yes)
		(property "Reference" "#PWR0360"
			(at 285.75 132.08 0)
			(effects
				(font
					(size 1.27 1.27)
				)
				(hide yes)
			)
		)
		(property "Value" "+3V3"
			(at 282.575 125.73 0)
			(effects
				(font
					(size 1.27 1.27)
					(thickness 0.15)
				)
				(justify left bottom)
			)
		)
		(property "Footprint" ""
			(at 300.99 135.89 0)
			(effects
				(font
					(size 1.27 1.27)
					(thickness 0.15)
				)
				(justify left bottom)
				(hide yes)
			)
		)
		(property "Datasheet" ""
			(at 300.99 138.43 0)
			(effects
				(font
					(size 1.27 1.27)
					(thickness 0.15)
				)
				(justify left bottom)
				(hide yes)
			)
		)
		(property "Description" ""
			(at 285.75 128.27 0)
			(effects
				(font
					(size 1.27 1.27)
				)
			)
		)
		(property "Author" "Antmicro"
			(at 300.99 130.81 0)
			(effects
				(font
					(size 1.27 1.27)
					(thickness 0.15)
				)
				(justify left bottom)
				(hide yes)
			)
		)
		(property "License" "Apache-2.0"
			(at 300.99 133.35 0)
			(effects
				(font
					(size 1.27 1.27)
					(thickness 0.15)
				)
				(justify left bottom)
				(hide yes)
			)
		)
		(pin "1"
		)
		(instances
			(project "sodimm-ddr5-tester"
				(path ""
					(reference "#PWR0360")
					(unit 1)
				)
			)
		)
	)
	(symbol
		(lib_id "antmicropower:PWR_FLAG")
		(at 123.825 178.435 0)
		(unit 1)
		(exclude_from_sim no)
		(in_bom yes)
		(on_board yes)
		(dnp no)
		(fields_autoplaced yes)
		(property "Reference" "#FLG0110"
			(at 123.825 176.53 0)
			(effects
				(font
					(size 1.27 1.27)
				)
				(hide yes)
			)
		)
		(property "Value" "PWR_FLAG"
			(at 123.825 174.8592 0)
			(effects
				(font
					(size 1.27 1.27)
				)
			)
		)
		(property "Footprint" ""
			(at 123.825 178.435 0)
			(effects
				(font
					(size 1.27 1.27)
				)
				(hide yes)
			)
		)
		(property "Datasheet" ""
			(at 123.825 178.435 0)
			(effects
				(font
					(size 1.27 1.27)
				)
				(hide yes)
			)
		)
		(property "Description" ""
			(at 123.825 178.435 0)
			(effects
				(font
					(size 1.27 1.27)
				)
			)
		)
		(pin "1"
		)
		(instances
			(project "sodimm-ddr5-tester"
				(path ""
					(reference "#FLG0110")
					(unit 1)
				)
			)
		)
	)
	(symbol
		(lib_id "antmicroCapacitors0402:C_100n_0402")
		(at 33.655 29.845 90)
		(unit 1)
		(exclude_from_sim no)
		(in_bom yes)
		(on_board yes)
		(dnp no)
		(property "Reference" "C169"
			(at 41.91 26.0285 90)
			(effects
				(font
					(size 1.27 1.27)
				)
				(justify right)
			)
		)
		(property "Value" "C_100n_0402"
			(at 43.815 9.525 0)
			(effects
				(font
					(size 1.27 1.27)
					(thickness 0.15)
				)
				(justify left bottom)
				(hide yes)
			)
		)
		(property "Footprint" "antmicro-footprints:C_0402_1005Metric"
			(at 46.355 9.525 0)
			(effects
				(font
					(size 1.27 1.27)
					(thickness 0.15)
				)
				(justify left bottom)
				(hide yes)
			)
		)
		(property "Datasheet" "https://www.murata.com/products/productdetail?partno=GRM155R61H104KE14%23"
			(at 48.895 9.525 0)
			(effects
				(font
					(size 1.27 1.27)
					(thickness 0.15)
				)
				(justify left bottom)
				(hide yes)
			)
		)
		(property "Description" ""
			(at 33.655 29.845 0)
			(effects
				(font
					(size 1.27 1.27)
				)
			)
		)
		(property "Manufacturer" "Murata"
			(at 53.975 9.525 0)
			(effects
				(font
					(size 1.27 1.27)
					(thickness 0.15)
				)
				(justify left bottom)
				(hide yes)
			)
		)
		(property "MPN" "GRM155R61H104KE14D"
			(at 51.435 9.525 0)
			(effects
				(font
					(size 1.27 1.27)
					(thickness 0.15)
				)
				(justify left bottom)
				(hide yes)
			)
		)
		(property "Val" "100n"
			(at 41.91 28.5685 90)
			(effects
				(font
					(size 1.27 1.27)
					(thickness 0.15)
				)
				(justify right)
			)
		)
		(property "License" "Apache-2.0"
			(at 56.515 9.525 0)
			(effects
				(font
					(size 1.27 1.27)
					(thickness 0.15)
				)
				(justify left bottom)
				(hide yes)
			)
		)
		(property "Author" "Antmicro"
			(at 59.055 9.525 0)
			(effects
				(font
					(size 1.27 1.27)
					(thickness 0.15)
				)
				(justify left bottom)
				(hide yes)
			)
		)
		(property "Voltage" "50V"
			(at 61.595 9.525 0)
			(effects
				(font
					(size 1.27 1.27)
				)
				(justify left bottom)
				(hide yes)
			)
		)
		(property "Dielectric" "X5R"
			(at 64.135 9.525 0)
			(effects
				(font
					(size 1.27 1.27)
				)
				(justify left bottom)
				(hide yes)
			)
		)
		(pin "1"
		)
		(pin "2"
		)
		(instances
			(project "sodimm-ddr5-tester"
				(path ""
					(reference "C169")
					(unit 1)
				)
			)
		)
	)
	(symbol
		(lib_id "antmicropower:VDC")
		(at 17.145 156.21 0)
		(unit 1)
		(exclude_from_sim no)
		(in_bom yes)
		(on_board yes)
		(dnp no)
		(fields_autoplaced yes)
		(property "Reference" "#PWR0286"
			(at 17.145 158.75 0)
			(effects
				(font
					(size 1.27 1.27)
				)
				(hide yes)
			)
		)
		(property "Value" "VDC"
			(at 17.145 151.13 0)
			(effects
				(font
					(size 1.27 1.27)
				)
			)
		)
		(property "Footprint" ""
			(at 17.145 156.21 0)
			(effects
				(font
					(size 1.27 1.27)
				)
				(hide yes)
			)
		)
		(property "Datasheet" ""
			(at 17.145 156.21 0)
			(effects
				(font
					(size 1.27 1.27)
				)
				(hide yes)
			)
		)
		(property "Description" ""
			(at 17.145 156.21 0)
			(effects
				(font
					(size 1.27 1.27)
				)
			)
		)
		(pin "1"
		)
		(instances
			(project "sodimm-ddr5-tester"
				(path ""
					(reference "#PWR0286")
					(unit 1)
				)
			)
		)
	)
	(symbol
		(lib_id "antmicroCapacitors0603:C_22u_0603")
		(at 285.75 187.325 90)
		(unit 1)
		(exclude_from_sim no)
		(in_bom yes)
		(on_board yes)
		(dnp no)
		(property "Reference" "C191"
			(at 286.385 182.88 90)
			(effects
				(font
					(size 1.27 1.27)
				)
				(justify right)
			)
		)
		(property "Value" "C_22u_0603"
			(at 295.91 167.005 0)
			(effects
				(font
					(size 1.27 1.27)
					(thickness 0.15)
				)
				(justify left bottom)
				(hide yes)
			)
		)
		(property "Footprint" "antmicro-footprints:C_0603_1608Metric"
			(at 298.45 167.005 0)
			(effects
				(font
					(size 1.27 1.27)
					(thickness 0.15)
				)
				(justify left bottom)
				(hide yes)
			)
		)
		(property "Datasheet" "https://www.murata.com/products/productdetail?partno=GRM188R60J226MEA0%23"
			(at 300.99 167.005 0)
			(effects
				(font
					(size 1.27 1.27)
					(thickness 0.15)
				)
				(justify left bottom)
				(hide yes)
			)
		)
		(property "Description" ""
			(at 285.75 187.325 0)
			(effects
				(font
					(size 1.27 1.27)
				)
			)
		)
		(property "Manufacturer" "Murata"
			(at 306.07 167.005 0)
			(effects
				(font
					(size 1.27 1.27)
					(thickness 0.15)
				)
				(justify left bottom)
				(hide yes)
			)
		)
		(property "MPN" "GRM188R60J226MEA0D"
			(at 303.53 167.005 0)
			(effects
				(font
					(size 1.27 1.27)
					(thickness 0.15)
				)
				(justify left bottom)
				(hide yes)
			)
		)
		(property "Val" "22u"
			(at 286.385 186.69 90)
			(effects
				(font
					(size 1.27 1.27)
					(thickness 0.15)
				)
				(justify right)
			)
		)
		(property "License" "Apache-2.0"
			(at 308.61 167.005 0)
			(effects
				(font
					(size 1.27 1.27)
					(thickness 0.15)
				)
				(justify left bottom)
				(hide yes)
			)
		)
		(property "Author" "Antmicro"
			(at 311.15 167.005 0)
			(effects
				(font
					(size 1.27 1.27)
					(thickness 0.15)
				)
				(justify left bottom)
				(hide yes)
			)
		)
		(property "Voltage" ""
			(at 313.69 167.005 0)
			(effects
				(font
					(size 1.27 1.27)
				)
				(justify left bottom)
				(hide yes)
			)
		)
		(property "Dielectric" ""
			(at 316.23 167.005 0)
			(effects
				(font
					(size 1.27 1.27)
				)
				(justify left bottom)
				(hide yes)
			)
		)
		(pin "1"
		)
		(pin "2"
		)
		(instances
			(project "sodimm-ddr5-tester"
				(path ""
					(reference "C191")
					(unit 1)
				)
			)
		)
	)
	(symbol
		(lib_id "antmicroCapacitors0402:C_10u_6.3V_0402")
		(at 61.595 255.27 90)
		(unit 1)
		(exclude_from_sim no)
		(in_bom yes)
		(on_board yes)
		(dnp no)
		(fields_autoplaced yes)
		(property "Reference" "C211"
			(at 63.9191 251.893 90)
			(effects
				(font
					(size 1.27 1.27)
					(thickness 0.15)
				)
				(justify right)
			)
		)
		(property "Value" "C_10u_6.3V_0402"
			(at 71.755 234.95 0)
			(effects
				(font
					(size 1.27 1.27)
					(thickness 0.15)
				)
				(justify left bottom)
				(hide yes)
			)
		)
		(property "Footprint" "antmicro-footprints:C_0402_1005Metric"
			(at 74.295 234.95 0)
			(effects
				(font
					(size 1.27 1.27)
					(thickness 0.15)
				)
				(justify left bottom)
				(hide yes)
			)
		)
		(property "Datasheet" "https://www.murata.com/products/productdetail?partno=GRM155R60J106ME15%23"
			(at 76.835 234.95 0)
			(effects
				(font
					(size 1.27 1.27)
					(thickness 0.15)
				)
				(justify left bottom)
				(hide yes)
			)
		)
		(property "Description" ""
			(at 61.595 255.27 0)
			(effects
				(font
					(size 1.27 1.27)
				)
			)
		)
		(property "MPN" "GRM155R60J106ME15D"
			(at 79.375 234.95 0)
			(effects
				(font
					(size 1.27 1.27)
					(thickness 0.15)
				)
				(justify left bottom)
				(hide yes)
			)
		)
		(property "Manufacturer" "Murata"
			(at 81.915 234.95 0)
			(effects
				(font
					(size 1.27 1.27)
					(thickness 0.15)
				)
				(justify left bottom)
				(hide yes)
			)
		)
		(property "License" "Apache-2.0"
			(at 84.455 234.95 0)
			(effects
				(font
					(size 1.27 1.27)
					(thickness 0.15)
				)
				(justify left bottom)
				(hide yes)
			)
		)
		(property "Author" "Antmicro"
			(at 86.995 234.95 0)
			(effects
				(font
					(size 1.27 1.27)
					(thickness 0.15)
				)
				(justify left bottom)
				(hide yes)
			)
		)
		(property "Val" "10u"
			(at 63.9191 254.4167 90)
			(effects
				(font
					(size 1.27 1.27)
					(thickness 0.15)
				)
				(justify right)
			)
		)
		(property "Voltage" "6.3V"
			(at 89.535 234.95 0)
			(effects
				(font
					(size 1.27 1.27)
				)
				(justify left bottom)
				(hide yes)
			)
		)
		(property "Dielectric" "X5R"
			(at 92.075 234.95 0)
			(effects
				(font
					(size 1.27 1.27)
				)
				(justify left bottom)
				(hide yes)
			)
		)
		(pin "1"
		)
		(pin "2"
		)
		(instances
			(project "sodimm-ddr5-tester"
				(path ""
					(reference "C211")
					(unit 1)
				)
			)
		)
	)
	(symbol
		(lib_id "antmicroCapacitorsmisc:C_22u_25V_0805")
		(at 226.06 164.465 90)
		(unit 1)
		(exclude_from_sim no)
		(in_bom yes)
		(on_board yes)
		(dnp no)
		(property "Reference" "C178"
			(at 226.695 160.02 90)
			(effects
				(font
					(size 1.27 1.27)
				)
				(justify right)
			)
		)
		(property "Value" "C_22u_25V_0805"
			(at 229.87 164.465 0)
			(effects
				(font
					(size 1.27 1.27)
				)
				(hide yes)
			)
		)
		(property "Footprint" "antmicro-footprints:C_0805_2012Metric"
			(at 220.98 159.385 0)
			(effects
				(font
					(size 1.27 1.27)
				)
				(justify left)
				(hide yes)
			)
		)
		(property "Datasheet" "https://product.samsungsem.com/mlcc/CL21A226MAYNNN.do"
			(at 226.06 164.465 0)
			(effects
				(font
					(size 1.27 1.27)
				)
				(hide yes)
			)
		)
		(property "Description" ""
			(at 226.06 164.465 0)
			(effects
				(font
					(size 1.27 1.27)
				)
			)
		)
		(property "Manufacturer" "Samsung Electro-Mechanics"
			(at 215.9 159.385 0)
			(effects
				(font
					(size 1.27 1.27)
				)
				(justify left)
				(hide yes)
			)
		)
		(property "MPN" "CL21A226MAYNNNE"
			(at 218.44 159.385 0)
			(effects
				(font
					(size 1.27 1.27)
				)
				(justify left)
				(hide yes)
			)
		)
		(property "Val" "22u_25V"
			(at 226.695 163.83 90)
			(effects
				(font
					(size 1.27 1.27)
				)
				(justify right)
			)
		)
		(property "License" "Apache-2.0"
			(at 248.92 144.145 0)
			(effects
				(font
					(size 1.27 1.27)
					(thickness 0.15)
				)
				(justify left bottom)
				(hide yes)
			)
		)
		(property "Author" "Antmicro"
			(at 251.46 144.145 0)
			(effects
				(font
					(size 1.27 1.27)
					(thickness 0.15)
				)
				(justify left bottom)
				(hide yes)
			)
		)
		(property "Voltage" ""
			(at 254 144.145 0)
			(effects
				(font
					(size 1.27 1.27)
				)
				(justify left bottom)
				(hide yes)
			)
		)
		(property "Dielectric" ""
			(at 256.54 144.145 0)
			(effects
				(font
					(size 1.27 1.27)
				)
				(justify left bottom)
				(hide yes)
			)
		)
		(pin "1"
		)
		(pin "2"
		)
		(instances
			(project "sodimm-ddr5-tester"
				(path ""
					(reference "C178")
					(unit 1)
				)
			)
		)
	)
	(symbol
		(lib_id "antmicroTestPoints:TP_1mm_SMD")
		(at 267.97 278.13 0)
		(unit 1)
		(exclude_from_sim no)
		(in_bom yes)
		(on_board yes)
		(dnp no)
		(property "Reference" "TP64"
			(at 274.828 278.13 0)
			(effects
				(font
					(size 1.27 1.27)
				)
			)
		)
		(property "Value" "TP_1mm_SMD"
			(at 283.21 285.75 0)
			(effects
				(font
					(size 1.27 1.27)
					(thickness 0.15)
				)
				(justify left bottom)
				(hide yes)
			)
		)
		(property "Footprint" "antmicro-footprints:TP_SMD_1mm"
			(at 283.21 288.29 0)
			(effects
				(font
					(size 1.27 1.27)
					(thickness 0.15)
				)
				(justify left bottom)
				(hide yes)
			)
		)
		(property "Datasheet" ""
			(at 283.21 290.83 0)
			(effects
				(font
					(size 1.27 1.27)
					(thickness 0.15)
				)
				(justify left bottom)
				(hide yes)
			)
		)
		(property "Description" ""
			(at 267.97 278.13 0)
			(effects
				(font
					(size 1.27 1.27)
				)
			)
		)
		(property "MPN" ""
			(at 267.97 278.13 0)
			(effects
				(font
					(size 1.27 1.27)
				)
				(hide yes)
			)
		)
		(property "Manufacturer" ""
			(at 267.97 278.13 0)
			(effects
				(font
					(size 1.27 1.27)
				)
				(hide yes)
			)
		)
		(property "Author" "Antmicro"
			(at 283.21 293.37 0)
			(effects
				(font
					(size 1.27 1.27)
					(thickness 0.15)
				)
				(justify left bottom)
				(hide yes)
			)
		)
		(property "License" "Apache-2.0"
			(at 283.21 295.91 0)
			(effects
				(font
					(size 1.27 1.27)
					(thickness 0.15)
				)
				(justify left bottom)
				(hide yes)
			)
		)
		(pin "1"
		)
		(instances
			(project "sodimm-ddr5-tester"
				(path ""
					(reference "TP64")
					(unit 1)
				)
			)
		)
	)
	(symbol
		(lib_id "antmicropower:+1V8")
		(at 154.94 276.86 0)
		(unit 1)
		(exclude_from_sim no)
		(in_bom yes)
		(on_board yes)
		(dnp no)
		(property "Reference" "#PWR029"
			(at 154.94 280.67 0)
			(effects
				(font
					(size 1.27 1.27)
				)
				(hide yes)
			)
		)
		(property "Value" "+1V8"
			(at 151.638 274.066 0)
			(effects
				(font
					(size 1.27 1.27)
					(thickness 0.15)
				)
				(justify left bottom)
			)
		)
		(property "Footprint" ""
			(at 170.18 284.48 0)
			(effects
				(font
					(size 1.27 1.27)
					(thickness 0.15)
				)
				(justify left bottom)
				(hide yes)
			)
		)
		(property "Datasheet" ""
			(at 170.18 287.02 0)
			(effects
				(font
					(size 1.27 1.27)
					(thickness 0.15)
				)
				(justify left bottom)
				(hide yes)
			)
		)
		(property "Description" ""
			(at 154.94 276.86 0)
			(effects
				(font
					(size 1.27 1.27)
				)
			)
		)
		(property "Author" "Antmicro"
			(at 170.18 281.94 0)
			(effects
				(font
					(size 1.27 1.27)
					(thickness 0.15)
				)
				(justify left bottom)
				(hide yes)
			)
		)
		(property "License" "Apache-2.0"
			(at 170.18 284.48 0)
			(effects
				(font
					(size 1.27 1.27)
					(thickness 0.15)
				)
				(justify left bottom)
				(hide yes)
			)
		)
		(pin "1"
		)
		(instances
			(project "sodimm-ddr5-tester"
				(path ""
					(reference "#PWR029")
					(unit 1)
				)
			)
		)
	)
	(symbol
		(lib_id "antmicroResistorsmisc:R_0R01_1206")
		(at 306.705 212.725 0)
		(unit 1)
		(exclude_from_sim no)
		(in_bom yes)
		(on_board yes)
		(dnp no)
		(property "Reference" "R148"
			(at 309.245 207.645 0)
			(effects
				(font
					(size 1.27 1.27)
				)
			)
		)
		(property "Value" "R_0R01_1206"
			(at 327.025 225.425 0)
			(effects
				(font
					(size 1.27 1.27)
					(thickness 0.15)
				)
				(justify left bottom)
				(hide yes)
			)
		)
		(property "Footprint" "antmicro-footprints:R_1206_3216Metric"
			(at 327.025 227.965 0)
			(effects
				(font
					(size 1.27 1.27)
					(thickness 0.15)
				)
				(justify left bottom)
				(hide yes)
			)
		)
		(property "Datasheet" "https://www.yageo.com/upload/media/product/productsearch/datasheet/rchip/PYu-RL_Group_521_RoHS_L_2.pdf"
			(at 327.025 230.505 0)
			(effects
				(font
					(size 1.27 1.27)
					(thickness 0.15)
				)
				(justify left bottom)
				(hide yes)
			)
		)
		(property "Description" ""
			(at 306.705 212.725 0)
			(effects
				(font
					(size 1.27 1.27)
				)
			)
		)
		(property "Manufacturer" "YAGEO"
			(at 327.025 235.585 0)
			(effects
				(font
					(size 1.27 1.27)
					(thickness 0.15)
				)
				(justify left bottom)
				(hide yes)
			)
		)
		(property "MPN" "RL1206FR-7W0R01L"
			(at 327.025 233.045 0)
			(effects
				(font
					(size 1.27 1.27)
					(thickness 0.15)
				)
				(justify left bottom)
				(hide yes)
			)
		)
		(property "Val" "0R01"
			(at 309.245 210.185 0)
			(effects
				(font
					(size 1.27 1.27)
					(thickness 0.15)
				)
			)
		)
		(property "License" "Apache-2.0"
			(at 327.025 238.125 0)
			(effects
				(font
					(size 1.27 1.27)
					(thickness 0.15)
				)
				(justify left bottom)
				(hide yes)
			)
		)
		(property "Author" "Antmicro"
			(at 327.025 240.665 0)
			(effects
				(font
					(size 1.27 1.27)
					(thickness 0.15)
				)
				(justify left bottom)
				(hide yes)
			)
		)
		(property "Tolerance" "1%"
			(at 327.025 222.885 0)
			(effects
				(font
					(size 1.27 1.27)
				)
				(justify left bottom)
				(hide yes)
			)
		)
		(pin "1"
		)
		(pin "2"
		)
		(instances
			(project "sodimm-ddr5-tester"
				(path ""
					(reference "R148")
					(unit 1)
				)
			)
		)
	)
	(symbol
		(lib_id "antmicroCapacitors0603:C_22u_0603")
		(at 98.425 114.3 90)
		(unit 1)
		(exclude_from_sim no)
		(in_bom yes)
		(on_board yes)
		(dnp no)
		(property "Reference" "C215"
			(at 99.06 109.855 90)
			(effects
				(font
					(size 1.27 1.27)
				)
				(justify right)
			)
		)
		(property "Value" "C_22u_0603"
			(at 108.585 93.98 0)
			(effects
				(font
					(size 1.27 1.27)
					(thickness 0.15)
				)
				(justify left bottom)
				(hide yes)
			)
		)
		(property "Footprint" "antmicro-footprints:C_0603_1608Metric"
			(at 111.125 93.98 0)
			(effects
				(font
					(size 1.27 1.27)
					(thickness 0.15)
				)
				(justify left bottom)
				(hide yes)
			)
		)
		(property "Datasheet" "https://www.murata.com/products/productdetail?partno=GRM188R60J226MEA0%23"
			(at 113.665 93.98 0)
			(effects
				(font
					(size 1.27 1.27)
					(thickness 0.15)
				)
				(justify left bottom)
				(hide yes)
			)
		)
		(property "Description" ""
			(at 98.425 114.3 0)
			(effects
				(font
					(size 1.27 1.27)
				)
			)
		)
		(property "Manufacturer" "Murata"
			(at 118.745 93.98 0)
			(effects
				(font
					(size 1.27 1.27)
					(thickness 0.15)
				)
				(justify left bottom)
				(hide yes)
			)
		)
		(property "MPN" "GRM188R60J226MEA0D"
			(at 116.205 93.98 0)
			(effects
				(font
					(size 1.27 1.27)
					(thickness 0.15)
				)
				(justify left bottom)
				(hide yes)
			)
		)
		(property "Val" "22u"
			(at 99.06 113.665 90)
			(effects
				(font
					(size 1.27 1.27)
					(thickness 0.15)
				)
				(justify right)
			)
		)
		(property "License" "Apache-2.0"
			(at 121.285 93.98 0)
			(effects
				(font
					(size 1.27 1.27)
					(thickness 0.15)
				)
				(justify left bottom)
				(hide yes)
			)
		)
		(property "Author" "Antmicro"
			(at 123.825 93.98 0)
			(effects
				(font
					(size 1.27 1.27)
					(thickness 0.15)
				)
				(justify left bottom)
				(hide yes)
			)
		)
		(property "Voltage" ""
			(at 126.365 93.98 0)
			(effects
				(font
					(size 1.27 1.27)
				)
				(justify left bottom)
				(hide yes)
			)
		)
		(property "Dielectric" ""
			(at 128.905 93.98 0)
			(effects
				(font
					(size 1.27 1.27)
				)
				(justify left bottom)
				(hide yes)
			)
		)
		(pin "1"
		)
		(pin "2"
		)
		(instances
			(project "sodimm-ddr5-tester"
				(path ""
					(reference "C215")
					(unit 1)
				)
			)
		)
	)
	(symbol
		(lib_id "antmicropower:+1V2_MGTAVTT")
		(at 93.345 243.205 0)
		(unit 1)
		(exclude_from_sim no)
		(in_bom yes)
		(on_board yes)
		(dnp no)
		(fields_autoplaced yes)
		(property "Reference" "#PWR0394"
			(at 93.345 247.015 0)
			(effects
				(font
					(size 1.27 1.27)
				)
				(hide yes)
			)
		)
		(property "Value" "+1V2_MGTAVTT"
			(at 93.345 239.395 0)
			(effects
				(font
					(size 1.27 1.27)
				)
			)
		)
		(property "Footprint" ""
			(at 93.345 243.205 0)
			(effects
				(font
					(size 1.27 1.27)
				)
				(hide yes)
			)
		)
		(property "Datasheet" ""
			(at 93.345 243.205 0)
			(effects
				(font
					(size 1.27 1.27)
				)
				(hide yes)
			)
		)
		(property "Description" ""
			(at 93.345 243.205 0)
			(effects
				(font
					(size 1.27 1.27)
				)
			)
		)
		(pin "1"
		)
		(instances
			(project "sodimm-ddr5-tester"
				(path ""
					(reference "#PWR0394")
					(unit 1)
				)
			)
		)
	)
	(symbol
		(lib_id "antmicropower:GND")
		(at 170.815 263.525 0)
		(mirror y)
		(unit 1)
		(exclude_from_sim no)
		(in_bom yes)
		(on_board yes)
		(dnp no)
		(property "Reference" "#PWR0392"
			(at 170.815 269.875 0)
			(effects
				(font
					(size 1.27 1.27)
				)
				(hide yes)
			)
		)
		(property "Value" "GND"
			(at 168.656 267.462 0)
			(effects
				(font
					(size 1.27 1.27)
					(thickness 0.15)
				)
				(justify right)
			)
		)
		(property "Footprint" ""
			(at 161.925 271.145 0)
			(effects
				(font
					(size 1.27 1.27)
					(thickness 0.15)
				)
				(justify left bottom)
				(hide yes)
			)
		)
		(property "Datasheet" ""
			(at 161.925 276.225 0)
			(effects
				(font
					(size 1.27 1.27)
					(thickness 0.15)
				)
				(justify left bottom)
				(hide yes)
			)
		)
		(property "Description" ""
			(at 161.925 278.765 0)
			(effects
				(font
					(size 1.27 1.27)
				)
				(justify left bottom)
				(hide yes)
			)
		)
		(property "Author" "Antmicro"
			(at 161.925 271.145 0)
			(effects
				(font
					(size 1.27 1.27)
					(thickness 0.15)
				)
				(justify left bottom)
				(hide yes)
			)
		)
		(property "License" "Apache-2.0"
			(at 161.925 273.685 0)
			(effects
				(font
					(size 1.27 1.27)
					(thickness 0.15)
				)
				(justify left bottom)
				(hide yes)
			)
		)
		(pin "1"
		)
		(instances
			(project "sodimm-ddr5-tester"
				(path ""
					(reference "#PWR0392")
					(unit 1)
				)
			)
		)
	)
	(symbol
		(lib_id "antmicroResistors0402:R_10k_0402")
		(at 92.71 121.92 0)
		(unit 1)
		(exclude_from_sim no)
		(in_bom yes)
		(on_board yes)
		(dnp no)
		(property "Reference" "R181"
			(at 95.25 119.38 0)
			(effects
				(font
					(size 1.27 1.27)
				)
			)
		)
		(property "Value" "R_10k_0402"
			(at 113.03 134.62 0)
			(effects
				(font
					(size 1.27 1.27)
					(thickness 0.15)
				)
				(justify left bottom)
				(hide yes)
			)
		)
		(property "Footprint" "antmicro-footprints:R_0402_1005Metric"
			(at 113.03 137.16 0)
			(effects
				(font
					(size 1.27 1.27)
					(thickness 0.15)
				)
				(justify left bottom)
				(hide yes)
			)
		)
		(property "Datasheet" "https://www.bourns.com/docs/product-datasheets/cr.pdf"
			(at 113.03 139.7 0)
			(effects
				(font
					(size 1.27 1.27)
					(thickness 0.15)
				)
				(justify left bottom)
				(hide yes)
			)
		)
		(property "Description" ""
			(at 92.71 121.92 0)
			(effects
				(font
					(size 1.27 1.27)
				)
			)
		)
		(property "Manufacturer" "Bourns"
			(at 113.03 144.78 0)
			(effects
				(font
					(size 1.27 1.27)
					(thickness 0.15)
				)
				(justify left bottom)
				(hide yes)
			)
		)
		(property "MPN" "CR0402-FX-1002GLF"
			(at 113.03 142.24 0)
			(effects
				(font
					(size 1.27 1.27)
					(thickness 0.15)
				)
				(justify left bottom)
				(hide yes)
			)
		)
		(property "Val" "10k"
			(at 95.25 124.46 0)
			(effects
				(font
					(size 1.27 1.27)
					(thickness 0.15)
				)
			)
		)
		(property "License" "Apache-2.0"
			(at 113.03 147.32 0)
			(effects
				(font
					(size 1.27 1.27)
					(thickness 0.15)
				)
				(justify left bottom)
				(hide yes)
			)
		)
		(property "Author" "Antmicro"
			(at 113.03 149.86 0)
			(effects
				(font
					(size 1.27 1.27)
					(thickness 0.15)
				)
				(justify left bottom)
				(hide yes)
			)
		)
		(property "Tolerance" "1%"
			(at 113.03 132.08 0)
			(effects
				(font
					(size 1.27 1.27)
				)
				(justify left bottom)
				(hide yes)
			)
		)
		(pin "1"
		)
		(pin "2"
		)
		(instances
			(project "sodimm-ddr5-tester"
				(path ""
					(reference "R181")
					(unit 1)
				)
			)
		)
	)
	(symbol
		(lib_id "antmicroCapacitors0402:C_100n_0402")
		(at 109.22 256.54 270)
		(mirror x)
		(unit 1)
		(exclude_from_sim no)
		(in_bom yes)
		(on_board yes)
		(dnp no)
		(property "Reference" "C205"
			(at 107.95 252.095 90)
			(effects
				(font
					(size 1.27 1.27)
				)
				(justify right)
			)
		)
		(property "Value" "C_100n_0402"
			(at 99.06 236.22 0)
			(effects
				(font
					(size 1.27 1.27)
					(thickness 0.15)
				)
				(justify left bottom)
				(hide yes)
			)
		)
		(property "Footprint" "antmicro-footprints:C_0402_1005Metric"
			(at 96.52 236.22 0)
			(effects
				(font
					(size 1.27 1.27)
					(thickness 0.15)
				)
				(justify left bottom)
				(hide yes)
			)
		)
		(property "Datasheet" "https://www.murata.com/products/productdetail?partno=GRM155R61H104KE14%23"
			(at 93.98 236.22 0)
			(effects
				(font
					(size 1.27 1.27)
					(thickness 0.15)
				)
				(justify left bottom)
				(hide yes)
			)
		)
		(property "Description" ""
			(at 109.22 256.54 0)
			(effects
				(font
					(size 1.27 1.27)
				)
			)
		)
		(property "Manufacturer" "Murata"
			(at 88.9 236.22 0)
			(effects
				(font
					(size 1.27 1.27)
					(thickness 0.15)
				)
				(justify left bottom)
				(hide yes)
			)
		)
		(property "MPN" "GRM155R61H104KE14D"
			(at 91.44 236.22 0)
			(effects
				(font
					(size 1.27 1.27)
					(thickness 0.15)
				)
				(justify left bottom)
				(hide yes)
			)
		)
		(property "Val" "100n"
			(at 107.95 255.905 90)
			(effects
				(font
					(size 1.27 1.27)
					(thickness 0.15)
				)
				(justify right)
			)
		)
		(property "License" "Apache-2.0"
			(at 86.36 236.22 0)
			(effects
				(font
					(size 1.27 1.27)
					(thickness 0.15)
				)
				(justify left bottom)
				(hide yes)
			)
		)
		(property "Author" "Antmicro"
			(at 83.82 236.22 0)
			(effects
				(font
					(size 1.27 1.27)
					(thickness 0.15)
				)
				(justify left bottom)
				(hide yes)
			)
		)
		(property "Voltage" "50V"
			(at 81.28 236.22 0)
			(effects
				(font
					(size 1.27 1.27)
				)
				(justify left bottom)
				(hide yes)
			)
		)
		(property "Dielectric" "X5R"
			(at 78.74 236.22 0)
			(effects
				(font
					(size 1.27 1.27)
				)
				(justify left bottom)
				(hide yes)
			)
		)
		(pin "1"
		)
		(pin "2"
		)
		(instances
			(project "sodimm-ddr5-tester"
				(path ""
					(reference "C205")
					(unit 1)
				)
			)
		)
	)
	(symbol
		(lib_id "antmicropower:GND")
		(at 160.02 186.69 0)
		(unit 1)
		(exclude_from_sim no)
		(in_bom yes)
		(on_board yes)
		(dnp no)
		(fields_autoplaced yes)
		(property "Reference" "#PWR0335"
			(at 160.02 193.04 0)
			(effects
				(font
					(size 1.27 1.27)
				)
				(hide yes)
			)
		)
		(property "Value" "GND"
			(at 162.56 187.96 0)
			(effects
				(font
					(size 1.27 1.27)
					(thickness 0.15)
				)
				(justify left)
			)
		)
		(property "Footprint" ""
			(at 168.91 194.31 0)
			(effects
				(font
					(size 1.27 1.27)
					(thickness 0.15)
				)
				(justify left bottom)
				(hide yes)
			)
		)
		(property "Datasheet" ""
			(at 168.91 199.39 0)
			(effects
				(font
					(size 1.27 1.27)
					(thickness 0.15)
				)
				(justify left bottom)
				(hide yes)
			)
		)
		(property "Description" ""
			(at 168.91 201.93 0)
			(effects
				(font
					(size 1.27 1.27)
				)
				(justify left bottom)
				(hide yes)
			)
		)
		(property "Author" "Antmicro"
			(at 168.91 194.31 0)
			(effects
				(font
					(size 1.27 1.27)
					(thickness 0.15)
				)
				(justify left bottom)
				(hide yes)
			)
		)
		(property "License" "Apache-2.0"
			(at 168.91 196.85 0)
			(effects
				(font
					(size 1.27 1.27)
					(thickness 0.15)
				)
				(justify left bottom)
				(hide yes)
			)
		)
		(pin "1"
		)
		(instances
			(project "sodimm-ddr5-tester"
				(path ""
					(reference "#PWR0335")
					(unit 1)
				)
			)
		)
	)
	(symbol
		(lib_id "antmicroFuses:F_4A_1206")
		(at 38.735 22.225 0)
		(unit 1)
		(exclude_from_sim no)
		(in_bom yes)
		(on_board yes)
		(dnp no)
		(property "Reference" "F1"
			(at 41.275 17.145 0)
			(effects
				(font
					(size 1.27 1.27)
					(thickness 0.15)
				)
			)
		)
		(property "Value" "F_4A_1206"
			(at 59.055 29.845 0)
			(effects
				(font
					(size 1.27 1.27)
					(thickness 0.15)
				)
				(justify left bottom)
				(hide yes)
			)
		)
		(property "Footprint" "antmicro-footprints:F_1206_3216Metric"
			(at 59.055 32.385 0)
			(effects
				(font
					(size 1.27 1.27)
					(thickness 0.15)
				)
				(justify left bottom)
				(hide yes)
			)
		)
		(property "Datasheet" "https://www.littelfuse.com/media?resourcetype=datasheets&itemid=dbe9bcd7-6072-4adf-bf5b-d33e52a6b90f&filename=littelfuse-fuse-466-datasheet"
			(at 59.055 34.925 0)
			(effects
				(font
					(size 1.27 1.27)
					(thickness 0.15)
				)
				(justify left bottom)
				(hide yes)
			)
		)
		(property "Description" ""
			(at 38.735 22.225 0)
			(effects
				(font
					(size 1.27 1.27)
				)
			)
		)
		(property "Manufacturer" "Littelfuse"
			(at 59.055 37.465 0)
			(effects
				(font
					(size 1.27 1.27)
					(thickness 0.15)
				)
				(justify left bottom)
				(hide yes)
			)
		)
		(property "MPN" "0466004.NR "
			(at 41.275 19.685 0)
			(effects
				(font
					(size 1.27 1.27)
					(thickness 0.15)
				)
			)
		)
		(property "Author" "Antmicro"
			(at 59.055 42.545 0)
			(effects
				(font
					(size 1.27 1.27)
					(thickness 0.15)
				)
				(justify left bottom)
				(hide yes)
			)
		)
		(property "License" "Apache-2.0"
			(at 59.055 45.085 0)
			(effects
				(font
					(size 1.27 1.27)
					(thickness 0.15)
				)
				(justify left bottom)
				(hide yes)
			)
		)
		(pin "2"
		)
		(pin "1"
		)
		(instances
			(project "sodimm-ddr5-tester"
				(path ""
					(reference "F1")
					(unit 1)
				)
			)
		)
	)
	(symbol
		(lib_id "antmicroResistors0402:R_0R_0402")
		(at 355.6 182.245 90)
		(unit 1)
		(exclude_from_sim no)
		(in_bom no)
		(on_board yes)
		(dnp yes)
		(property "Reference" "R156"
			(at 358.14 178.435 90)
			(effects
				(font
					(size 1.27 1.27)
				)
				(justify right)
			)
		)
		(property "Value" "R_0R_0402"
			(at 368.3 161.925 0)
			(effects
				(font
					(size 1.27 1.27)
					(thickness 0.15)
				)
				(justify left bottom)
				(hide yes)
			)
		)
		(property "Footprint" "antmicro-footprints:R_0402_1005Metric"
			(at 370.84 161.925 0)
			(effects
				(font
					(size 1.27 1.27)
					(thickness 0.15)
				)
				(justify left bottom)
				(hide yes)
			)
		)
		(property "Datasheet" "https://industrial.panasonic.com/cdbs/www-data/pdf/RDA0000/AOA0000C301.pdf"
			(at 373.38 161.925 0)
			(effects
				(font
					(size 1.27 1.27)
					(thickness 0.15)
				)
				(justify left bottom)
				(hide yes)
			)
		)
		(property "Description" ""
			(at 355.6 182.245 0)
			(effects
				(font
					(size 1.27 1.27)
				)
			)
		)
		(property "Manufacturer" "Panasonic"
			(at 378.46 161.925 0)
			(effects
				(font
					(size 1.27 1.27)
					(thickness 0.15)
				)
				(justify left bottom)
				(hide yes)
			)
		)
		(property "MPN" "ERJ2GE0R00X"
			(at 375.92 161.925 0)
			(effects
				(font
					(size 1.27 1.27)
					(thickness 0.15)
				)
				(justify left bottom)
				(hide yes)
			)
		)
		(property "Val" "0R"
			(at 358.14 180.975 90)
			(effects
				(font
					(size 1.27 1.27)
					(thickness 0.15)
				)
				(justify right)
			)
		)
		(property "License" "Apache-2.0"
			(at 381 161.925 0)
			(effects
				(font
					(size 1.27 1.27)
					(thickness 0.15)
				)
				(justify left bottom)
				(hide yes)
			)
		)
		(property "Author" "Antmicro"
			(at 383.54 161.925 0)
			(effects
				(font
					(size 1.27 1.27)
					(thickness 0.15)
				)
				(justify left bottom)
				(hide yes)
			)
		)
		(property "Tolerance" "~"
			(at 365.76 161.925 0)
			(effects
				(font
					(size 1.27 1.27)
				)
				(justify left bottom)
				(hide yes)
			)
		)
		(property "Current" "1A"
			(at 358.14 183.5149 90)
			(effects
				(font
					(size 1.27 1.27)
					(thickness 0.15)
				)
				(justify right)
				(hide yes)
			)
		)
		(pin "1"
		)
		(pin "2"
		)
		(instances
			(project "sodimm-ddr5-tester"
				(path ""
					(reference "R156")
					(unit 1)
				)
			)
		)
	)
	(symbol
		(lib_id "antmicroPMICPowerSequencers:LM3880")
		(at 366.395 42.545 0)
		(unit 1)
		(exclude_from_sim no)
		(in_bom yes)
		(on_board yes)
		(dnp no)
		(fields_autoplaced yes)
		(property "Reference" "U31"
			(at 368.4144 40.005 0)
			(effects
				(font
					(size 1.27 1.27)
				)
				(justify left)
			)
		)
		(property "Value" "LM3880"
			(at 368.4144 42.545 0)
			(effects
				(font
					(size 1.27 1.27)
				)
				(justify left)
			)
		)
		(property "Footprint" "antmicro-footprints:SOT-23-6"
			(at 382.905 48.895 0)
			(effects
				(font
					(size 1.27 1.27)
				)
				(hide yes)
			)
		)
		(property "Datasheet" "http://www.ti.com/lit/ds/symlink/lm3880.pdf"
			(at 390.525 50.8 0)
			(effects
				(font
					(size 1.27 1.27)
				)
				(hide yes)
			)
		)
		(property "Description" ""
			(at 366.395 42.545 0)
			(effects
				(font
					(size 1.27 1.27)
				)
			)
		)
		(property "Manufacturer" "Texas Instruments"
			(at 377.19 52.705 0)
			(effects
				(font
					(size 1.27 1.27)
				)
				(hide yes)
			)
		)
		(property "MPN" "LM3880MFX-1AA/NOPB"
			(at 380.365 54.61 0)
			(effects
				(font
					(size 1.27 1.27)
				)
				(hide yes)
			)
		)
		(property "Author" "Antmicro"
			(at 391.795 62.865 0)
			(effects
				(font
					(size 1.27 1.27)
					(thickness 0.15)
				)
				(justify left bottom)
				(hide yes)
			)
		)
		(property "License" "Apache-2.0"
			(at 391.795 65.405 0)
			(effects
				(font
					(size 1.27 1.27)
					(thickness 0.15)
				)
				(justify left bottom)
				(hide yes)
			)
		)
		(pin "1"
		)
		(pin "2"
		)
		(pin "3"
		)
		(pin "4"
		)
		(pin "5"
		)
		(pin "6"
		)
		(instances
			(project "sodimm-ddr5-tester"
				(path ""
					(reference "U31")
					(unit 1)
				)
			)
		)
	)
	(symbol
		(lib_id "antmicroTestPoints:TP_1mm_SMD")
		(at 229.87 278.13 0)
		(unit 1)
		(exclude_from_sim no)
		(in_bom yes)
		(on_board yes)
		(dnp no)
		(property "Reference" "TP65"
			(at 236.728 278.13 0)
			(effects
				(font
					(size 1.27 1.27)
				)
			)
		)
		(property "Value" "TP_1mm_SMD"
			(at 245.11 285.75 0)
			(effects
				(font
					(size 1.27 1.27)
					(thickness 0.15)
				)
				(justify left bottom)
				(hide yes)
			)
		)
		(property "Footprint" "antmicro-footprints:TP_SMD_1mm"
			(at 245.11 288.29 0)
			(effects
				(font
					(size 1.27 1.27)
					(thickness 0.15)
				)
				(justify left bottom)
				(hide yes)
			)
		)
		(property "Datasheet" ""
			(at 245.11 290.83 0)
			(effects
				(font
					(size 1.27 1.27)
					(thickness 0.15)
				)
				(justify left bottom)
				(hide yes)
			)
		)
		(property "Description" ""
			(at 229.87 278.13 0)
			(effects
				(font
					(size 1.27 1.27)
				)
			)
		)
		(property "MPN" ""
			(at 229.87 278.13 0)
			(effects
				(font
					(size 1.27 1.27)
				)
				(hide yes)
			)
		)
		(property "Manufacturer" ""
			(at 229.87 278.13 0)
			(effects
				(font
					(size 1.27 1.27)
				)
				(hide yes)
			)
		)
		(property "Author" "Antmicro"
			(at 245.11 293.37 0)
			(effects
				(font
					(size 1.27 1.27)
					(thickness 0.15)
				)
				(justify left bottom)
				(hide yes)
			)
		)
		(property "License" "Apache-2.0"
			(at 245.11 295.91 0)
			(effects
				(font
					(size 1.27 1.27)
					(thickness 0.15)
				)
				(justify left bottom)
				(hide yes)
			)
		)
		(pin "1"
		)
		(instances
			(project "sodimm-ddr5-tester"
				(path ""
					(reference "TP65")
					(unit 1)
				)
			)
		)
	)
	(symbol
		(lib_id "antmicroResistors0402:R_47k_0402")
		(at 209.55 44.45 270)
		(mirror x)
		(unit 1)
		(exclude_from_sim no)
		(in_bom yes)
		(on_board yes)
		(dnp no)
		(fields_autoplaced yes)
		(property "Reference" "R149"
			(at 207.899 41.0794 90)
			(effects
				(font
					(size 1.27 1.27)
				)
				(justify right)
			)
		)
		(property "Value" "R_47k_0402"
			(at 196.85 24.13 0)
			(effects
				(font
					(size 1.27 1.27)
					(thickness 0.15)
				)
				(justify left bottom)
				(hide yes)
			)
		)
		(property "Footprint" "antmicro-footprints:R_0402_1005Metric"
			(at 194.31 24.13 0)
			(effects
				(font
					(size 1.27 1.27)
					(thickness 0.15)
				)
				(justify left bottom)
				(hide yes)
			)
		)
		(property "Datasheet" "https://www.bourns.com/docs/product-datasheets/cr.pdf"
			(at 191.77 24.13 0)
			(effects
				(font
					(size 1.27 1.27)
					(thickness 0.15)
				)
				(justify left bottom)
				(hide yes)
			)
		)
		(property "Description" ""
			(at 209.55 44.45 0)
			(effects
				(font
					(size 1.27 1.27)
				)
			)
		)
		(property "Manufacturer" "Bourns"
			(at 186.69 24.13 0)
			(effects
				(font
					(size 1.27 1.27)
					(thickness 0.15)
				)
				(justify left bottom)
				(hide yes)
			)
		)
		(property "MPN" "CR0402-FX-4702GLF"
			(at 189.23 24.13 0)
			(effects
				(font
					(size 1.27 1.27)
					(thickness 0.15)
				)
				(justify left bottom)
				(hide yes)
			)
		)
		(property "Val" "47k"
			(at 207.899 43.6097 90)
			(effects
				(font
					(size 1.27 1.27)
					(thickness 0.15)
				)
				(justify right)
			)
		)
		(property "License" "Apache-2.0"
			(at 184.15 24.13 0)
			(effects
				(font
					(size 1.27 1.27)
					(thickness 0.15)
				)
				(justify left bottom)
				(hide yes)
			)
		)
		(property "Author" "Antmicro"
			(at 181.61 24.13 0)
			(effects
				(font
					(size 1.27 1.27)
					(thickness 0.15)
				)
				(justify left bottom)
				(hide yes)
			)
		)
		(property "Tolerance" "1%"
			(at 199.39 24.13 0)
			(effects
				(font
					(size 1.27 1.27)
				)
				(justify left bottom)
				(hide yes)
			)
		)
		(pin "1"
		)
		(pin "2"
		)
		(instances
			(project "sodimm-ddr5-tester"
				(path ""
					(reference "R149")
					(unit 1)
				)
			)
		)
	)
	(symbol
		(lib_id "antmicropower:GND")
		(at 85.725 137.16 0)
		(unit 1)
		(exclude_from_sim no)
		(in_bom yes)
		(on_board yes)
		(dnp no)
		(fields_autoplaced yes)
		(property "Reference" "#PWR0380"
			(at 85.725 143.51 0)
			(effects
				(font
					(size 1.27 1.27)
				)
				(hide yes)
			)
		)
		(property "Value" "GND"
			(at 87.63 138.43 0)
			(effects
				(font
					(size 1.27 1.27)
					(thickness 0.15)
				)
				(justify left)
			)
		)
		(property "Footprint" ""
			(at 94.615 144.78 0)
			(effects
				(font
					(size 1.27 1.27)
					(thickness 0.15)
				)
				(justify left bottom)
				(hide yes)
			)
		)
		(property "Datasheet" ""
			(at 94.615 149.86 0)
			(effects
				(font
					(size 1.27 1.27)
					(thickness 0.15)
				)
				(justify left bottom)
				(hide yes)
			)
		)
		(property "Description" ""
			(at 94.615 152.4 0)
			(effects
				(font
					(size 1.27 1.27)
				)
				(justify left bottom)
				(hide yes)
			)
		)
		(property "Author" "Antmicro"
			(at 94.615 144.78 0)
			(effects
				(font
					(size 1.27 1.27)
					(thickness 0.15)
				)
				(justify left bottom)
				(hide yes)
			)
		)
		(property "License" "Apache-2.0"
			(at 94.615 147.32 0)
			(effects
				(font
					(size 1.27 1.27)
					(thickness 0.15)
				)
				(justify left bottom)
				(hide yes)
			)
		)
		(pin "1"
		)
		(instances
			(project "sodimm-ddr5-tester"
				(path ""
					(reference "#PWR0380")
					(unit 1)
				)
			)
		)
	)
	(symbol
		(lib_id "antmicropower:VDC")
		(at 98.425 55.245 0)
		(unit 1)
		(exclude_from_sim no)
		(in_bom yes)
		(on_board yes)
		(dnp no)
		(property "Reference" "#PWR0300"
			(at 98.425 57.785 0)
			(effects
				(font
					(size 1.27 1.27)
				)
				(hide yes)
			)
		)
		(property "Value" "VDC"
			(at 98.425 51.435 0)
			(effects
				(font
					(size 1.27 1.27)
				)
			)
		)
		(property "Footprint" ""
			(at 98.425 55.245 0)
			(effects
				(font
					(size 1.27 1.27)
				)
				(hide yes)
			)
		)
		(property "Datasheet" ""
			(at 98.425 55.245 0)
			(effects
				(font
					(size 1.27 1.27)
				)
				(hide yes)
			)
		)
		(property "Description" ""
			(at 98.425 55.245 0)
			(effects
				(font
					(size 1.27 1.27)
				)
			)
		)
		(pin "1"
		)
		(instances
			(project "sodimm-ddr5-tester"
				(path ""
					(reference "#PWR0300")
					(unit 1)
				)
			)
		)
	)
	(symbol
		(lib_id "antmicropower:+3V3")
		(at 358.14 97.155 0)
		(unit 1)
		(exclude_from_sim no)
		(in_bom yes)
		(on_board yes)
		(dnp no)
		(fields_autoplaced yes)
		(property "Reference" "#PWR0386"
			(at 358.14 100.965 0)
			(effects
				(font
					(size 1.27 1.27)
				)
				(hide yes)
			)
		)
		(property "Value" "+3V3"
			(at 354.965 94.615 0)
			(effects
				(font
					(size 1.27 1.27)
					(thickness 0.15)
				)
				(justify left bottom)
			)
		)
		(property "Footprint" ""
			(at 373.38 104.775 0)
			(effects
				(font
					(size 1.27 1.27)
					(thickness 0.15)
				)
				(justify left bottom)
				(hide yes)
			)
		)
		(property "Datasheet" ""
			(at 373.38 107.315 0)
			(effects
				(font
					(size 1.27 1.27)
					(thickness 0.15)
				)
				(justify left bottom)
				(hide yes)
			)
		)
		(property "Description" ""
			(at 358.14 97.155 0)
			(effects
				(font
					(size 1.27 1.27)
				)
			)
		)
		(property "Author" "Antmicro"
			(at 373.38 99.695 0)
			(effects
				(font
					(size 1.27 1.27)
					(thickness 0.15)
				)
				(justify left bottom)
				(hide yes)
			)
		)
		(property "License" "Apache-2.0"
			(at 373.38 102.235 0)
			(effects
				(font
					(size 1.27 1.27)
					(thickness 0.15)
				)
				(justify left bottom)
				(hide yes)
			)
		)
		(pin "1"
		)
		(instances
			(project "sodimm-ddr5-tester"
				(path ""
					(reference "#PWR0386")
					(unit 1)
				)
			)
		)
	)
	(symbol
		(lib_id "antmicropower:+5V")
		(at 180.34 276.86 0)
		(unit 1)
		(exclude_from_sim no)
		(in_bom yes)
		(on_board yes)
		(dnp no)
		(property "Reference" "#PWR028"
			(at 180.34 280.67 0)
			(effects
				(font
					(size 1.27 1.27)
				)
				(hide yes)
			)
		)
		(property "Value" "+5V"
			(at 180.086 273.304 0)
			(effects
				(font
					(size 1.27 1.27)
					(thickness 0.15)
				)
			)
		)
		(property "Footprint" ""
			(at 195.58 284.48 0)
			(effects
				(font
					(size 1.27 1.27)
					(thickness 0.15)
				)
				(justify left bottom)
				(hide yes)
			)
		)
		(property "Datasheet" ""
			(at 195.58 287.02 0)
			(effects
				(font
					(size 1.27 1.27)
					(thickness 0.15)
				)
				(justify left bottom)
				(hide yes)
			)
		)
		(property "Description" ""
			(at 180.34 276.86 0)
			(effects
				(font
					(size 1.27 1.27)
				)
			)
		)
		(property "Author" "Antmicro"
			(at 195.58 284.48 0)
			(effects
				(font
					(size 1.27 1.27)
					(thickness 0.15)
				)
				(justify left bottom)
				(hide yes)
			)
		)
		(property "License" "Apache-2.0"
			(at 195.58 287.02 0)
			(effects
				(font
					(size 1.27 1.27)
					(thickness 0.15)
				)
				(justify left bottom)
				(hide yes)
			)
		)
		(pin "1"
		)
		(instances
			(project "sodimm-ddr5-tester"
				(path ""
					(reference "#PWR028")
					(unit 1)
				)
			)
		)
	)
	(symbol
		(lib_id "antmicroPMICVoltageRegulatorsLinear:NCP718BSN330T1G")
		(at 114.3 39.37 0)
		(unit 1)
		(exclude_from_sim no)
		(in_bom yes)
		(on_board yes)
		(dnp no)
		(property "Reference" "U21"
			(at 124.46 33.02 0)
			(effects
				(font
					(size 1.27 1.27)
				)
			)
		)
		(property "Value" "NCP718BSN330T1G"
			(at 124.46 35.56 0)
			(effects
				(font
					(size 1.27 1.27)
					(thickness 0.15)
				)
			)
		)
		(property "Footprint" "antmicro-footprints:SOT-23-5"
			(at 149.86 48.26 0)
			(effects
				(font
					(size 1.27 1.27)
					(thickness 0.15)
				)
				(justify left bottom)
				(hide yes)
			)
		)
		(property "Datasheet" "https://www.mouser.com/datasheet/2/308/NCP718_D-1224359.pdf"
			(at 149.86 50.8 0)
			(effects
				(font
					(size 1.27 1.27)
					(thickness 0.15)
				)
				(justify left bottom)
				(hide yes)
			)
		)
		(property "Description" ""
			(at 114.3 39.37 0)
			(effects
				(font
					(size 1.27 1.27)
				)
			)
		)
		(property "MPN" "NCP718BSN330T1G"
			(at 149.86 53.34 0)
			(effects
				(font
					(size 1.27 1.27)
					(thickness 0.15)
				)
				(justify left bottom)
				(hide yes)
			)
		)
		(property "Manufacturer" "ON Semiconductor"
			(at 149.86 55.88 0)
			(effects
				(font
					(size 1.27 1.27)
					(thickness 0.15)
				)
				(justify left bottom)
				(hide yes)
			)
		)
		(property "Author" "Antmicro"
			(at 149.86 58.42 0)
			(effects
				(font
					(size 1.27 1.27)
					(thickness 0.15)
				)
				(justify left bottom)
				(hide yes)
			)
		)
		(property "License" "Apache-2.0"
			(at 149.86 60.96 0)
			(effects
				(font
					(size 1.27 1.27)
					(thickness 0.15)
				)
				(justify left bottom)
				(hide yes)
			)
		)
		(pin "1"
		)
		(pin "2"
		)
		(pin "3"
		)
		(pin "4"
		)
		(pin "5"
		)
		(instances
			(project "sodimm-ddr5-tester"
				(path ""
					(reference "U21")
					(unit 1)
				)
			)
		)
	)
	(symbol
		(lib_id "antmicroPushbuttonSwitches:SW_KMR211NGLFS_SMD")
		(at 193.675 69.85 90)
		(unit 1)
		(exclude_from_sim no)
		(in_bom yes)
		(on_board yes)
		(dnp no)
		(fields_autoplaced yes)
		(property "Reference" "SW5"
			(at 197.231 63.9394 90)
			(effects
				(font
					(size 1.27 1.27)
					(thickness 0.15)
				)
				(justify right)
			)
		)
		(property "Value" "SW_KMR211NGLFS_SMD"
			(at 201.295 44.45 0)
			(effects
				(font
					(size 1.27 1.27)
					(thickness 0.15)
				)
				(justify left bottom)
				(hide yes)
			)
		)
		(property "Footprint" "antmicro-footprints:SW_KMR211NGLFS_SMD"
			(at 203.835 44.45 0)
			(effects
				(font
					(size 1.27 1.27)
					(thickness 0.15)
				)
				(justify left bottom)
				(hide yes)
			)
		)
		(property "Datasheet" "http://www.farnell.com/datasheets/2631211.pdf"
			(at 206.375 44.45 0)
			(effects
				(font
					(size 1.27 1.27)
					(thickness 0.15)
				)
				(justify left bottom)
				(hide yes)
			)
		)
		(property "Description" ""
			(at 193.675 69.85 0)
			(effects
				(font
					(size 1.27 1.27)
				)
			)
		)
		(property "MPN" "KMR211NGLFS"
			(at 197.231 66.4631 90)
			(effects
				(font
					(size 1.27 1.27)
					(thickness 0.15)
				)
				(justify right)
			)
		)
		(property "Manufacturer" "C&K"
			(at 208.915 44.45 0)
			(effects
				(font
					(size 1.27 1.27)
					(thickness 0.15)
				)
				(justify left bottom)
				(hide yes)
			)
		)
		(property "Author" "Antmicro"
			(at 211.455 44.45 0)
			(effects
				(font
					(size 1.27 1.27)
					(thickness 0.15)
				)
				(justify left bottom)
				(hide yes)
			)
		)
		(property "License" "Apache-2.0"
			(at 213.995 44.45 0)
			(effects
				(font
					(size 1.27 1.27)
					(thickness 0.15)
				)
				(justify left bottom)
				(hide yes)
			)
		)
		(pin "1"
		)
		(pin "2"
		)
		(pin "3"
		)
		(pin "4"
		)
		(instances
			(project "sodimm-ddr5-tester"
				(path ""
					(reference "SW5")
					(unit 1)
				)
			)
		)
	)
	(symbol
		(lib_id "antmicropower:GND")
		(at 353.06 133.985 0)
		(unit 1)
		(exclude_from_sim no)
		(in_bom yes)
		(on_board yes)
		(dnp no)
		(fields_autoplaced yes)
		(property "Reference" "#PWR0385"
			(at 353.06 140.335 0)
			(effects
				(font
					(size 1.27 1.27)
				)
				(hide yes)
			)
		)
		(property "Value" "GND"
			(at 355.6 135.255 0)
			(effects
				(font
					(size 1.27 1.27)
					(thickness 0.15)
				)
				(justify left)
			)
		)
		(property "Footprint" ""
			(at 361.95 141.605 0)
			(effects
				(font
					(size 1.27 1.27)
					(thickness 0.15)
				)
				(justify left bottom)
				(hide yes)
			)
		)
		(property "Datasheet" ""
			(at 361.95 146.685 0)
			(effects
				(font
					(size 1.27 1.27)
					(thickness 0.15)
				)
				(justify left bottom)
				(hide yes)
			)
		)
		(property "Description" ""
			(at 361.95 149.225 0)
			(effects
				(font
					(size 1.27 1.27)
				)
				(justify left bottom)
				(hide yes)
			)
		)
		(property "Author" "Antmicro"
			(at 361.95 141.605 0)
			(effects
				(font
					(size 1.27 1.27)
					(thickness 0.15)
				)
				(justify left bottom)
				(hide yes)
			)
		)
		(property "License" "Apache-2.0"
			(at 361.95 144.145 0)
			(effects
				(font
					(size 1.27 1.27)
					(thickness 0.15)
				)
				(justify left bottom)
				(hide yes)
			)
		)
		(pin "1"
		)
		(instances
			(project "sodimm-ddr5-tester"
				(path ""
					(reference "#PWR0385")
					(unit 1)
				)
			)
		)
	)
	(symbol
		(lib_id "antmicropower:GND")
		(at 285.75 208.915 0)
		(unit 1)
		(exclude_from_sim no)
		(in_bom yes)
		(on_board yes)
		(dnp no)
		(fields_autoplaced yes)
		(property "Reference" "#PWR0310"
			(at 285.75 215.265 0)
			(effects
				(font
					(size 1.27 1.27)
				)
				(hide yes)
			)
		)
		(property "Value" "GND"
			(at 288.29 210.185 0)
			(effects
				(font
					(size 1.27 1.27)
					(thickness 0.15)
				)
				(justify left)
			)
		)
		(property "Footprint" ""
			(at 294.64 216.535 0)
			(effects
				(font
					(size 1.27 1.27)
					(thickness 0.15)
				)
				(justify left bottom)
				(hide yes)
			)
		)
		(property "Datasheet" ""
			(at 294.64 221.615 0)
			(effects
				(font
					(size 1.27 1.27)
					(thickness 0.15)
				)
				(justify left bottom)
				(hide yes)
			)
		)
		(property "Description" ""
			(at 294.64 224.155 0)
			(effects
				(font
					(size 1.27 1.27)
				)
				(justify left bottom)
				(hide yes)
			)
		)
		(property "Author" "Antmicro"
			(at 294.64 216.535 0)
			(effects
				(font
					(size 1.27 1.27)
					(thickness 0.15)
				)
				(justify left bottom)
				(hide yes)
			)
		)
		(property "License" "Apache-2.0"
			(at 294.64 219.075 0)
			(effects
				(font
					(size 1.27 1.27)
					(thickness 0.15)
				)
				(justify left bottom)
				(hide yes)
			)
		)
		(pin "1"
		)
		(instances
			(project "sodimm-ddr5-tester"
				(path ""
					(reference "#PWR0310")
					(unit 1)
				)
			)
		)
	)
	(symbol
		(lib_id "antmicropower:+1V2")
		(at 325.755 211.455 0)
		(unit 1)
		(exclude_from_sim no)
		(in_bom yes)
		(on_board yes)
		(dnp no)
		(property "Reference" "#PWR0326"
			(at 325.755 215.265 0)
			(effects
				(font
					(size 1.27 1.27)
				)
				(hide yes)
			)
		)
		(property "Value" "+1V2"
			(at 325.755 207.899 0)
			(effects
				(font
					(size 1.27 1.27)
				)
			)
		)
		(property "Footprint" ""
			(at 325.755 211.455 0)
			(effects
				(font
					(size 1.27 1.27)
				)
				(hide yes)
			)
		)
		(property "Datasheet" ""
			(at 325.755 211.455 0)
			(effects
				(font
					(size 1.27 1.27)
				)
				(hide yes)
			)
		)
		(property "Description" ""
			(at 325.755 211.455 0)
			(effects
				(font
					(size 1.27 1.27)
				)
			)
		)
		(pin "1"
		)
		(instances
			(project "sodimm-ddr5-tester"
				(path ""
					(reference "#PWR0326")
					(unit 1)
				)
			)
		)
	)
	(symbol
		(lib_id "antmicropower:GND")
		(at 364.49 125.73 0)
		(unit 1)
		(exclude_from_sim no)
		(in_bom yes)
		(on_board yes)
		(dnp no)
		(fields_autoplaced yes)
		(property "Reference" "#PWR0388"
			(at 364.49 132.08 0)
			(effects
				(font
					(size 1.27 1.27)
				)
				(hide yes)
			)
		)
		(property "Value" "GND"
			(at 367.03 127 0)
			(effects
				(font
					(size 1.27 1.27)
					(thickness 0.15)
				)
				(justify left)
			)
		)
		(property "Footprint" ""
			(at 373.38 133.35 0)
			(effects
				(font
					(size 1.27 1.27)
					(thickness 0.15)
				)
				(justify left bottom)
				(hide yes)
			)
		)
		(property "Datasheet" ""
			(at 373.38 138.43 0)
			(effects
				(font
					(size 1.27 1.27)
					(thickness 0.15)
				)
				(justify left bottom)
				(hide yes)
			)
		)
		(property "Description" ""
			(at 373.38 140.97 0)
			(effects
				(font
					(size 1.27 1.27)
				)
				(justify left bottom)
				(hide yes)
			)
		)
		(property "Author" "Antmicro"
			(at 373.38 133.35 0)
			(effects
				(font
					(size 1.27 1.27)
					(thickness 0.15)
				)
				(justify left bottom)
				(hide yes)
			)
		)
		(property "License" "Apache-2.0"
			(at 373.38 135.89 0)
			(effects
				(font
					(size 1.27 1.27)
					(thickness 0.15)
				)
				(justify left bottom)
				(hide yes)
			)
		)
		(pin "1"
		)
		(instances
			(project "sodimm-ddr5-tester"
				(path ""
					(reference "#PWR0388")
					(unit 1)
				)
			)
		)
	)
	(symbol
		(lib_id "antmicropower:GND")
		(at 286.893 40.005 0)
		(mirror y)
		(unit 1)
		(exclude_from_sim no)
		(in_bom yes)
		(on_board yes)
		(dnp no)
		(fields_autoplaced yes)
		(property "Reference" "#PWR0369"
			(at 286.893 46.355 0)
			(effects
				(font
					(size 1.27 1.27)
				)
				(hide yes)
			)
		)
		(property "Value" "GND"
			(at 289.56 41.275 0)
			(effects
				(font
					(size 1.27 1.27)
					(thickness 0.15)
				)
				(justify right)
			)
		)
		(property "Footprint" ""
			(at 278.003 47.625 0)
			(effects
				(font
					(size 1.27 1.27)
					(thickness 0.15)
				)
				(justify left bottom)
				(hide yes)
			)
		)
		(property "Datasheet" ""
			(at 278.003 52.705 0)
			(effects
				(font
					(size 1.27 1.27)
					(thickness 0.15)
				)
				(justify left bottom)
				(hide yes)
			)
		)
		(property "Description" ""
			(at 278.003 55.245 0)
			(effects
				(font
					(size 1.27 1.27)
				)
				(justify left bottom)
				(hide yes)
			)
		)
		(property "Author" "Antmicro"
			(at 278.003 47.625 0)
			(effects
				(font
					(size 1.27 1.27)
					(thickness 0.15)
				)
				(justify left bottom)
				(hide yes)
			)
		)
		(property "License" "Apache-2.0"
			(at 278.003 50.165 0)
			(effects
				(font
					(size 1.27 1.27)
					(thickness 0.15)
				)
				(justify left bottom)
				(hide yes)
			)
		)
		(pin "1"
		)
		(instances
			(project "sodimm-ddr5-tester"
				(path ""
					(reference "#PWR0369")
					(unit 1)
				)
			)
		)
	)
	(symbol
		(lib_id "antmicroTestPoints:TP_1mm_SMD")
		(at 147.955 39.37 0)
		(unit 1)
		(exclude_from_sim no)
		(in_bom yes)
		(on_board yes)
		(dnp no)
		(property "Reference" "TP19"
			(at 149.225 41.275 0)
			(effects
				(font
					(size 1.27 1.27)
				)
				(justify left)
			)
		)
		(property "Value" "TP_1mm_SMD"
			(at 163.195 46.99 0)
			(effects
				(font
					(size 1.27 1.27)
					(thickness 0.15)
				)
				(justify left bottom)
				(hide yes)
			)
		)
		(property "Footprint" "antmicro-footprints:TP_SMD_1mm"
			(at 163.195 49.53 0)
			(effects
				(font
					(size 1.27 1.27)
					(thickness 0.15)
				)
				(justify left bottom)
				(hide yes)
			)
		)
		(property "Datasheet" ""
			(at 163.195 52.07 0)
			(effects
				(font
					(size 1.27 1.27)
					(thickness 0.15)
				)
				(justify left bottom)
				(hide yes)
			)
		)
		(property "Description" ""
			(at 147.955 39.37 0)
			(effects
				(font
					(size 1.27 1.27)
				)
			)
		)
		(property "MPN" ""
			(at 147.955 39.37 0)
			(effects
				(font
					(size 1.27 1.27)
				)
				(hide yes)
			)
		)
		(property "Manufacturer" ""
			(at 147.955 39.37 0)
			(effects
				(font
					(size 1.27 1.27)
				)
				(hide yes)
			)
		)
		(property "Author" "Antmicro"
			(at 163.195 54.61 0)
			(effects
				(font
					(size 1.27 1.27)
					(thickness 0.15)
				)
				(justify left bottom)
				(hide yes)
			)
		)
		(property "License" "Apache-2.0"
			(at 163.195 57.15 0)
			(effects
				(font
					(size 1.27 1.27)
					(thickness 0.15)
				)
				(justify left bottom)
				(hide yes)
			)
		)
		(pin "1"
		)
		(instances
			(project "sodimm-ddr5-tester"
				(path ""
					(reference "TP19")
					(unit 1)
				)
			)
		)
	)
	(symbol
		(lib_id "antmicroPMICVoltageRegulatorsDCDCSwitchingRegulators:MPM54304GMN")
		(at 237.49 174.625 0)
		(unit 1)
		(exclude_from_sim no)
		(in_bom yes)
		(on_board yes)
		(dnp no)
		(fields_autoplaced yes)
		(property "Reference" "U20"
			(at 251.46 167.13 0)
			(effects
				(font
					(size 1.27 1.27)
					(thickness 0.15)
				)
			)
		)
		(property "Value" "MPM54304GMN"
			(at 251.46 169.6537 0)
			(effects
				(font
					(size 1.27 1.27)
					(thickness 0.15)
				)
			)
		)
		(property "Footprint" "antmicro-footprints:LGA-33_7x7mm_P0.65mm"
			(at 284.48 182.245 0)
			(effects
				(font
					(size 1.27 1.27)
					(thickness 0.15)
				)
				(justify left bottom)
				(hide yes)
			)
		)
		(property "Datasheet" "https://www.monolithicpower.com/en/documentview/productdocument/index/version/2/document_type/Datasheet/lang/en/sku/MPM54304/document_id/4982/"
			(at 284.48 184.785 0)
			(effects
				(font
					(size 1.27 1.27)
					(thickness 0.15)
				)
				(justify left bottom)
				(hide yes)
			)
		)
		(property "Description" ""
			(at 237.49 174.625 0)
			(effects
				(font
					(size 1.27 1.27)
				)
			)
		)
		(property "MPN" "MPM54304GMN-0000"
			(at 284.48 187.325 0)
			(effects
				(font
					(size 1.27 1.27)
					(thickness 0.15)
				)
				(justify left bottom)
				(hide yes)
			)
		)
		(property "Manufacturer" "Monolithic Power Systems"
			(at 284.48 189.865 0)
			(effects
				(font
					(size 1.27 1.27)
					(thickness 0.15)
				)
				(justify left bottom)
				(hide yes)
			)
		)
		(property "Author" "Antmicro"
			(at 284.48 192.405 0)
			(effects
				(font
					(size 1.27 1.27)
					(thickness 0.15)
				)
				(justify left bottom)
				(hide yes)
			)
		)
		(property "License" "Apache-2.0"
			(at 284.48 194.945 0)
			(effects
				(font
					(size 1.27 1.27)
					(thickness 0.15)
				)
				(justify left bottom)
				(hide yes)
			)
		)
		(pin "1"
		)
		(pin "10"
		)
		(pin "11"
		)
		(pin "12"
		)
		(pin "13"
		)
		(pin "14"
		)
		(pin "15"
		)
		(pin "16"
		)
		(pin "17"
		)
		(pin "18"
		)
		(pin "19"
		)
		(pin "2"
		)
		(pin "20"
		)
		(pin "21"
		)
		(pin "22"
		)
		(pin "23"
		)
		(pin "24"
		)
		(pin "25"
		)
		(pin "26"
		)
		(pin "27"
		)
		(pin "28"
		)
		(pin "29"
		)
		(pin "3"
		)
		(pin "30"
		)
		(pin "31"
		)
		(pin "32"
		)
		(pin "33"
		)
		(pin "4"
		)
		(pin "5"
		)
		(pin "6"
		)
		(pin "7"
		)
		(pin "8"
		)
		(pin "9"
		)
		(instances
			(project "sodimm-ddr5-tester"
				(path ""
					(reference "U20")
					(unit 1)
				)
			)
		)
	)
	(symbol
		(lib_id "antmicropower:PWR_FLAG")
		(at 284.48 157.48 0)
		(unit 1)
		(exclude_from_sim no)
		(in_bom yes)
		(on_board yes)
		(dnp no)
		(fields_autoplaced yes)
		(property "Reference" "#FLG05"
			(at 284.48 155.575 0)
			(effects
				(font
					(size 1.27 1.27)
				)
				(hide yes)
			)
		)
		(property "Value" "PWR_FLAG"
			(at 284.48 153.67 0)
			(effects
				(font
					(size 1.27 1.27)
				)
			)
		)
		(property "Footprint" ""
			(at 284.48 157.48 0)
			(effects
				(font
					(size 1.27 1.27)
				)
				(hide yes)
			)
		)
		(property "Datasheet" ""
			(at 284.48 157.48 0)
			(effects
				(font
					(size 1.27 1.27)
				)
				(hide yes)
			)
		)
		(property "Description" ""
			(at 284.48 157.48 0)
			(effects
				(font
					(size 1.27 1.27)
				)
			)
		)
		(pin "1"
		)
		(instances
			(project "sodimm-ddr5-tester"
				(path ""
					(reference "#FLG05")
					(unit 1)
				)
			)
		)
	)
	(symbol
		(lib_id "antmicropower:+1V0_MGTAVCC")
		(at 130.81 153.035 0)
		(unit 1)
		(exclude_from_sim no)
		(in_bom yes)
		(on_board yes)
		(dnp no)
		(fields_autoplaced yes)
		(property "Reference" "#PWR0324"
			(at 130.81 156.845 0)
			(effects
				(font
					(size 1.27 1.27)
				)
				(hide yes)
			)
		)
		(property "Value" "+1V0_MGTAVCC"
			(at 130.81 149.225 0)
			(effects
				(font
					(size 1.27 1.27)
				)
			)
		)
		(property "Footprint" ""
			(at 130.81 153.035 0)
			(effects
				(font
					(size 1.27 1.27)
				)
				(hide yes)
			)
		)
		(property "Datasheet" ""
			(at 130.81 153.035 0)
			(effects
				(font
					(size 1.27 1.27)
				)
				(hide yes)
			)
		)
		(property "Description" ""
			(at 130.81 153.035 0)
			(effects
				(font
					(size 1.27 1.27)
				)
			)
		)
		(pin "1"
		)
		(instances
			(project "sodimm-ddr5-tester"
				(path ""
					(reference "#PWR0324")
					(unit 1)
				)
			)
		)
	)
	(symbol
		(lib_id "antmicropower:GND")
		(at 248.285 262.255 0)
		(unit 1)
		(exclude_from_sim no)
		(in_bom yes)
		(on_board yes)
		(dnp no)
		(property "Reference" "#PWR0365"
			(at 248.285 268.605 0)
			(effects
				(font
					(size 1.27 1.27)
				)
				(hide yes)
			)
		)
		(property "Value" "GND"
			(at 246.38 266.192 0)
			(effects
				(font
					(size 1.27 1.27)
					(thickness 0.15)
				)
				(justify left)
			)
		)
		(property "Footprint" ""
			(at 257.175 269.875 0)
			(effects
				(font
					(size 1.27 1.27)
					(thickness 0.15)
				)
				(justify left bottom)
				(hide yes)
			)
		)
		(property "Datasheet" ""
			(at 257.175 274.955 0)
			(effects
				(font
					(size 1.27 1.27)
					(thickness 0.15)
				)
				(justify left bottom)
				(hide yes)
			)
		)
		(property "Description" ""
			(at 257.175 277.495 0)
			(effects
				(font
					(size 1.27 1.27)
				)
				(justify left bottom)
				(hide yes)
			)
		)
		(property "Author" "Antmicro"
			(at 257.175 269.875 0)
			(effects
				(font
					(size 1.27 1.27)
					(thickness 0.15)
				)
				(justify left bottom)
				(hide yes)
			)
		)
		(property "License" "Apache-2.0"
			(at 257.175 272.415 0)
			(effects
				(font
					(size 1.27 1.27)
					(thickness 0.15)
				)
				(justify left bottom)
				(hide yes)
			)
		)
		(pin "1"
		)
		(instances
			(project "sodimm-ddr5-tester"
				(path ""
					(reference "#PWR0365")
					(unit 1)
				)
			)
		)
	)
	(symbol
		(lib_id "antmicroTestPoints:TP_1mm_SMD")
		(at 248.92 281.94 0)
		(unit 1)
		(exclude_from_sim no)
		(in_bom yes)
		(on_board yes)
		(dnp no)
		(property "Reference" "TP62"
			(at 255.778 281.94 0)
			(effects
				(font
					(size 1.27 1.27)
				)
			)
		)
		(property "Value" "TP_1mm_SMD"
			(at 264.16 289.56 0)
			(effects
				(font
					(size 1.27 1.27)
					(thickness 0.15)
				)
				(justify left bottom)
				(hide yes)
			)
		)
		(property "Footprint" "antmicro-footprints:TP_SMD_1mm"
			(at 264.16 292.1 0)
			(effects
				(font
					(size 1.27 1.27)
					(thickness 0.15)
				)
				(justify left bottom)
				(hide yes)
			)
		)
		(property "Datasheet" ""
			(at 264.16 294.64 0)
			(effects
				(font
					(size 1.27 1.27)
					(thickness 0.15)
				)
				(justify left bottom)
				(hide yes)
			)
		)
		(property "Description" ""
			(at 248.92 281.94 0)
			(effects
				(font
					(size 1.27 1.27)
				)
			)
		)
		(property "MPN" ""
			(at 248.92 281.94 0)
			(effects
				(font
					(size 1.27 1.27)
				)
				(hide yes)
			)
		)
		(property "Manufacturer" ""
			(at 248.92 281.94 0)
			(effects
				(font
					(size 1.27 1.27)
				)
				(hide yes)
			)
		)
		(property "Author" "Antmicro"
			(at 264.16 297.18 0)
			(effects
				(font
					(size 1.27 1.27)
					(thickness 0.15)
				)
				(justify left bottom)
				(hide yes)
			)
		)
		(property "License" "Apache-2.0"
			(at 264.16 299.72 0)
			(effects
				(font
					(size 1.27 1.27)
					(thickness 0.15)
				)
				(justify left bottom)
				(hide yes)
			)
		)
		(pin "1"
		)
		(instances
			(project "sodimm-ddr5-tester"
				(path ""
					(reference "TP62")
					(unit 1)
				)
			)
		)
	)
	(symbol
		(lib_id "antmicropower:+1V8")
		(at 131.445 178.435 0)
		(unit 1)
		(exclude_from_sim no)
		(in_bom yes)
		(on_board yes)
		(dnp no)
		(fields_autoplaced yes)
		(property "Reference" "#PWR0321"
			(at 131.445 182.245 0)
			(effects
				(font
					(size 1.27 1.27)
				)
				(hide yes)
			)
		)
		(property "Value" "+1V8"
			(at 128.27 175.895 0)
			(effects
				(font
					(size 1.27 1.27)
					(thickness 0.15)
				)
				(justify left bottom)
			)
		)
		(property "Footprint" ""
			(at 146.685 186.055 0)
			(effects
				(font
					(size 1.27 1.27)
					(thickness 0.15)
				)
				(justify left bottom)
				(hide yes)
			)
		)
		(property "Datasheet" ""
			(at 146.685 188.595 0)
			(effects
				(font
					(size 1.27 1.27)
					(thickness 0.15)
				)
				(justify left bottom)
				(hide yes)
			)
		)
		(property "Description" ""
			(at 131.445 178.435 0)
			(effects
				(font
					(size 1.27 1.27)
				)
			)
		)
		(property "Author" "Antmicro"
			(at 146.685 183.515 0)
			(effects
				(font
					(size 1.27 1.27)
					(thickness 0.15)
				)
				(justify left bottom)
				(hide yes)
			)
		)
		(property "License" "Apache-2.0"
			(at 146.685 186.055 0)
			(effects
				(font
					(size 1.27 1.27)
					(thickness 0.15)
				)
				(justify left bottom)
				(hide yes)
			)
		)
		(pin "1"
		)
		(instances
			(project "sodimm-ddr5-tester"
				(path ""
					(reference "#PWR0321")
					(unit 1)
				)
			)
		)
	)
	(symbol
		(lib_id "antmicropower:PWR_FLAG")
		(at 139.065 38.735 0)
		(unit 1)
		(exclude_from_sim no)
		(in_bom yes)
		(on_board yes)
		(dnp no)
		(fields_autoplaced yes)
		(property "Reference" "#FLG0120"
			(at 139.065 36.83 0)
			(effects
				(font
					(size 1.27 1.27)
				)
				(hide yes)
			)
		)
		(property "Value" "PWR_FLAG"
			(at 139.065 35.1592 0)
			(effects
				(font
					(size 1.27 1.27)
				)
			)
		)
		(property "Footprint" ""
			(at 139.065 38.735 0)
			(effects
				(font
					(size 1.27 1.27)
				)
				(hide yes)
			)
		)
		(property "Datasheet" ""
			(at 139.065 38.735 0)
			(effects
				(font
					(size 1.27 1.27)
				)
				(hide yes)
			)
		)
		(property "Description" ""
			(at 139.065 38.735 0)
			(effects
				(font
					(size 1.27 1.27)
				)
			)
		)
		(pin "1"
		)
		(instances
			(project "sodimm-ddr5-tester"
				(path ""
					(reference "#FLG0120")
					(unit 1)
				)
			)
		)
	)
	(symbol
		(lib_id "antmicropower:+3V3_AON")
		(at 207.01 96.52 0)
		(mirror y)
		(unit 1)
		(exclude_from_sim no)
		(in_bom yes)
		(on_board yes)
		(dnp no)
		(property "Reference" "#PWR0297"
			(at 207.01 100.33 0)
			(effects
				(font
					(size 1.27 1.27)
				)
				(hide yes)
			)
		)
		(property "Value" "+3V3_AON"
			(at 212.725 93.345 0)
			(effects
				(font
					(size 1.27 1.27)
				)
			)
		)
		(property "Footprint" ""
			(at 207.01 96.52 0)
			(effects
				(font
					(size 1.27 1.27)
				)
				(hide yes)
			)
		)
		(property "Datasheet" ""
			(at 207.01 96.52 0)
			(effects
				(font
					(size 1.27 1.27)
				)
				(hide yes)
			)
		)
		(property "Description" ""
			(at 207.01 96.52 0)
			(effects
				(font
					(size 1.27 1.27)
				)
			)
		)
		(pin "1"
		)
		(instances
			(project "sodimm-ddr5-tester"
				(path ""
					(reference "#PWR0297")
					(unit 1)
				)
			)
		)
	)
	(symbol
		(lib_id "antmicroShuntsJumpers:Net-Tie_P0.127mm")
		(at 304.8 201.93 90)
		(unit 1)
		(exclude_from_sim no)
		(in_bom no)
		(on_board yes)
		(dnp no)
		(fields_autoplaced yes)
		(property "Reference" "NT7"
			(at 303.53 201.93 0)
			(effects
				(font
					(size 1.27 1.27)
				)
				(hide yes)
			)
		)
		(property "Value" "Net-Tie_P0.127mm"
			(at 312.42 180.34 0)
			(effects
				(font
					(size 1.27 1.27)
					(thickness 0.15)
				)
				(justify left bottom)
				(hide yes)
			)
		)
		(property "Footprint" "antmicro-footprints:NetTie-2_SMD_Pad0.127mm"
			(at 317.5 180.34 0)
			(effects
				(font
					(size 1.27 1.27)
					(thickness 0.15)
				)
				(justify left bottom)
				(hide yes)
			)
		)
		(property "Datasheet" ""
			(at 320.04 180.34 0)
			(effects
				(font
					(size 1.27 1.27)
					(thickness 0.15)
				)
				(justify left bottom)
				(hide yes)
			)
		)
		(property "Description" ""
			(at 304.8 201.93 0)
			(effects
				(font
					(size 1.27 1.27)
				)
			)
		)
		(property "MPN" ""
			(at 314.96 180.34 0)
			(effects
				(font
					(size 1.27 1.27)
					(thickness 0.15)
				)
				(justify left bottom)
			)
		)
		(property "Manufacturer" ""
			(at 322.58 180.34 0)
			(effects
				(font
					(size 1.27 1.27)
					(thickness 0.15)
				)
				(justify left bottom)
				(hide yes)
			)
		)
		(property "Author" "Antmicro"
			(at 325.12 180.34 0)
			(effects
				(font
					(size 1.27 1.27)
					(thickness 0.15)
				)
				(justify left bottom)
				(hide yes)
			)
		)
		(property "License" "Apache-2.0"
			(at 327.66 180.34 0)
			(effects
				(font
					(size 1.27 1.27)
					(thickness 0.15)
				)
				(justify left bottom)
				(hide yes)
			)
		)
		(pin "1"
		)
		(pin "2"
		)
		(instances
			(project "sodimm-ddr5-tester"
				(path ""
					(reference "NT7")
					(unit 1)
				)
			)
		)
	)
	(symbol
		(lib_id "antmicroTestPoints:TP_1206_SMD_RCW-0C")
		(at 339.09 243.205 0)
		(unit 1)
		(exclude_from_sim no)
		(in_bom yes)
		(on_board yes)
		(dnp no)
		(fields_autoplaced yes)
		(property "Reference" "TP21"
			(at 343.662 242.3744 0)
			(effects
				(font
					(size 1.27 1.27)
					(thickness 0.15)
				)
				(justify left)
			)
		)
		(property "Value" "TP_1206_SMD_RCW-0C"
			(at 343.662 244.8981 0)
			(effects
				(font
					(size 1.27 1.27)
					(thickness 0.15)
				)
				(justify left)
			)
		)
		(property "Footprint" "antmicro-footprints:TP_1206_SMD_RCW-0C"
			(at 356.87 253.365 0)
			(effects
				(font
					(size 1.27 1.27)
					(thickness 0.15)
				)
				(justify left bottom)
				(hide yes)
			)
		)
		(property "Datasheet" "https://www.te.com/commerce/DocumentDelivery/DDEController?Action=srchrtrv&DocNm=1773266&DocType=DS&DocLang=English"
			(at 356.87 255.905 0)
			(effects
				(font
					(size 1.27 1.27)
					(thickness 0.15)
				)
				(justify left bottom)
				(hide yes)
			)
		)
		(property "Description" ""
			(at 339.09 243.205 0)
			(effects
				(font
					(size 1.27 1.27)
				)
			)
		)
		(property "MPN" "RCW-0C"
			(at 356.87 258.445 0)
			(effects
				(font
					(size 1.27 1.27)
					(thickness 0.15)
				)
				(justify left bottom)
				(hide yes)
			)
		)
		(property "Manufacturer" "TE Connectivity"
			(at 356.87 260.985 0)
			(effects
				(font
					(size 1.27 1.27)
					(thickness 0.15)
				)
				(justify left bottom)
				(hide yes)
			)
		)
		(property "Author" "Antmicro"
			(at 356.87 263.525 0)
			(effects
				(font
					(size 1.27 1.27)
					(thickness 0.15)
				)
				(justify left bottom)
				(hide yes)
			)
		)
		(property "License" "Apache-2.0"
			(at 356.87 266.065 0)
			(effects
				(font
					(size 1.27 1.27)
					(thickness 0.15)
				)
				(justify left bottom)
				(hide yes)
			)
		)
		(pin "1"
		)
		(instances
			(project "sodimm-ddr5-tester"
				(path ""
					(reference "TP21")
					(unit 1)
				)
			)
		)
	)
	(symbol
		(lib_id "antmicroResistorsmisc:R_0R01_1206")
		(at 306.07 158.115 0)
		(unit 1)
		(exclude_from_sim no)
		(in_bom yes)
		(on_board yes)
		(dnp no)
		(property "Reference" "R145"
			(at 308.61 153.035 0)
			(effects
				(font
					(size 1.27 1.27)
				)
			)
		)
		(property "Value" "R_0R01_1206"
			(at 326.39 170.815 0)
			(effects
				(font
					(size 1.27 1.27)
					(thickness 0.15)
				)
				(justify left bottom)
				(hide yes)
			)
		)
		(property "Footprint" "antmicro-footprints:R_1206_3216Metric"
			(at 326.39 173.355 0)
			(effects
				(font
					(size 1.27 1.27)
					(thickness 0.15)
				)
				(justify left bottom)
				(hide yes)
			)
		)
		(property "Datasheet" "https://www.yageo.com/upload/media/product/productsearch/datasheet/rchip/PYu-RL_Group_521_RoHS_L_2.pdf"
			(at 326.39 175.895 0)
			(effects
				(font
					(size 1.27 1.27)
					(thickness 0.15)
				)
				(justify left bottom)
				(hide yes)
			)
		)
		(property "Description" ""
			(at 306.07 158.115 0)
			(effects
				(font
					(size 1.27 1.27)
				)
			)
		)
		(property "Manufacturer" "YAGEO"
			(at 326.39 180.975 0)
			(effects
				(font
					(size 1.27 1.27)
					(thickness 0.15)
				)
				(justify left bottom)
				(hide yes)
			)
		)
		(property "MPN" "RL1206FR-7W0R01L"
			(at 326.39 178.435 0)
			(effects
				(font
					(size 1.27 1.27)
					(thickness 0.15)
				)
				(justify left bottom)
				(hide yes)
			)
		)
		(property "Val" "0R01"
			(at 308.61 155.575 0)
			(effects
				(font
					(size 1.27 1.27)
					(thickness 0.15)
				)
			)
		)
		(property "License" "Apache-2.0"
			(at 326.39 183.515 0)
			(effects
				(font
					(size 1.27 1.27)
					(thickness 0.15)
				)
				(justify left bottom)
				(hide yes)
			)
		)
		(property "Author" "Antmicro"
			(at 326.39 186.055 0)
			(effects
				(font
					(size 1.27 1.27)
					(thickness 0.15)
				)
				(justify left bottom)
				(hide yes)
			)
		)
		(property "Tolerance" "1%"
			(at 326.39 168.275 0)
			(effects
				(font
					(size 1.27 1.27)
				)
				(justify left bottom)
				(hide yes)
			)
		)
		(pin "1"
		)
		(pin "2"
		)
		(instances
			(project "sodimm-ddr5-tester"
				(path ""
					(reference "R145")
					(unit 1)
				)
			)
		)
	)
	(symbol
		(lib_id "antmicroCapacitors0402:C_22n_0402")
		(at 85.725 135.89 90)
		(unit 1)
		(exclude_from_sim no)
		(in_bom yes)
		(on_board yes)
		(dnp no)
		(fields_autoplaced yes)
		(property "Reference" "C210"
			(at 88.9 132.0735 90)
			(effects
				(font
					(size 1.27 1.27)
				)
				(justify right)
			)
		)
		(property "Value" "C_22n_0402"
			(at 95.885 115.57 0)
			(effects
				(font
					(size 1.27 1.27)
					(thickness 0.15)
				)
				(justify left bottom)
				(hide yes)
			)
		)
		(property "Footprint" "antmicro-footprints:C_0402_1005Metric"
			(at 98.425 115.57 0)
			(effects
				(font
					(size 1.27 1.27)
					(thickness 0.15)
				)
				(justify left bottom)
				(hide yes)
			)
		)
		(property "Datasheet" "https://www.murata.com/products/productdetail?partno=GCM155R71H223MA55%23"
			(at 100.965 115.57 0)
			(effects
				(font
					(size 1.27 1.27)
					(thickness 0.15)
				)
				(justify left bottom)
				(hide yes)
			)
		)
		(property "Description" ""
			(at 85.725 135.89 0)
			(effects
				(font
					(size 1.27 1.27)
				)
			)
		)
		(property "Manufacturer" "Murata"
			(at 106.045 115.57 0)
			(effects
				(font
					(size 1.27 1.27)
					(thickness 0.15)
				)
				(justify left bottom)
				(hide yes)
			)
		)
		(property "MPN" "GCM155R71H223MA55D"
			(at 103.505 115.57 0)
			(effects
				(font
					(size 1.27 1.27)
					(thickness 0.15)
				)
				(justify left bottom)
				(hide yes)
			)
		)
		(property "Val" "22n"
			(at 88.9 134.6135 90)
			(effects
				(font
					(size 1.27 1.27)
					(thickness 0.15)
				)
				(justify right)
			)
		)
		(property "License" "Apache-2.0"
			(at 108.585 115.57 0)
			(effects
				(font
					(size 1.27 1.27)
					(thickness 0.15)
				)
				(justify left bottom)
				(hide yes)
			)
		)
		(property "Author" "Antmicro"
			(at 111.125 115.57 0)
			(effects
				(font
					(size 1.27 1.27)
					(thickness 0.15)
				)
				(justify left bottom)
				(hide yes)
			)
		)
		(property "Voltage" ""
			(at 113.665 115.57 0)
			(effects
				(font
					(size 1.27 1.27)
				)
				(justify left bottom)
				(hide yes)
			)
		)
		(property "Dielectric" ""
			(at 116.205 115.57 0)
			(effects
				(font
					(size 1.27 1.27)
				)
				(justify left bottom)
				(hide yes)
			)
		)
		(pin "1"
		)
		(pin "2"
		)
		(instances
			(project "sodimm-ddr5-tester"
				(path ""
					(reference "C210")
					(unit 1)
				)
			)
		)
	)
	(symbol
		(lib_id "antmicroResistors0402:R_0R_0402")
		(at 189.865 184.15 90)
		(unit 1)
		(exclude_from_sim no)
		(in_bom no)
		(on_board yes)
		(dnp yes)
		(property "Reference" "R163"
			(at 192.405 180.34 90)
			(effects
				(font
					(size 1.27 1.27)
				)
				(justify right)
			)
		)
		(property "Value" "R_0R_0402"
			(at 202.565 163.83 0)
			(effects
				(font
					(size 1.27 1.27)
					(thickness 0.15)
				)
				(justify left bottom)
				(hide yes)
			)
		)
		(property "Footprint" "antmicro-footprints:R_0402_1005Metric"
			(at 205.105 163.83 0)
			(effects
				(font
					(size 1.27 1.27)
					(thickness 0.15)
				)
				(justify left bottom)
				(hide yes)
			)
		)
		(property "Datasheet" "https://industrial.panasonic.com/cdbs/www-data/pdf/RDA0000/AOA0000C301.pdf"
			(at 207.645 163.83 0)
			(effects
				(font
					(size 1.27 1.27)
					(thickness 0.15)
				)
				(justify left bottom)
				(hide yes)
			)
		)
		(property "Description" ""
			(at 189.865 184.15 0)
			(effects
				(font
					(size 1.27 1.27)
				)
			)
		)
		(property "Manufacturer" "Panasonic"
			(at 212.725 163.83 0)
			(effects
				(font
					(size 1.27 1.27)
					(thickness 0.15)
				)
				(justify left bottom)
				(hide yes)
			)
		)
		(property "MPN" "ERJ2GE0R00X"
			(at 210.185 163.83 0)
			(effects
				(font
					(size 1.27 1.27)
					(thickness 0.15)
				)
				(justify left bottom)
				(hide yes)
			)
		)
		(property "Val" "0R"
			(at 192.405 182.88 90)
			(effects
				(font
					(size 1.27 1.27)
					(thickness 0.15)
				)
				(justify right)
			)
		)
		(property "License" "Apache-2.0"
			(at 215.265 163.83 0)
			(effects
				(font
					(size 1.27 1.27)
					(thickness 0.15)
				)
				(justify left bottom)
				(hide yes)
			)
		)
		(property "Author" "Antmicro"
			(at 217.805 163.83 0)
			(effects
				(font
					(size 1.27 1.27)
					(thickness 0.15)
				)
				(justify left bottom)
				(hide yes)
			)
		)
		(property "Tolerance" "~"
			(at 200.025 163.83 0)
			(effects
				(font
					(size 1.27 1.27)
				)
				(justify left bottom)
				(hide yes)
			)
		)
		(property "Current" "1A"
			(at 192.405 185.4199 90)
			(effects
				(font
					(size 1.27 1.27)
					(thickness 0.15)
				)
				(justify right)
				(hide yes)
			)
		)
		(pin "1"
		)
		(pin "2"
		)
		(instances
			(project "sodimm-ddr5-tester"
				(path ""
					(reference "R163")
					(unit 1)
				)
			)
		)
	)
	(symbol
		(lib_id "antmicroResistorsmisc:R_0R01_1206")
		(at 111.76 216.535 0)
		(unit 1)
		(exclude_from_sim no)
		(in_bom yes)
		(on_board yes)
		(dnp no)
		(property "Reference" "R144"
			(at 114.3 211.455 0)
			(effects
				(font
					(size 1.27 1.27)
				)
			)
		)
		(property "Value" "R_0R01_1206"
			(at 132.08 229.235 0)
			(effects
				(font
					(size 1.27 1.27)
					(thickness 0.15)
				)
				(justify left bottom)
				(hide yes)
			)
		)
		(property "Footprint" "antmicro-footprints:R_1206_3216Metric"
			(at 132.08 231.775 0)
			(effects
				(font
					(size 1.27 1.27)
					(thickness 0.15)
				)
				(justify left bottom)
				(hide yes)
			)
		)
		(property "Datasheet" "https://www.yageo.com/upload/media/product/productsearch/datasheet/rchip/PYu-RL_Group_521_RoHS_L_2.pdf"
			(at 132.08 234.315 0)
			(effects
				(font
					(size 1.27 1.27)
					(thickness 0.15)
				)
				(justify left bottom)
				(hide yes)
			)
		)
		(property "Description" ""
			(at 111.76 216.535 0)
			(effects
				(font
					(size 1.27 1.27)
				)
			)
		)
		(property "Manufacturer" "YAGEO"
			(at 132.08 239.395 0)
			(effects
				(font
					(size 1.27 1.27)
					(thickness 0.15)
				)
				(justify left bottom)
				(hide yes)
			)
		)
		(property "MPN" "RL1206FR-7W0R01L"
			(at 132.08 236.855 0)
			(effects
				(font
					(size 1.27 1.27)
					(thickness 0.15)
				)
				(justify left bottom)
				(hide yes)
			)
		)
		(property "Val" "0R01"
			(at 114.3 213.995 0)
			(effects
				(font
					(size 1.27 1.27)
					(thickness 0.15)
				)
			)
		)
		(property "License" "Apache-2.0"
			(at 132.08 241.935 0)
			(effects
				(font
					(size 1.27 1.27)
					(thickness 0.15)
				)
				(justify left bottom)
				(hide yes)
			)
		)
		(property "Author" "Antmicro"
			(at 132.08 244.475 0)
			(effects
				(font
					(size 1.27 1.27)
					(thickness 0.15)
				)
				(justify left bottom)
				(hide yes)
			)
		)
		(property "Tolerance" "1%"
			(at 132.08 226.695 0)
			(effects
				(font
					(size 1.27 1.27)
				)
				(justify left bottom)
				(hide yes)
			)
		)
		(pin "1"
		)
		(pin "2"
		)
		(instances
			(project "sodimm-ddr5-tester"
				(path ""
					(reference "R144")
					(unit 1)
				)
			)
		)
	)
	(symbol
		(lib_id "antmicropower:GND")
		(at 386.715 220.98 0)
		(unit 1)
		(exclude_from_sim no)
		(in_bom yes)
		(on_board yes)
		(dnp no)
		(fields_autoplaced yes)
		(property "Reference" "#PWR0346"
			(at 386.715 227.33 0)
			(effects
				(font
					(size 1.27 1.27)
				)
				(hide yes)
			)
		)
		(property "Value" "GND"
			(at 388.62 222.25 0)
			(effects
				(font
					(size 1.27 1.27)
					(thickness 0.15)
				)
				(justify left)
			)
		)
		(property "Footprint" ""
			(at 395.605 228.6 0)
			(effects
				(font
					(size 1.27 1.27)
					(thickness 0.15)
				)
				(justify left bottom)
				(hide yes)
			)
		)
		(property "Datasheet" ""
			(at 395.605 233.68 0)
			(effects
				(font
					(size 1.27 1.27)
					(thickness 0.15)
				)
				(justify left bottom)
				(hide yes)
			)
		)
		(property "Description" ""
			(at 395.605 236.22 0)
			(effects
				(font
					(size 1.27 1.27)
				)
				(justify left bottom)
				(hide yes)
			)
		)
		(property "Author" "Antmicro"
			(at 395.605 228.6 0)
			(effects
				(font
					(size 1.27 1.27)
					(thickness 0.15)
				)
				(justify left bottom)
				(hide yes)
			)
		)
		(property "License" "Apache-2.0"
			(at 395.605 231.14 0)
			(effects
				(font
					(size 1.27 1.27)
					(thickness 0.15)
				)
				(justify left bottom)
				(hide yes)
			)
		)
		(pin "1"
		)
		(instances
			(project "sodimm-ddr5-tester"
				(path ""
					(reference "#PWR0346")
					(unit 1)
				)
			)
		)
	)
	(symbol
		(lib_id "antmicropower:+1V1")
		(at 325.755 196.215 0)
		(unit 1)
		(exclude_from_sim no)
		(in_bom yes)
		(on_board yes)
		(dnp no)
		(property "Reference" "#PWR0322"
			(at 325.755 200.025 0)
			(effects
				(font
					(size 1.27 1.27)
				)
				(hide yes)
			)
		)
		(property "Value" "+1V1"
			(at 325.755 192.659 0)
			(effects
				(font
					(size 1.27 1.27)
				)
			)
		)
		(property "Footprint" ""
			(at 325.755 196.215 0)
			(effects
				(font
					(size 1.27 1.27)
				)
				(hide yes)
			)
		)
		(property "Datasheet" ""
			(at 325.755 196.215 0)
			(effects
				(font
					(size 1.27 1.27)
				)
				(hide yes)
			)
		)
		(property "Description" ""
			(at 325.755 196.215 0)
			(effects
				(font
					(size 1.27 1.27)
				)
			)
		)
		(pin "1"
		)
		(instances
			(project "sodimm-ddr5-tester"
				(path ""
					(reference "#PWR0322")
					(unit 1)
				)
			)
		)
	)
	(symbol
		(lib_id "antmicroResistors0402:R_0R_0402")
		(at 386.715 218.44 90)
		(unit 1)
		(exclude_from_sim no)
		(in_bom no)
		(on_board yes)
		(dnp yes)
		(property "Reference" "R169"
			(at 388.62 214.63 90)
			(effects
				(font
					(size 1.27 1.27)
				)
				(justify right)
			)
		)
		(property "Value" "R_0R_0402"
			(at 399.415 198.12 0)
			(effects
				(font
					(size 1.27 1.27)
					(thickness 0.15)
				)
				(justify left bottom)
				(hide yes)
			)
		)
		(property "Footprint" "antmicro-footprints:R_0402_1005Metric"
			(at 401.955 198.12 0)
			(effects
				(font
					(size 1.27 1.27)
					(thickness 0.15)
				)
				(justify left bottom)
				(hide yes)
			)
		)
		(property "Datasheet" "https://industrial.panasonic.com/cdbs/www-data/pdf/RDA0000/AOA0000C301.pdf"
			(at 404.495 198.12 0)
			(effects
				(font
					(size 1.27 1.27)
					(thickness 0.15)
				)
				(justify left bottom)
				(hide yes)
			)
		)
		(property "Description" ""
			(at 386.715 218.44 0)
			(effects
				(font
					(size 1.27 1.27)
				)
			)
		)
		(property "Manufacturer" "Panasonic"
			(at 409.575 198.12 0)
			(effects
				(font
					(size 1.27 1.27)
					(thickness 0.15)
				)
				(justify left bottom)
				(hide yes)
			)
		)
		(property "MPN" "ERJ2GE0R00X"
			(at 407.035 198.12 0)
			(effects
				(font
					(size 1.27 1.27)
					(thickness 0.15)
				)
				(justify left bottom)
				(hide yes)
			)
		)
		(property "Val" "0R"
			(at 388.62 217.17 90)
			(effects
				(font
					(size 1.27 1.27)
					(thickness 0.15)
				)
				(justify right)
			)
		)
		(property "License" "Apache-2.0"
			(at 412.115 198.12 0)
			(effects
				(font
					(size 1.27 1.27)
					(thickness 0.15)
				)
				(justify left bottom)
				(hide yes)
			)
		)
		(property "Author" "Antmicro"
			(at 414.655 198.12 0)
			(effects
				(font
					(size 1.27 1.27)
					(thickness 0.15)
				)
				(justify left bottom)
				(hide yes)
			)
		)
		(property "Tolerance" "~"
			(at 396.875 198.12 0)
			(effects
				(font
					(size 1.27 1.27)
				)
				(justify left bottom)
				(hide yes)
			)
		)
		(property "Current" "1A"
			(at 388.62 219.7099 90)
			(effects
				(font
					(size 1.27 1.27)
					(thickness 0.15)
				)
				(justify right)
				(hide yes)
			)
		)
		(pin "1"
		)
		(pin "2"
		)
		(instances
			(project "sodimm-ddr5-tester"
				(path ""
					(reference "R169")
					(unit 1)
				)
			)
		)
	)
	(symbol
		(lib_id "antmicroFuses:F_4A_1206")
		(at 47.625 55.245 0)
		(unit 1)
		(exclude_from_sim no)
		(in_bom yes)
		(on_board yes)
		(dnp no)
		(fields_autoplaced yes)
		(property "Reference" "F2"
			(at 50.165 51.435 0)
			(effects
				(font
					(size 1.27 1.27)
					(thickness 0.15)
				)
			)
		)
		(property "Value" "F_4A_1206"
			(at 67.945 62.865 0)
			(effects
				(font
					(size 1.27 1.27)
					(thickness 0.15)
				)
				(justify left bottom)
				(hide yes)
			)
		)
		(property "Footprint" "antmicro-footprints:F_1206_3216Metric"
			(at 67.945 65.405 0)
			(effects
				(font
					(size 1.27 1.27)
					(thickness 0.15)
				)
				(justify left bottom)
				(hide yes)
			)
		)
		(property "Datasheet" "https://www.littelfuse.com/media?resourcetype=datasheets&itemid=dbe9bcd7-6072-4adf-bf5b-d33e52a6b90f&filename=littelfuse-fuse-466-datasheet"
			(at 67.945 67.945 0)
			(effects
				(font
					(size 1.27 1.27)
					(thickness 0.15)
				)
				(justify left bottom)
				(hide yes)
			)
		)
		(property "Description" ""
			(at 47.625 55.245 0)
			(effects
				(font
					(size 1.27 1.27)
				)
			)
		)
		(property "Manufacturer" "Littelfuse"
			(at 67.945 70.485 0)
			(effects
				(font
					(size 1.27 1.27)
					(thickness 0.15)
				)
				(justify left bottom)
				(hide yes)
			)
		)
		(property "MPN" "0466004.NR "
			(at 50.165 53.975 0)
			(effects
				(font
					(size 1.27 1.27)
					(thickness 0.15)
				)
			)
		)
		(property "Author" "Antmicro"
			(at 67.945 75.565 0)
			(effects
				(font
					(size 1.27 1.27)
					(thickness 0.15)
				)
				(justify left bottom)
				(hide yes)
			)
		)
		(property "License" "Apache-2.0"
			(at 67.945 78.105 0)
			(effects
				(font
					(size 1.27 1.27)
					(thickness 0.15)
				)
				(justify left bottom)
				(hide yes)
			)
		)
		(pin "2"
		)
		(pin "1"
		)
		(instances
			(project "sodimm-ddr5-tester"
				(path ""
					(reference "F2")
					(unit 1)
				)
			)
		)
	)
	(symbol
		(lib_id "antmicroResistors0402:R_0R_0402")
		(at 386.715 172.085 90)
		(unit 1)
		(exclude_from_sim no)
		(in_bom yes)
		(on_board yes)
		(dnp no)
		(fields_autoplaced yes)
		(property "Reference" "R166"
			(at 388.62 168.2749 90)
			(effects
				(font
					(size 1.27 1.27)
				)
				(justify right)
			)
		)
		(property "Value" "R_0R_0402"
			(at 399.415 151.765 0)
			(effects
				(font
					(size 1.27 1.27)
					(thickness 0.15)
				)
				(justify left bottom)
				(hide yes)
			)
		)
		(property "Footprint" "antmicro-footprints:R_0402_1005Metric"
			(at 401.955 151.765 0)
			(effects
				(font
					(size 1.27 1.27)
					(thickness 0.15)
				)
				(justify left bottom)
				(hide yes)
			)
		)
		(property "Datasheet" "https://industrial.panasonic.com/cdbs/www-data/pdf/RDA0000/AOA0000C301.pdf"
			(at 404.495 151.765 0)
			(effects
				(font
					(size 1.27 1.27)
					(thickness 0.15)
				)
				(justify left bottom)
				(hide yes)
			)
		)
		(property "Description" ""
			(at 386.715 172.085 0)
			(effects
				(font
					(size 1.27 1.27)
				)
			)
		)
		(property "Manufacturer" "Panasonic"
			(at 409.575 151.765 0)
			(effects
				(font
					(size 1.27 1.27)
					(thickness 0.15)
				)
				(justify left bottom)
				(hide yes)
			)
		)
		(property "MPN" "ERJ2GE0R00X"
			(at 407.035 151.765 0)
			(effects
				(font
					(size 1.27 1.27)
					(thickness 0.15)
				)
				(justify left bottom)
				(hide yes)
			)
		)
		(property "Val" "0R"
			(at 388.62 170.8149 90)
			(effects
				(font
					(size 1.27 1.27)
					(thickness 0.15)
				)
				(justify right)
			)
		)
		(property "License" "Apache-2.0"
			(at 412.115 151.765 0)
			(effects
				(font
					(size 1.27 1.27)
					(thickness 0.15)
				)
				(justify left bottom)
				(hide yes)
			)
		)
		(property "Author" "Antmicro"
			(at 414.655 151.765 0)
			(effects
				(font
					(size 1.27 1.27)
					(thickness 0.15)
				)
				(justify left bottom)
				(hide yes)
			)
		)
		(property "Tolerance" "~"
			(at 396.875 151.765 0)
			(effects
				(font
					(size 1.27 1.27)
				)
				(justify left bottom)
				(hide yes)
			)
		)
		(property "Current" "1A"
			(at 388.62 172.0849 90)
			(effects
				(font
					(size 1.27 1.27)
					(thickness 0.15)
				)
				(justify right)
				(hide yes)
			)
		)
		(pin "1"
		)
		(pin "2"
		)
		(instances
			(project "sodimm-ddr5-tester"
				(path ""
					(reference "R166")
					(unit 1)
				)
			)
		)
	)
	(symbol
		(lib_id "antmicroResistors0402:R_10k_0402")
		(at 299.72 100.965 0)
		(unit 1)
		(exclude_from_sim no)
		(in_bom yes)
		(on_board yes)
		(dnp no)
		(property "Reference" "R173"
			(at 302.26 102.87 0)
			(effects
				(font
					(size 1.27 1.27)
				)
			)
		)
		(property "Value" "R_10k_0402"
			(at 320.04 113.665 0)
			(effects
				(font
					(size 1.27 1.27)
					(thickness 0.15)
				)
				(justify left bottom)
				(hide yes)
			)
		)
		(property "Footprint" "antmicro-footprints:R_0402_1005Metric"
			(at 320.04 116.205 0)
			(effects
				(font
					(size 1.27 1.27)
					(thickness 0.15)
				)
				(justify left bottom)
				(hide yes)
			)
		)
		(property "Datasheet" "https://www.bourns.com/docs/product-datasheets/cr.pdf"
			(at 320.04 118.745 0)
			(effects
				(font
					(size 1.27 1.27)
					(thickness 0.15)
				)
				(justify left bottom)
				(hide yes)
			)
		)
		(property "Description" ""
			(at 299.72 100.965 0)
			(effects
				(font
					(size 1.27 1.27)
				)
			)
		)
		(property "Manufacturer" "Bourns"
			(at 320.04 123.825 0)
			(effects
				(font
					(size 1.27 1.27)
					(thickness 0.15)
				)
				(justify left bottom)
				(hide yes)
			)
		)
		(property "MPN" "CR0402-FX-1002GLF"
			(at 320.04 121.285 0)
			(effects
				(font
					(size 1.27 1.27)
					(thickness 0.15)
				)
				(justify left bottom)
				(hide yes)
			)
		)
		(property "Val" "10k"
			(at 302.26 104.775 0)
			(effects
				(font
					(size 1.27 1.27)
					(thickness 0.15)
				)
			)
		)
		(property "License" "Apache-2.0"
			(at 320.04 126.365 0)
			(effects
				(font
					(size 1.27 1.27)
					(thickness 0.15)
				)
				(justify left bottom)
				(hide yes)
			)
		)
		(property "Author" "Antmicro"
			(at 320.04 128.905 0)
			(effects
				(font
					(size 1.27 1.27)
					(thickness 0.15)
				)
				(justify left bottom)
				(hide yes)
			)
		)
		(property "Tolerance" "1%"
			(at 320.04 111.125 0)
			(effects
				(font
					(size 1.27 1.27)
				)
				(justify left bottom)
				(hide yes)
			)
		)
		(pin "1"
		)
		(pin "2"
		)
		(instances
			(project "sodimm-ddr5-tester"
				(path ""
					(reference "R173")
					(unit 1)
				)
			)
		)
	)
	(symbol
		(lib_id "antmicroCapacitors0402:C_1u_0402")
		(at 21.59 184.15 90)
		(unit 1)
		(exclude_from_sim no)
		(in_bom yes)
		(on_board yes)
		(dnp no)
		(fields_autoplaced yes)
		(property "Reference" "C172"
			(at 24.13 180.3335 90)
			(effects
				(font
					(size 1.27 1.27)
				)
				(justify right)
			)
		)
		(property "Value" "C_1u_0402"
			(at 25.4 184.15 0)
			(effects
				(font
					(size 1.27 1.27)
				)
				(hide yes)
			)
		)
		(property "Footprint" "antmicro-footprints:C_0402_1005Metric"
			(at 16.51 179.07 0)
			(effects
				(font
					(size 1.27 1.27)
				)
				(justify left)
				(hide yes)
			)
		)
		(property "Datasheet" "https://product.tdk.com/en/search/capacitor/ceramic/mlcc/info?part_no=C1005X6S1A105K050BC"
			(at 21.59 184.15 0)
			(effects
				(font
					(size 1.27 1.27)
				)
				(hide yes)
			)
		)
		(property "Description" ""
			(at 21.59 184.15 0)
			(effects
				(font
					(size 1.27 1.27)
				)
			)
		)
		(property "Manufacturer" "TDK"
			(at 11.43 179.07 0)
			(effects
				(font
					(size 1.27 1.27)
				)
				(justify left)
				(hide yes)
			)
		)
		(property "MPN" "C1005X6S1A105K050BC"
			(at 13.97 179.07 0)
			(effects
				(font
					(size 1.27 1.27)
				)
				(justify left)
				(hide yes)
			)
		)
		(property "Val" "1u"
			(at 24.13 182.8735 90)
			(effects
				(font
					(size 1.27 1.27)
				)
				(justify right)
			)
		)
		(property "License" "Apache-2.0"
			(at 44.45 163.83 0)
			(effects
				(font
					(size 1.27 1.27)
					(thickness 0.15)
				)
				(justify left bottom)
				(hide yes)
			)
		)
		(property "Author" "Antmicro"
			(at 46.99 163.83 0)
			(effects
				(font
					(size 1.27 1.27)
					(thickness 0.15)
				)
				(justify left bottom)
				(hide yes)
			)
		)
		(property "Voltage" ""
			(at 49.53 163.83 0)
			(effects
				(font
					(size 1.27 1.27)
				)
				(justify left bottom)
				(hide yes)
			)
		)
		(property "Dielectric" ""
			(at 52.07 163.83 0)
			(effects
				(font
					(size 1.27 1.27)
				)
				(justify left bottom)
				(hide yes)
			)
		)
		(pin "1"
		)
		(pin "2"
		)
		(instances
			(project "sodimm-ddr5-tester"
				(path ""
					(reference "C172")
					(unit 1)
				)
			)
		)
	)
	(symbol
		(lib_id "antmicropower:GND")
		(at 238.76 251.46 0)
		(unit 1)
		(exclude_from_sim no)
		(in_bom yes)
		(on_board yes)
		(dnp no)
		(fields_autoplaced yes)
		(property "Reference" "#PWR0357"
			(at 238.76 257.81 0)
			(effects
				(font
					(size 1.27 1.27)
				)
				(hide yes)
			)
		)
		(property "Value" "GND"
			(at 240.665 252.73 0)
			(effects
				(font
					(size 1.27 1.27)
					(thickness 0.15)
				)
				(justify left)
			)
		)
		(property "Footprint" ""
			(at 247.65 259.08 0)
			(effects
				(font
					(size 1.27 1.27)
					(thickness 0.15)
				)
				(justify left bottom)
				(hide yes)
			)
		)
		(property "Datasheet" ""
			(at 247.65 264.16 0)
			(effects
				(font
					(size 1.27 1.27)
					(thickness 0.15)
				)
				(justify left bottom)
				(hide yes)
			)
		)
		(property "Description" ""
			(at 247.65 266.7 0)
			(effects
				(font
					(size 1.27 1.27)
				)
				(justify left bottom)
				(hide yes)
			)
		)
		(property "Author" "Antmicro"
			(at 247.65 259.08 0)
			(effects
				(font
					(size 1.27 1.27)
					(thickness 0.15)
				)
				(justify left bottom)
				(hide yes)
			)
		)
		(property "License" "Apache-2.0"
			(at 247.65 261.62 0)
			(effects
				(font
					(size 1.27 1.27)
					(thickness 0.15)
				)
				(justify left bottom)
				(hide yes)
			)
		)
		(pin "1"
		)
		(instances
			(project "sodimm-ddr5-tester"
				(path ""
					(reference "#PWR0357")
					(unit 1)
				)
			)
		)
	)
	(symbol
		(lib_id "antmicroCapacitors0603:C_22u_0603")
		(at 285.75 165.735 90)
		(unit 1)
		(exclude_from_sim no)
		(in_bom yes)
		(on_board yes)
		(dnp no)
		(property "Reference" "C190"
			(at 286.385 161.29 90)
			(effects
				(font
					(size 1.27 1.27)
				)
				(justify right)
			)
		)
		(property "Value" "C_22u_0603"
			(at 295.91 145.415 0)
			(effects
				(font
					(size 1.27 1.27)
					(thickness 0.15)
				)
				(justify left bottom)
				(hide yes)
			)
		)
		(property "Footprint" "antmicro-footprints:C_0603_1608Metric"
			(at 298.45 145.415 0)
			(effects
				(font
					(size 1.27 1.27)
					(thickness 0.15)
				)
				(justify left bottom)
				(hide yes)
			)
		)
		(property "Datasheet" "https://www.murata.com/products/productdetail?partno=GRM188R60J226MEA0%23"
			(at 300.99 145.415 0)
			(effects
				(font
					(size 1.27 1.27)
					(thickness 0.15)
				)
				(justify left bottom)
				(hide yes)
			)
		)
		(property "Description" ""
			(at 285.75 165.735 0)
			(effects
				(font
					(size 1.27 1.27)
				)
			)
		)
		(property "Manufacturer" "Murata"
			(at 306.07 145.415 0)
			(effects
				(font
					(size 1.27 1.27)
					(thickness 0.15)
				)
				(justify left bottom)
				(hide yes)
			)
		)
		(property "MPN" "GRM188R60J226MEA0D"
			(at 303.53 145.415 0)
			(effects
				(font
					(size 1.27 1.27)
					(thickness 0.15)
				)
				(justify left bottom)
				(hide yes)
			)
		)
		(property "Val" "22u"
			(at 286.385 165.1 90)
			(effects
				(font
					(size 1.27 1.27)
					(thickness 0.15)
				)
				(justify right)
			)
		)
		(property "License" "Apache-2.0"
			(at 308.61 145.415 0)
			(effects
				(font
					(size 1.27 1.27)
					(thickness 0.15)
				)
				(justify left bottom)
				(hide yes)
			)
		)
		(property "Author" "Antmicro"
			(at 311.15 145.415 0)
			(effects
				(font
					(size 1.27 1.27)
					(thickness 0.15)
				)
				(justify left bottom)
				(hide yes)
			)
		)
		(property "Voltage" ""
			(at 313.69 145.415 0)
			(effects
				(font
					(size 1.27 1.27)
				)
				(justify left bottom)
				(hide yes)
			)
		)
		(property "Dielectric" ""
			(at 316.23 145.415 0)
			(effects
				(font
					(size 1.27 1.27)
				)
				(justify left bottom)
				(hide yes)
			)
		)
		(pin "1"
		)
		(pin "2"
		)
		(instances
			(project "sodimm-ddr5-tester"
				(path ""
					(reference "C190")
					(unit 1)
				)
			)
		)
	)
	(symbol
		(lib_id "antmicropower:GND")
		(at 22.86 261.62 0)
		(unit 1)
		(exclude_from_sim no)
		(in_bom yes)
		(on_board yes)
		(dnp no)
		(fields_autoplaced yes)
		(property "Reference" "#PWR0374"
			(at 22.86 267.97 0)
			(effects
				(font
					(size 1.27 1.27)
				)
				(hide yes)
			)
		)
		(property "Value" "GND"
			(at 25.4 262.89 0)
			(effects
				(font
					(size 1.27 1.27)
					(thickness 0.15)
				)
				(justify left)
			)
		)
		(property "Footprint" ""
			(at 31.75 269.24 0)
			(effects
				(font
					(size 1.27 1.27)
					(thickness 0.15)
				)
				(justify left bottom)
				(hide yes)
			)
		)
		(property "Datasheet" ""
			(at 31.75 274.32 0)
			(effects
				(font
					(size 1.27 1.27)
					(thickness 0.15)
				)
				(justify left bottom)
				(hide yes)
			)
		)
		(property "Description" ""
			(at 31.75 276.86 0)
			(effects
				(font
					(size 1.27 1.27)
				)
				(justify left bottom)
				(hide yes)
			)
		)
		(property "Author" "Antmicro"
			(at 31.75 269.24 0)
			(effects
				(font
					(size 1.27 1.27)
					(thickness 0.15)
				)
				(justify left bottom)
				(hide yes)
			)
		)
		(property "License" "Apache-2.0"
			(at 31.75 271.78 0)
			(effects
				(font
					(size 1.27 1.27)
					(thickness 0.15)
				)
				(justify left bottom)
				(hide yes)
			)
		)
		(pin "1"
		)
		(instances
			(project "sodimm-ddr5-tester"
				(path ""
					(reference "#PWR0374")
					(unit 1)
				)
			)
		)
	)
	(symbol
		(lib_id "antmicropower:+3V3")
		(at 353.06 127.635 0)
		(unit 1)
		(exclude_from_sim no)
		(in_bom yes)
		(on_board yes)
		(dnp no)
		(fields_autoplaced yes)
		(property "Reference" "#PWR0384"
			(at 353.06 131.445 0)
			(effects
				(font
					(size 1.27 1.27)
				)
				(hide yes)
			)
		)
		(property "Value" "+3V3"
			(at 349.885 125.095 0)
			(effects
				(font
					(size 1.27 1.27)
					(thickness 0.15)
				)
				(justify left bottom)
			)
		)
		(property "Footprint" ""
			(at 368.3 135.255 0)
			(effects
				(font
					(size 1.27 1.27)
					(thickness 0.15)
				)
				(justify left bottom)
				(hide yes)
			)
		)
		(property "Datasheet" ""
			(at 368.3 137.795 0)
			(effects
				(font
					(size 1.27 1.27)
					(thickness 0.15)
				)
				(justify left bottom)
				(hide yes)
			)
		)
		(property "Description" ""
			(at 353.06 127.635 0)
			(effects
				(font
					(size 1.27 1.27)
				)
			)
		)
		(property "Author" "Antmicro"
			(at 368.3 130.175 0)
			(effects
				(font
					(size 1.27 1.27)
					(thickness 0.15)
				)
				(justify left bottom)
				(hide yes)
			)
		)
		(property "License" "Apache-2.0"
			(at 368.3 132.715 0)
			(effects
				(font
					(size 1.27 1.27)
					(thickness 0.15)
				)
				(justify left bottom)
				(hide yes)
			)
		)
		(pin "1"
		)
		(instances
			(project "sodimm-ddr5-tester"
				(path ""
					(reference "#PWR0384")
					(unit 1)
				)
			)
		)
	)
	(symbol
		(lib_id "antmicropower:PWR_FLAG")
		(at 58.42 64.135 0)
		(unit 1)
		(exclude_from_sim no)
		(in_bom yes)
		(on_board yes)
		(dnp no)
		(fields_autoplaced yes)
		(property "Reference" "#FLG0122"
			(at 58.42 62.23 0)
			(effects
				(font
					(size 1.27 1.27)
				)
				(hide yes)
			)
		)
		(property "Value" "PWR_FLAG"
			(at 58.42 60.5592 0)
			(effects
				(font
					(size 1.27 1.27)
				)
			)
		)
		(property "Footprint" ""
			(at 58.42 64.135 0)
			(effects
				(font
					(size 1.27 1.27)
				)
				(hide yes)
			)
		)
		(property "Datasheet" ""
			(at 58.42 64.135 0)
			(effects
				(font
					(size 1.27 1.27)
				)
				(hide yes)
			)
		)
		(property "Description" ""
			(at 58.42 64.135 0)
			(effects
				(font
					(size 1.27 1.27)
				)
			)
		)
		(pin "1"
		)
		(instances
			(project "sodimm-ddr5-tester"
				(path ""
					(reference "#FLG0122")
					(unit 1)
				)
			)
		)
	)
	(symbol
		(lib_id "antmicropower:+1V1")
		(at 160.02 276.86 0)
		(unit 1)
		(exclude_from_sim no)
		(in_bom yes)
		(on_board yes)
		(dnp no)
		(property "Reference" "#PWR026"
			(at 160.02 280.67 0)
			(effects
				(font
					(size 1.27 1.27)
				)
				(hide yes)
			)
		)
		(property "Value" "+1V1"
			(at 160.02 273.304 0)
			(effects
				(font
					(size 1.27 1.27)
				)
			)
		)
		(property "Footprint" ""
			(at 160.02 276.86 0)
			(effects
				(font
					(size 1.27 1.27)
				)
				(hide yes)
			)
		)
		(property "Datasheet" ""
			(at 160.02 276.86 0)
			(effects
				(font
					(size 1.27 1.27)
				)
				(hide yes)
			)
		)
		(property "Description" ""
			(at 160.02 276.86 0)
			(effects
				(font
					(size 1.27 1.27)
				)
			)
		)
		(pin "1"
		)
		(instances
			(project "sodimm-ddr5-tester"
				(path ""
					(reference "#PWR026")
					(unit 1)
				)
			)
		)
	)
	(symbol
		(lib_id "antmicroResistorsmisc:R_0R01_1206")
		(at 111.76 158.115 0)
		(unit 1)
		(exclude_from_sim no)
		(in_bom yes)
		(on_board yes)
		(dnp no)
		(property "Reference" "R141"
			(at 114.3 153.035 0)
			(effects
				(font
					(size 1.27 1.27)
				)
			)
		)
		(property "Value" "R_0R01_1206"
			(at 132.08 170.815 0)
			(effects
				(font
					(size 1.27 1.27)
					(thickness 0.15)
				)
				(justify left bottom)
				(hide yes)
			)
		)
		(property "Footprint" "antmicro-footprints:R_1206_3216Metric"
			(at 132.08 173.355 0)
			(effects
				(font
					(size 1.27 1.27)
					(thickness 0.15)
				)
				(justify left bottom)
				(hide yes)
			)
		)
		(property "Datasheet" "https://www.yageo.com/upload/media/product/productsearch/datasheet/rchip/PYu-RL_Group_521_RoHS_L_2.pdf"
			(at 132.08 175.895 0)
			(effects
				(font
					(size 1.27 1.27)
					(thickness 0.15)
				)
				(justify left bottom)
				(hide yes)
			)
		)
		(property "Description" ""
			(at 111.76 158.115 0)
			(effects
				(font
					(size 1.27 1.27)
				)
			)
		)
		(property "Manufacturer" "YAGEO"
			(at 132.08 180.975 0)
			(effects
				(font
					(size 1.27 1.27)
					(thickness 0.15)
				)
				(justify left bottom)
				(hide yes)
			)
		)
		(property "MPN" "RL1206FR-7W0R01L"
			(at 132.08 178.435 0)
			(effects
				(font
					(size 1.27 1.27)
					(thickness 0.15)
				)
				(justify left bottom)
				(hide yes)
			)
		)
		(property "Val" "0R01"
			(at 114.3 155.575 0)
			(effects
				(font
					(size 1.27 1.27)
					(thickness 0.15)
				)
			)
		)
		(property "License" "Apache-2.0"
			(at 132.08 183.515 0)
			(effects
				(font
					(size 1.27 1.27)
					(thickness 0.15)
				)
				(justify left bottom)
				(hide yes)
			)
		)
		(property "Author" "Antmicro"
			(at 132.08 186.055 0)
			(effects
				(font
					(size 1.27 1.27)
					(thickness 0.15)
				)
				(justify left bottom)
				(hide yes)
			)
		)
		(property "Tolerance" "1%"
			(at 132.08 168.275 0)
			(effects
				(font
					(size 1.27 1.27)
				)
				(justify left bottom)
				(hide yes)
			)
		)
		(pin "1"
		)
		(pin "2"
		)
		(instances
			(project "sodimm-ddr5-tester"
				(path ""
					(reference "R141")
					(unit 1)
				)
			)
		)
	)
	(symbol
		(lib_id "antmicroCapacitorsmisc:C_22u_25V_0805")
		(at 17.145 102.87 90)
		(unit 1)
		(exclude_from_sim no)
		(in_bom yes)
		(on_board yes)
		(dnp no)
		(property "Reference" "C200"
			(at 17.78 98.425 90)
			(effects
				(font
					(size 1.27 1.27)
				)
				(justify right)
			)
		)
		(property "Value" "C_22u_25V_0805"
			(at 27.305 82.55 0)
			(effects
				(font
					(size 1.27 1.27)
					(thickness 0.15)
				)
				(justify left bottom)
				(hide yes)
			)
		)
		(property "Footprint" "antmicro-footprints:C_0805_2012Metric"
			(at 29.845 82.55 0)
			(effects
				(font
					(size 1.27 1.27)
					(thickness 0.15)
				)
				(justify left bottom)
				(hide yes)
			)
		)
		(property "Datasheet" "https://product.samsungsem.com/mlcc/CL21A226MAYNNN.do"
			(at 32.385 82.55 0)
			(effects
				(font
					(size 1.27 1.27)
					(thickness 0.15)
				)
				(justify left bottom)
				(hide yes)
			)
		)
		(property "Description" ""
			(at 17.145 102.87 0)
			(effects
				(font
					(size 1.27 1.27)
				)
			)
		)
		(property "Manufacturer" "Samsung Electro-Mechanics"
			(at 37.465 82.55 0)
			(effects
				(font
					(size 1.27 1.27)
					(thickness 0.15)
				)
				(justify left bottom)
				(hide yes)
			)
		)
		(property "MPN" "CL21A226MAYNNNE"
			(at 34.925 82.55 0)
			(effects
				(font
					(size 1.27 1.27)
					(thickness 0.15)
				)
				(justify left bottom)
				(hide yes)
			)
		)
		(property "Val" "22u_25V"
			(at 17.78 102.235 90)
			(effects
				(font
					(size 1.27 1.27)
					(thickness 0.15)
				)
				(justify right)
			)
		)
		(property "License" "Apache-2.0"
			(at 40.005 82.55 0)
			(effects
				(font
					(size 1.27 1.27)
					(thickness 0.15)
				)
				(justify left bottom)
				(hide yes)
			)
		)
		(property "Author" "Antmicro"
			(at 42.545 82.55 0)
			(effects
				(font
					(size 1.27 1.27)
					(thickness 0.15)
				)
				(justify left bottom)
				(hide yes)
			)
		)
		(property "Voltage" ""
			(at 45.085 82.55 0)
			(effects
				(font
					(size 1.27 1.27)
				)
				(justify left bottom)
				(hide yes)
			)
		)
		(property "Dielectric" ""
			(at 47.625 82.55 0)
			(effects
				(font
					(size 1.27 1.27)
				)
				(justify left bottom)
				(hide yes)
			)
		)
		(pin "1"
		)
		(pin "2"
		)
		(instances
			(project "sodimm-ddr5-tester"
				(path ""
					(reference "C200")
					(unit 1)
				)
			)
		)
	)
	(symbol
		(lib_id "antmicroTestPoints:TP_1mm_SMD")
		(at 120.65 278.13 270)
		(unit 1)
		(exclude_from_sim no)
		(in_bom yes)
		(on_board yes)
		(dnp no)
		(property "Reference" "TP27"
			(at 120.65 283.1028 90)
			(effects
				(font
					(size 1.27 1.27)
				)
			)
		)
		(property "Value" "TP_1mm_SMD"
			(at 113.03 293.37 0)
			(effects
				(font
					(size 1.27 1.27)
					(thickness 0.15)
				)
				(justify left bottom)
				(hide yes)
			)
		)
		(property "Footprint" "antmicro-footprints:TP_SMD_1mm"
			(at 110.49 293.37 0)
			(effects
				(font
					(size 1.27 1.27)
					(thickness 0.15)
				)
				(justify left bottom)
				(hide yes)
			)
		)
		(property "Datasheet" ""
			(at 107.95 293.37 0)
			(effects
				(font
					(size 1.27 1.27)
					(thickness 0.15)
				)
				(justify left bottom)
				(hide yes)
			)
		)
		(property "Description" ""
			(at 120.65 278.13 0)
			(effects
				(font
					(size 1.27 1.27)
				)
			)
		)
		(property "MPN" ""
			(at 120.65 278.13 0)
			(effects
				(font
					(size 1.27 1.27)
				)
				(hide yes)
			)
		)
		(property "Manufacturer" ""
			(at 120.65 278.13 0)
			(effects
				(font
					(size 1.27 1.27)
				)
				(hide yes)
			)
		)
		(property "Author" "Antmicro"
			(at 105.41 293.37 0)
			(effects
				(font
					(size 1.27 1.27)
					(thickness 0.15)
				)
				(justify left bottom)
				(hide yes)
			)
		)
		(property "License" "Apache-2.0"
			(at 102.87 293.37 0)
			(effects
				(font
					(size 1.27 1.27)
					(thickness 0.15)
				)
				(justify left bottom)
				(hide yes)
			)
		)
		(pin "1"
		)
		(instances
			(project "sodimm-ddr5-tester"
				(path ""
					(reference "TP27")
					(unit 1)
				)
			)
		)
	)
	(symbol
		(lib_id "antmicropower:+3V3")
		(at 278.765 248.92 0)
		(unit 1)
		(exclude_from_sim no)
		(in_bom yes)
		(on_board yes)
		(dnp no)
		(fields_autoplaced yes)
		(property "Reference" "#PWR0285"
			(at 278.765 252.73 0)
			(effects
				(font
					(size 1.27 1.27)
				)
				(hide yes)
			)
		)
		(property "Value" "+3V3"
			(at 275.59 246.38 0)
			(effects
				(font
					(size 1.27 1.27)
					(thickness 0.15)
				)
				(justify left bottom)
			)
		)
		(property "Footprint" ""
			(at 294.005 256.54 0)
			(effects
				(font
					(size 1.27 1.27)
					(thickness 0.15)
				)
				(justify left bottom)
				(hide yes)
			)
		)
		(property "Datasheet" ""
			(at 294.005 259.08 0)
			(effects
				(font
					(size 1.27 1.27)
					(thickness 0.15)
				)
				(justify left bottom)
				(hide yes)
			)
		)
		(property "Description" ""
			(at 278.765 248.92 0)
			(effects
				(font
					(size 1.27 1.27)
				)
			)
		)
		(property "Author" "Antmicro"
			(at 294.005 251.46 0)
			(effects
				(font
					(size 1.27 1.27)
					(thickness 0.15)
				)
				(justify left bottom)
				(hide yes)
			)
		)
		(property "License" "Apache-2.0"
			(at 294.005 254 0)
			(effects
				(font
					(size 1.27 1.27)
					(thickness 0.15)
				)
				(justify left bottom)
				(hide yes)
			)
		)
		(pin "1"
		)
		(instances
			(project "sodimm-ddr5-tester"
				(path ""
					(reference "#PWR0285")
					(unit 1)
				)
			)
		)
	)
	(symbol
		(lib_id "antmicropower:PWR_FLAG")
		(at 58.42 31.115 0)
		(unit 1)
		(exclude_from_sim no)
		(in_bom yes)
		(on_board yes)
		(dnp no)
		(property "Reference" "#FLG0123"
			(at 58.42 29.21 0)
			(effects
				(font
					(size 1.27 1.27)
				)
				(hide yes)
			)
		)
		(property "Value" "PWR_FLAG"
			(at 58.42 27.5392 0)
			(effects
				(font
					(size 1.27 1.27)
				)
			)
		)
		(property "Footprint" ""
			(at 58.42 31.115 0)
			(effects
				(font
					(size 1.27 1.27)
				)
				(hide yes)
			)
		)
		(property "Datasheet" ""
			(at 58.42 31.115 0)
			(effects
				(font
					(size 1.27 1.27)
				)
				(hide yes)
			)
		)
		(property "Description" ""
			(at 58.42 31.115 0)
			(effects
				(font
					(size 1.27 1.27)
				)
			)
		)
		(pin "1"
		)
		(instances
			(project "sodimm-ddr5-tester"
				(path ""
					(reference "#FLG0123")
					(unit 1)
				)
			)
		)
	)
	(symbol
		(lib_id "antmicropower:+1V0")
		(at 144.145 98.425 0)
		(unit 1)
		(exclude_from_sim no)
		(in_bom yes)
		(on_board yes)
		(dnp no)
		(fields_autoplaced yes)
		(property "Reference" "#PWR0397"
			(at 144.145 102.235 0)
			(effects
				(font
					(size 1.27 1.27)
				)
				(hide yes)
			)
		)
		(property "Value" "+1V0"
			(at 144.145 94.869 0)
			(effects
				(font
					(size 1.27 1.27)
				)
			)
		)
		(property "Footprint" ""
			(at 144.145 98.425 0)
			(effects
				(font
					(size 1.27 1.27)
				)
				(hide yes)
			)
		)
		(property "Datasheet" ""
			(at 144.145 98.425 0)
			(effects
				(font
					(size 1.27 1.27)
				)
				(hide yes)
			)
		)
		(property "Description" ""
			(at 144.145 98.425 0)
			(effects
				(font
					(size 1.27 1.27)
				)
			)
		)
		(pin "1"
		)
		(instances
			(project "sodimm-ddr5-tester"
				(path ""
					(reference "#PWR0397")
					(unit 1)
				)
			)
		)
	)
	(symbol
		(lib_id "antmicropower:GND")
		(at 30.48 36.195 0)
		(unit 1)
		(exclude_from_sim no)
		(in_bom yes)
		(on_board yes)
		(dnp no)
		(fields_autoplaced yes)
		(property "Reference" "#PWR0283"
			(at 30.48 42.545 0)
			(effects
				(font
					(size 1.27 1.27)
				)
				(hide yes)
			)
		)
		(property "Value" "GND"
			(at 33.02 37.465 0)
			(effects
				(font
					(size 1.27 1.27)
					(thickness 0.15)
				)
				(justify left)
			)
		)
		(property "Footprint" ""
			(at 39.37 43.815 0)
			(effects
				(font
					(size 1.27 1.27)
					(thickness 0.15)
				)
				(justify left bottom)
				(hide yes)
			)
		)
		(property "Datasheet" ""
			(at 39.37 48.895 0)
			(effects
				(font
					(size 1.27 1.27)
					(thickness 0.15)
				)
				(justify left bottom)
				(hide yes)
			)
		)
		(property "Description" ""
			(at 39.37 51.435 0)
			(effects
				(font
					(size 1.27 1.27)
				)
				(justify left bottom)
				(hide yes)
			)
		)
		(property "Author" "Antmicro"
			(at 39.37 43.815 0)
			(effects
				(font
					(size 1.27 1.27)
					(thickness 0.15)
				)
				(justify left bottom)
				(hide yes)
			)
		)
		(property "License" "Apache-2.0"
			(at 39.37 46.355 0)
			(effects
				(font
					(size 1.27 1.27)
					(thickness 0.15)
				)
				(justify left bottom)
				(hide yes)
			)
		)
		(pin "1"
		)
		(instances
			(project "sodimm-ddr5-tester"
				(path ""
					(reference "#PWR0283")
					(unit 1)
				)
			)
		)
	)
	(symbol
		(lib_id "antmicroCapacitors0603:C_22u_0603")
		(at 86.995 205.105 90)
		(unit 1)
		(exclude_from_sim no)
		(in_bom yes)
		(on_board yes)
		(dnp no)
		(fields_autoplaced yes)
		(property "Reference" "C188"
			(at 89.3191 201.728 90)
			(effects
				(font
					(size 1.27 1.27)
				)
				(justify right)
			)
		)
		(property "Value" "C_22u_0603"
			(at 97.155 184.785 0)
			(effects
				(font
					(size 1.27 1.27)
					(thickness 0.15)
				)
				(justify left bottom)
				(hide yes)
			)
		)
		(property "Footprint" "antmicro-footprints:C_0603_1608Metric"
			(at 99.695 184.785 0)
			(effects
				(font
					(size 1.27 1.27)
					(thickness 0.15)
				)
				(justify left bottom)
				(hide yes)
			)
		)
		(property "Datasheet" "https://www.murata.com/products/productdetail?partno=GRM188R60J226MEA0%23"
			(at 102.235 184.785 0)
			(effects
				(font
					(size 1.27 1.27)
					(thickness 0.15)
				)
				(justify left bottom)
				(hide yes)
			)
		)
		(property "Description" ""
			(at 86.995 205.105 0)
			(effects
				(font
					(size 1.27 1.27)
				)
			)
		)
		(property "Manufacturer" "Murata"
			(at 107.315 184.785 0)
			(effects
				(font
					(size 1.27 1.27)
					(thickness 0.15)
				)
				(justify left bottom)
				(hide yes)
			)
		)
		(property "MPN" "GRM188R60J226MEA0D"
			(at 104.775 184.785 0)
			(effects
				(font
					(size 1.27 1.27)
					(thickness 0.15)
				)
				(justify left bottom)
				(hide yes)
			)
		)
		(property "Val" "22u"
			(at 89.3191 204.2583 90)
			(effects
				(font
					(size 1.27 1.27)
					(thickness 0.15)
				)
				(justify right)
			)
		)
		(property "License" "Apache-2.0"
			(at 109.855 184.785 0)
			(effects
				(font
					(size 1.27 1.27)
					(thickness 0.15)
				)
				(justify left bottom)
				(hide yes)
			)
		)
		(property "Author" "Antmicro"
			(at 112.395 184.785 0)
			(effects
				(font
					(size 1.27 1.27)
					(thickness 0.15)
				)
				(justify left bottom)
				(hide yes)
			)
		)
		(property "Voltage" ""
			(at 114.935 184.785 0)
			(effects
				(font
					(size 1.27 1.27)
				)
				(justify left bottom)
				(hide yes)
			)
		)
		(property "Dielectric" ""
			(at 117.475 184.785 0)
			(effects
				(font
					(size 1.27 1.27)
				)
				(justify left bottom)
				(hide yes)
			)
		)
		(pin "1"
		)
		(pin "2"
		)
		(instances
			(project "sodimm-ddr5-tester"
				(path ""
					(reference "C188")
					(unit 1)
				)
			)
		)
	)
	(symbol
		(lib_id "antmicropower:+5V")
		(at 227.965 240.665 0)
		(unit 1)
		(exclude_from_sim no)
		(in_bom yes)
		(on_board yes)
		(dnp no)
		(fields_autoplaced yes)
		(property "Reference" "#PWR0349"
			(at 227.965 244.475 0)
			(effects
				(font
					(size 1.27 1.27)
				)
				(hide yes)
			)
		)
		(property "Value" "+5V"
			(at 227.965 237.0906 0)
			(effects
				(font
					(size 1.27 1.27)
					(thickness 0.15)
				)
			)
		)
		(property "Footprint" ""
			(at 243.205 248.285 0)
			(effects
				(font
					(size 1.27 1.27)
					(thickness 0.15)
				)
				(justify left bottom)
				(hide yes)
			)
		)
		(property "Datasheet" ""
			(at 243.205 250.825 0)
			(effects
				(font
					(size 1.27 1.27)
					(thickness 0.15)
				)
				(justify left bottom)
				(hide yes)
			)
		)
		(property "Description" ""
			(at 227.965 240.665 0)
			(effects
				(font
					(size 1.27 1.27)
				)
			)
		)
		(property "Author" "Antmicro"
			(at 243.205 248.285 0)
			(effects
				(font
					(size 1.27 1.27)
					(thickness 0.15)
				)
				(justify left bottom)
				(hide yes)
			)
		)
		(property "License" "Apache-2.0"
			(at 243.205 250.825 0)
			(effects
				(font
					(size 1.27 1.27)
					(thickness 0.15)
				)
				(justify left bottom)
				(hide yes)
			)
		)
		(pin "1"
		)
		(instances
			(project "sodimm-ddr5-tester"
				(path ""
					(reference "#PWR0349")
					(unit 1)
				)
			)
		)
	)
	(symbol
		(lib_id "antmicroResistors0402:R_47k_0402")
		(at 256.54 59.69 90)
		(unit 1)
		(exclude_from_sim no)
		(in_bom yes)
		(on_board yes)
		(dnp no)
		(property "Reference" "R171"
			(at 255.27 55.88 90)
			(effects
				(font
					(size 1.27 1.27)
				)
				(justify left)
			)
		)
		(property "Value" "R_47k_0402"
			(at 269.24 39.37 0)
			(effects
				(font
					(size 1.27 1.27)
					(thickness 0.15)
				)
				(justify left bottom)
				(hide yes)
			)
		)
		(property "Footprint" "antmicro-footprints:R_0402_1005Metric"
			(at 271.78 39.37 0)
			(effects
				(font
					(size 1.27 1.27)
					(thickness 0.15)
				)
				(justify left bottom)
				(hide yes)
			)
		)
		(property "Datasheet" "https://www.bourns.com/docs/product-datasheets/cr.pdf"
			(at 274.32 39.37 0)
			(effects
				(font
					(size 1.27 1.27)
					(thickness 0.15)
				)
				(justify left bottom)
				(hide yes)
			)
		)
		(property "Description" ""
			(at 256.54 59.69 0)
			(effects
				(font
					(size 1.27 1.27)
				)
			)
		)
		(property "Manufacturer" "Bourns"
			(at 279.4 39.37 0)
			(effects
				(font
					(size 1.27 1.27)
					(thickness 0.15)
				)
				(justify left bottom)
				(hide yes)
			)
		)
		(property "MPN" "CR0402-FX-4702GLF"
			(at 276.86 39.37 0)
			(effects
				(font
					(size 1.27 1.27)
					(thickness 0.15)
				)
				(justify left bottom)
				(hide yes)
			)
		)
		(property "Val" "47k"
			(at 255.27 58.42 90)
			(effects
				(font
					(size 1.27 1.27)
					(thickness 0.15)
				)
				(justify left)
			)
		)
		(property "License" "Apache-2.0"
			(at 281.94 39.37 0)
			(effects
				(font
					(size 1.27 1.27)
					(thickness 0.15)
				)
				(justify left bottom)
				(hide yes)
			)
		)
		(property "Author" "Antmicro"
			(at 284.48 39.37 0)
			(effects
				(font
					(size 1.27 1.27)
					(thickness 0.15)
				)
				(justify left bottom)
				(hide yes)
			)
		)
		(property "Tolerance" "1%"
			(at 266.7 39.37 0)
			(effects
				(font
					(size 1.27 1.27)
				)
				(justify left bottom)
				(hide yes)
			)
		)
		(pin "1"
		)
		(pin "2"
		)
		(instances
			(project "sodimm-ddr5-tester"
				(path ""
					(reference "R171")
					(unit 1)
				)
			)
		)
	)
	(symbol
		(lib_id "antmicroResistorsmisc:R_0R01_1206")
		(at 306.07 197.485 0)
		(unit 1)
		(exclude_from_sim no)
		(in_bom yes)
		(on_board yes)
		(dnp no)
		(property "Reference" "R147"
			(at 308.61 192.405 0)
			(effects
				(font
					(size 1.27 1.27)
				)
			)
		)
		(property "Value" "R_0R01_1206"
			(at 326.39 210.185 0)
			(effects
				(font
					(size 1.27 1.27)
					(thickness 0.15)
				)
				(justify left bottom)
				(hide yes)
			)
		)
		(property "Footprint" "antmicro-footprints:R_1206_3216Metric"
			(at 326.39 212.725 0)
			(effects
				(font
					(size 1.27 1.27)
					(thickness 0.15)
				)
				(justify left bottom)
				(hide yes)
			)
		)
		(property "Datasheet" "https://www.yageo.com/upload/media/product/productsearch/datasheet/rchip/PYu-RL_Group_521_RoHS_L_2.pdf"
			(at 326.39 215.265 0)
			(effects
				(font
					(size 1.27 1.27)
					(thickness 0.15)
				)
				(justify left bottom)
				(hide yes)
			)
		)
		(property "Description" ""
			(at 306.07 197.485 0)
			(effects
				(font
					(size 1.27 1.27)
				)
			)
		)
		(property "Manufacturer" "YAGEO"
			(at 326.39 220.345 0)
			(effects
				(font
					(size 1.27 1.27)
					(thickness 0.15)
				)
				(justify left bottom)
				(hide yes)
			)
		)
		(property "MPN" "RL1206FR-7W0R01L"
			(at 326.39 217.805 0)
			(effects
				(font
					(size 1.27 1.27)
					(thickness 0.15)
				)
				(justify left bottom)
				(hide yes)
			)
		)
		(property "Val" "0R01"
			(at 308.61 194.945 0)
			(effects
				(font
					(size 1.27 1.27)
					(thickness 0.15)
				)
			)
		)
		(property "License" "Apache-2.0"
			(at 326.39 222.885 0)
			(effects
				(font
					(size 1.27 1.27)
					(thickness 0.15)
				)
				(justify left bottom)
				(hide yes)
			)
		)
		(property "Author" "Antmicro"
			(at 326.39 225.425 0)
			(effects
				(font
					(size 1.27 1.27)
					(thickness 0.15)
				)
				(justify left bottom)
				(hide yes)
			)
		)
		(property "Tolerance" "1%"
			(at 326.39 207.645 0)
			(effects
				(font
					(size 1.27 1.27)
				)
				(justify left bottom)
				(hide yes)
			)
		)
		(pin "1"
		)
		(pin "2"
		)
		(instances
			(project "sodimm-ddr5-tester"
				(path ""
					(reference "R147")
					(unit 1)
				)
			)
		)
	)
	(symbol
		(lib_id "antmicropower:GND")
		(at 86.995 169.545 0)
		(unit 1)
		(exclude_from_sim no)
		(in_bom yes)
		(on_board yes)
		(dnp no)
		(fields_autoplaced yes)
		(property "Reference" "#PWR0304"
			(at 86.995 175.895 0)
			(effects
				(font
					(size 1.27 1.27)
				)
				(hide yes)
			)
		)
		(property "Value" "GND"
			(at 88.9 170.815 0)
			(effects
				(font
					(size 1.27 1.27)
					(thickness 0.15)
				)
				(justify left)
			)
		)
		(property "Footprint" ""
			(at 95.885 177.165 0)
			(effects
				(font
					(size 1.27 1.27)
					(thickness 0.15)
				)
				(justify left bottom)
				(hide yes)
			)
		)
		(property "Datasheet" ""
			(at 95.885 182.245 0)
			(effects
				(font
					(size 1.27 1.27)
					(thickness 0.15)
				)
				(justify left bottom)
				(hide yes)
			)
		)
		(property "Description" ""
			(at 95.885 184.785 0)
			(effects
				(font
					(size 1.27 1.27)
				)
				(justify left bottom)
				(hide yes)
			)
		)
		(property "Author" "Antmicro"
			(at 95.885 177.165 0)
			(effects
				(font
					(size 1.27 1.27)
					(thickness 0.15)
				)
				(justify left bottom)
				(hide yes)
			)
		)
		(property "License" "Apache-2.0"
			(at 95.885 179.705 0)
			(effects
				(font
					(size 1.27 1.27)
					(thickness 0.15)
				)
				(justify left bottom)
				(hide yes)
			)
		)
		(pin "1"
		)
		(instances
			(project "sodimm-ddr5-tester"
				(path ""
					(reference "#PWR0304")
					(unit 1)
				)
			)
		)
	)
	(symbol
		(lib_id "antmicropower:GND")
		(at 123.825 137.16 0)
		(unit 1)
		(exclude_from_sim no)
		(in_bom yes)
		(on_board yes)
		(dnp no)
		(fields_autoplaced yes)
		(property "Reference" "#PWR0396"
			(at 123.825 143.51 0)
			(effects
				(font
					(size 1.27 1.27)
				)
				(hide yes)
			)
		)
		(property "Value" "GND"
			(at 125.73 138.43 0)
			(effects
				(font
					(size 1.27 1.27)
					(thickness 0.15)
				)
				(justify left)
			)
		)
		(property "Footprint" ""
			(at 132.715 144.78 0)
			(effects
				(font
					(size 1.27 1.27)
					(thickness 0.15)
				)
				(justify left bottom)
				(hide yes)
			)
		)
		(property "Datasheet" ""
			(at 132.715 149.86 0)
			(effects
				(font
					(size 1.27 1.27)
					(thickness 0.15)
				)
				(justify left bottom)
				(hide yes)
			)
		)
		(property "Description" ""
			(at 132.715 152.4 0)
			(effects
				(font
					(size 1.27 1.27)
				)
				(justify left bottom)
				(hide yes)
			)
		)
		(property "Author" "Antmicro"
			(at 132.715 144.78 0)
			(effects
				(font
					(size 1.27 1.27)
					(thickness 0.15)
				)
				(justify left bottom)
				(hide yes)
			)
		)
		(property "License" "Apache-2.0"
			(at 132.715 147.32 0)
			(effects
				(font
					(size 1.27 1.27)
					(thickness 0.15)
				)
				(justify left bottom)
				(hide yes)
			)
		)
		(pin "1"
		)
		(instances
			(project "sodimm-ddr5-tester"
				(path ""
					(reference "#PWR0396")
					(unit 1)
				)
			)
		)
	)
	(symbol
		(lib_id "antmicropower:+12V")
		(at 34.29 53.975 0)
		(unit 1)
		(exclude_from_sim no)
		(in_bom yes)
		(on_board yes)
		(dnp no)
		(fields_autoplaced yes)
		(property "Reference" "#PWR0421"
			(at 34.29 57.785 0)
			(effects
				(font
					(size 1.27 1.27)
				)
				(hide yes)
			)
		)
		(property "Value" "+12V"
			(at 34.29 50.3992 0)
			(effects
				(font
					(size 1.27 1.27)
				)
			)
		)
		(property "Footprint" ""
			(at 34.29 53.975 0)
			(effects
				(font
					(size 1.27 1.27)
				)
				(hide yes)
			)
		)
		(property "Datasheet" ""
			(at 34.29 53.975 0)
			(effects
				(font
					(size 1.27 1.27)
				)
				(hide yes)
			)
		)
		(property "Description" ""
			(at 34.29 53.975 0)
			(effects
				(font
					(size 1.27 1.27)
				)
			)
		)
		(pin "1"
		)
		(instances
			(project "sodimm-ddr5-tester"
				(path ""
					(reference "#PWR0421")
					(unit 1)
				)
			)
		)
	)
	(symbol
		(lib_id "antmicroShuntsJumpers:Net-Tie_P0.127mm")
		(at 110.49 220.98 90)
		(unit 1)
		(exclude_from_sim no)
		(in_bom no)
		(on_board yes)
		(dnp no)
		(fields_autoplaced yes)
		(property "Reference" "NT4"
			(at 109.22 220.98 0)
			(effects
				(font
					(size 1.27 1.27)
				)
				(hide yes)
			)
		)
		(property "Value" "Net-Tie_P0.127mm"
			(at 118.11 199.39 0)
			(effects
				(font
					(size 1.27 1.27)
					(thickness 0.15)
				)
				(justify left bottom)
				(hide yes)
			)
		)
		(property "Footprint" "antmicro-footprints:NetTie-2_SMD_Pad0.127mm"
			(at 123.19 199.39 0)
			(effects
				(font
					(size 1.27 1.27)
					(thickness 0.15)
				)
				(justify left bottom)
				(hide yes)
			)
		)
		(property "Datasheet" ""
			(at 125.73 199.39 0)
			(effects
				(font
					(size 1.27 1.27)
					(thickness 0.15)
				)
				(justify left bottom)
				(hide yes)
			)
		)
		(property "Description" ""
			(at 110.49 220.98 0)
			(effects
				(font
					(size 1.27 1.27)
				)
			)
		)
		(property "MPN" ""
			(at 120.65 199.39 0)
			(effects
				(font
					(size 1.27 1.27)
					(thickness 0.15)
				)
				(justify left bottom)
			)
		)
		(property "Manufacturer" ""
			(at 128.27 199.39 0)
			(effects
				(font
					(size 1.27 1.27)
					(thickness 0.15)
				)
				(justify left bottom)
				(hide yes)
			)
		)
		(property "Author" "Antmicro"
			(at 130.81 199.39 0)
			(effects
				(font
					(size 1.27 1.27)
					(thickness 0.15)
				)
				(justify left bottom)
				(hide yes)
			)
		)
		(property "License" "Apache-2.0"
			(at 133.35 199.39 0)
			(effects
				(font
					(size 1.27 1.27)
					(thickness 0.15)
				)
				(justify left bottom)
				(hide yes)
			)
		)
		(pin "1"
		)
		(pin "2"
		)
		(instances
			(project "sodimm-ddr5-tester"
				(path ""
					(reference "NT4")
					(unit 1)
				)
			)
		)
	)
	(symbol
		(lib_id "antmicroTestPoints:TP_1mm_SMD")
		(at 154.94 278.13 270)
		(unit 1)
		(exclude_from_sim no)
		(in_bom yes)
		(on_board yes)
		(dnp no)
		(property "Reference" "TP34"
			(at 154.94 283.1028 90)
			(effects
				(font
					(size 1.27 1.27)
				)
			)
		)
		(property "Value" "TP_1mm_SMD"
			(at 147.32 293.37 0)
			(effects
				(font
					(size 1.27 1.27)
					(thickness 0.15)
				)
				(justify left bottom)
				(hide yes)
			)
		)
		(property "Footprint" "antmicro-footprints:TP_SMD_1mm"
			(at 144.78 293.37 0)
			(effects
				(font
					(size 1.27 1.27)
					(thickness 0.15)
				)
				(justify left bottom)
				(hide yes)
			)
		)
		(property "Datasheet" ""
			(at 142.24 293.37 0)
			(effects
				(font
					(size 1.27 1.27)
					(thickness 0.15)
				)
				(justify left bottom)
				(hide yes)
			)
		)
		(property "Description" ""
			(at 154.94 278.13 0)
			(effects
				(font
					(size 1.27 1.27)
				)
			)
		)
		(property "MPN" ""
			(at 154.94 278.13 0)
			(effects
				(font
					(size 1.27 1.27)
				)
				(hide yes)
			)
		)
		(property "Manufacturer" ""
			(at 154.94 278.13 0)
			(effects
				(font
					(size 1.27 1.27)
				)
				(hide yes)
			)
		)
		(property "Author" "Antmicro"
			(at 139.7 293.37 0)
			(effects
				(font
					(size 1.27 1.27)
					(thickness 0.15)
				)
				(justify left bottom)
				(hide yes)
			)
		)
		(property "License" "Apache-2.0"
			(at 137.16 293.37 0)
			(effects
				(font
					(size 1.27 1.27)
					(thickness 0.15)
				)
				(justify left bottom)
				(hide yes)
			)
		)
		(pin "1"
		)
		(instances
			(project "sodimm-ddr5-tester"
				(path ""
					(reference "TP34")
					(unit 1)
				)
			)
		)
	)
	(symbol
		(lib_id "antmicroCapacitors0402:C_100n_0402")
		(at 73.025 92.71 180)
		(unit 1)
		(exclude_from_sim no)
		(in_bom yes)
		(on_board yes)
		(dnp no)
		(property "Reference" "C208"
			(at 70.485 89.535 0)
			(effects
				(font
					(size 1.27 1.27)
				)
			)
		)
		(property "Value" "C_100n_0402"
			(at 52.705 82.55 0)
			(effects
				(font
					(size 1.27 1.27)
					(thickness 0.15)
				)
				(justify left bottom)
				(hide yes)
			)
		)
		(property "Footprint" "antmicro-footprints:C_0402_1005Metric"
			(at 52.705 80.01 0)
			(effects
				(font
					(size 1.27 1.27)
					(thickness 0.15)
				)
				(justify left bottom)
				(hide yes)
			)
		)
		(property "Datasheet" "https://www.murata.com/products/productdetail?partno=GRM155R61H104KE14%23"
			(at 52.705 77.47 0)
			(effects
				(font
					(size 1.27 1.27)
					(thickness 0.15)
				)
				(justify left bottom)
				(hide yes)
			)
		)
		(property "Description" ""
			(at 73.025 92.71 0)
			(effects
				(font
					(size 1.27 1.27)
				)
			)
		)
		(property "Manufacturer" "Murata"
			(at 52.705 72.39 0)
			(effects
				(font
					(size 1.27 1.27)
					(thickness 0.15)
				)
				(justify left bottom)
				(hide yes)
			)
		)
		(property "MPN" "GRM155R61H104KE14D"
			(at 52.705 74.93 0)
			(effects
				(font
					(size 1.27 1.27)
					(thickness 0.15)
				)
				(justify left bottom)
				(hide yes)
			)
		)
		(property "Val" "100n"
			(at 70.485 95.885 0)
			(effects
				(font
					(size 1.27 1.27)
					(thickness 0.15)
				)
			)
		)
		(property "License" "Apache-2.0"
			(at 52.705 69.85 0)
			(effects
				(font
					(size 1.27 1.27)
					(thickness 0.15)
				)
				(justify left bottom)
				(hide yes)
			)
		)
		(property "Author" "Antmicro"
			(at 52.705 67.31 0)
			(effects
				(font
					(size 1.27 1.27)
					(thickness 0.15)
				)
				(justify left bottom)
				(hide yes)
			)
		)
		(property "Voltage" "50V"
			(at 52.705 64.77 0)
			(effects
				(font
					(size 1.27 1.27)
				)
				(justify left bottom)
				(hide yes)
			)
		)
		(property "Dielectric" "X5R"
			(at 52.705 62.23 0)
			(effects
				(font
					(size 1.27 1.27)
				)
				(justify left bottom)
				(hide yes)
			)
		)
		(pin "1"
		)
		(pin "2"
		)
		(instances
			(project "sodimm-ddr5-tester"
				(path ""
					(reference "C208")
					(unit 1)
				)
			)
		)
	)
	(symbol
		(lib_id "antmicropower:GND")
		(at 356.87 221.615 0)
		(unit 1)
		(exclude_from_sim no)
		(in_bom yes)
		(on_board yes)
		(dnp no)
		(fields_autoplaced yes)
		(property "Reference" "#PWR0338"
			(at 356.87 227.965 0)
			(effects
				(font
					(size 1.27 1.27)
				)
				(hide yes)
			)
		)
		(property "Value" "GND"
			(at 359.41 222.885 0)
			(effects
				(font
					(size 1.27 1.27)
					(thickness 0.15)
				)
				(justify left)
			)
		)
		(property "Footprint" ""
			(at 365.76 229.235 0)
			(effects
				(font
					(size 1.27 1.27)
					(thickness 0.15)
				)
				(justify left bottom)
				(hide yes)
			)
		)
		(property "Datasheet" ""
			(at 365.76 234.315 0)
			(effects
				(font
					(size 1.27 1.27)
					(thickness 0.15)
				)
				(justify left bottom)
				(hide yes)
			)
		)
		(property "Description" ""
			(at 365.76 236.855 0)
			(effects
				(font
					(size 1.27 1.27)
				)
				(justify left bottom)
				(hide yes)
			)
		)
		(property "Author" "Antmicro"
			(at 365.76 229.235 0)
			(effects
				(font
					(size 1.27 1.27)
					(thickness 0.15)
				)
				(justify left bottom)
				(hide yes)
			)
		)
		(property "License" "Apache-2.0"
			(at 365.76 231.775 0)
			(effects
				(font
					(size 1.27 1.27)
					(thickness 0.15)
				)
				(justify left bottom)
				(hide yes)
			)
		)
		(pin "1"
		)
		(instances
			(project "sodimm-ddr5-tester"
				(path ""
					(reference "#PWR0338")
					(unit 1)
				)
			)
		)
	)
	(symbol
		(lib_id "antmicroCapacitors0402:C_1u_0402")
		(at 146.685 48.895 90)
		(unit 1)
		(exclude_from_sim no)
		(in_bom yes)
		(on_board yes)
		(dnp no)
		(property "Reference" "C194"
			(at 147.32 44.45 90)
			(effects
				(font
					(size 1.27 1.27)
				)
				(justify right)
			)
		)
		(property "Value" "C_1u_0402"
			(at 156.845 28.575 0)
			(effects
				(font
					(size 1.27 1.27)
					(thickness 0.15)
				)
				(justify left bottom)
				(hide yes)
			)
		)
		(property "Footprint" "antmicro-footprints:C_0402_1005Metric"
			(at 159.385 28.575 0)
			(effects
				(font
					(size 1.27 1.27)
					(thickness 0.15)
				)
				(justify left bottom)
				(hide yes)
			)
		)
		(property "Datasheet" "https://product.tdk.com/en/search/capacitor/ceramic/mlcc/info?part_no=C1005X6S1A105K050BC"
			(at 161.925 28.575 0)
			(effects
				(font
					(size 1.27 1.27)
					(thickness 0.15)
				)
				(justify left bottom)
				(hide yes)
			)
		)
		(property "Description" ""
			(at 146.685 48.895 0)
			(effects
				(font
					(size 1.27 1.27)
				)
			)
		)
		(property "Manufacturer" "TDK"
			(at 167.005 28.575 0)
			(effects
				(font
					(size 1.27 1.27)
					(thickness 0.15)
				)
				(justify left bottom)
				(hide yes)
			)
		)
		(property "MPN" "C1005X6S1A105K050BC"
			(at 164.465 28.575 0)
			(effects
				(font
					(size 1.27 1.27)
					(thickness 0.15)
				)
				(justify left bottom)
				(hide yes)
			)
		)
		(property "Val" "1u"
			(at 147.32 48.26 90)
			(effects
				(font
					(size 1.27 1.27)
					(thickness 0.15)
				)
				(justify right)
			)
		)
		(property "License" "Apache-2.0"
			(at 169.545 28.575 0)
			(effects
				(font
					(size 1.27 1.27)
					(thickness 0.15)
				)
				(justify left bottom)
				(hide yes)
			)
		)
		(property "Author" "Antmicro"
			(at 172.085 28.575 0)
			(effects
				(font
					(size 1.27 1.27)
					(thickness 0.15)
				)
				(justify left bottom)
				(hide yes)
			)
		)
		(property "Voltage" ""
			(at 174.625 28.575 0)
			(effects
				(font
					(size 1.27 1.27)
				)
				(justify left bottom)
				(hide yes)
			)
		)
		(property "Dielectric" ""
			(at 177.165 28.575 0)
			(effects
				(font
					(size 1.27 1.27)
				)
				(justify left bottom)
				(hide yes)
			)
		)
		(pin "1"
		)
		(pin "2"
		)
		(instances
			(project "sodimm-ddr5-tester"
				(path ""
					(reference "C194")
					(unit 1)
				)
			)
		)
	)
	(symbol
		(lib_id "antmicroResistorsmisc:R_0R01_1206")
		(at 111.76 179.705 0)
		(unit 1)
		(exclude_from_sim no)
		(in_bom yes)
		(on_board yes)
		(dnp no)
		(property "Reference" "R142"
			(at 114.3 174.625 0)
			(effects
				(font
					(size 1.27 1.27)
				)
			)
		)
		(property "Value" "R_0R01_1206"
			(at 132.08 192.405 0)
			(effects
				(font
					(size 1.27 1.27)
					(thickness 0.15)
				)
				(justify left bottom)
				(hide yes)
			)
		)
		(property "Footprint" "antmicro-footprints:R_1206_3216Metric"
			(at 132.08 194.945 0)
			(effects
				(font
					(size 1.27 1.27)
					(thickness 0.15)
				)
				(justify left bottom)
				(hide yes)
			)
		)
		(property "Datasheet" "https://www.yageo.com/upload/media/product/productsearch/datasheet/rchip/PYu-RL_Group_521_RoHS_L_2.pdf"
			(at 132.08 197.485 0)
			(effects
				(font
					(size 1.27 1.27)
					(thickness 0.15)
				)
				(justify left bottom)
				(hide yes)
			)
		)
		(property "Description" ""
			(at 111.76 179.705 0)
			(effects
				(font
					(size 1.27 1.27)
				)
			)
		)
		(property "Manufacturer" "YAGEO"
			(at 132.08 202.565 0)
			(effects
				(font
					(size 1.27 1.27)
					(thickness 0.15)
				)
				(justify left bottom)
				(hide yes)
			)
		)
		(property "MPN" "RL1206FR-7W0R01L"
			(at 132.08 200.025 0)
			(effects
				(font
					(size 1.27 1.27)
					(thickness 0.15)
				)
				(justify left bottom)
				(hide yes)
			)
		)
		(property "Val" "0R01"
			(at 114.3 177.165 0)
			(effects
				(font
					(size 1.27 1.27)
					(thickness 0.15)
				)
			)
		)
		(property "License" "Apache-2.0"
			(at 132.08 205.105 0)
			(effects
				(font
					(size 1.27 1.27)
					(thickness 0.15)
				)
				(justify left bottom)
				(hide yes)
			)
		)
		(property "Author" "Antmicro"
			(at 132.08 207.645 0)
			(effects
				(font
					(size 1.27 1.27)
					(thickness 0.15)
				)
				(justify left bottom)
				(hide yes)
			)
		)
		(property "Tolerance" "1%"
			(at 132.08 189.865 0)
			(effects
				(font
					(size 1.27 1.27)
				)
				(justify left bottom)
				(hide yes)
			)
		)
		(pin "1"
		)
		(pin "2"
		)
		(instances
			(project "sodimm-ddr5-tester"
				(path ""
					(reference "R142")
					(unit 1)
				)
			)
		)
	)
	(symbol
		(lib_id "antmicroTestPoints:TP_1mm_SMD")
		(at 148.59 278.13 270)
		(unit 1)
		(exclude_from_sim no)
		(in_bom yes)
		(on_board yes)
		(dnp no)
		(property "Reference" "TP32"
			(at 148.59 283.1028 90)
			(effects
				(font
					(size 1.27 1.27)
				)
			)
		)
		(property "Value" "TP_1mm_SMD"
			(at 140.97 293.37 0)
			(effects
				(font
					(size 1.27 1.27)
					(thickness 0.15)
				)
				(justify left bottom)
				(hide yes)
			)
		)
		(property "Footprint" "antmicro-footprints:TP_SMD_1mm"
			(at 138.43 293.37 0)
			(effects
				(font
					(size 1.27 1.27)
					(thickness 0.15)
				)
				(justify left bottom)
				(hide yes)
			)
		)
		(property "Datasheet" ""
			(at 135.89 293.37 0)
			(effects
				(font
					(size 1.27 1.27)
					(thickness 0.15)
				)
				(justify left bottom)
				(hide yes)
			)
		)
		(property "Description" ""
			(at 148.59 278.13 0)
			(effects
				(font
					(size 1.27 1.27)
				)
			)
		)
		(property "MPN" ""
			(at 148.59 278.13 0)
			(effects
				(font
					(size 1.27 1.27)
				)
				(hide yes)
			)
		)
		(property "Manufacturer" ""
			(at 148.59 278.13 0)
			(effects
				(font
					(size 1.27 1.27)
				)
				(hide yes)
			)
		)
		(property "Author" "Antmicro"
			(at 133.35 293.37 0)
			(effects
				(font
					(size 1.27 1.27)
					(thickness 0.15)
				)
				(justify left bottom)
				(hide yes)
			)
		)
		(property "License" "Apache-2.0"
			(at 130.81 293.37 0)
			(effects
				(font
					(size 1.27 1.27)
					(thickness 0.15)
				)
				(justify left bottom)
				(hide yes)
			)
		)
		(pin "1"
		)
		(instances
			(project "sodimm-ddr5-tester"
				(path ""
					(reference "TP32")
					(unit 1)
				)
			)
		)
	)
	(symbol
		(lib_id "antmicropower:GND")
		(at 114.935 257.81 0)
		(mirror y)
		(unit 1)
		(exclude_from_sim no)
		(in_bom yes)
		(on_board yes)
		(dnp no)
		(property "Reference" "#PWR0376"
			(at 114.935 264.16 0)
			(effects
				(font
					(size 1.27 1.27)
				)
				(hide yes)
			)
		)
		(property "Value" "GND"
			(at 113.538 262.128 0)
			(effects
				(font
					(size 1.27 1.27)
					(thickness 0.15)
				)
				(justify right)
			)
		)
		(property "Footprint" ""
			(at 106.045 265.43 0)
			(effects
				(font
					(size 1.27 1.27)
					(thickness 0.15)
				)
				(justify left bottom)
				(hide yes)
			)
		)
		(property "Datasheet" ""
			(at 106.045 270.51 0)
			(effects
				(font
					(size 1.27 1.27)
					(thickness 0.15)
				)
				(justify left bottom)
				(hide yes)
			)
		)
		(property "Description" ""
			(at 106.045 273.05 0)
			(effects
				(font
					(size 1.27 1.27)
				)
				(justify left bottom)
				(hide yes)
			)
		)
		(property "Author" "Antmicro"
			(at 106.045 265.43 0)
			(effects
				(font
					(size 1.27 1.27)
					(thickness 0.15)
				)
				(justify left bottom)
				(hide yes)
			)
		)
		(property "License" "Apache-2.0"
			(at 106.045 267.97 0)
			(effects
				(font
					(size 1.27 1.27)
					(thickness 0.15)
				)
				(justify left bottom)
				(hide yes)
			)
		)
		(pin "1"
		)
		(instances
			(project "sodimm-ddr5-tester"
				(path ""
					(reference "#PWR0376")
					(unit 1)
				)
			)
		)
	)
	(symbol
		(lib_id "antmicroTestPoints:TP_1mm_SMD")
		(at 229.87 274.32 0)
		(unit 1)
		(exclude_from_sim no)
		(in_bom yes)
		(on_board yes)
		(dnp no)
		(property "Reference" "TP66"
			(at 236.728 274.32 0)
			(effects
				(font
					(size 1.27 1.27)
				)
			)
		)
		(property "Value" "TP_1mm_SMD"
			(at 245.11 281.94 0)
			(effects
				(font
					(size 1.27 1.27)
					(thickness 0.15)
				)
				(justify left bottom)
				(hide yes)
			)
		)
		(property "Footprint" "antmicro-footprints:TP_SMD_1mm"
			(at 245.11 284.48 0)
			(effects
				(font
					(size 1.27 1.27)
					(thickness 0.15)
				)
				(justify left bottom)
				(hide yes)
			)
		)
		(property "Datasheet" ""
			(at 245.11 287.02 0)
			(effects
				(font
					(size 1.27 1.27)
					(thickness 0.15)
				)
				(justify left bottom)
				(hide yes)
			)
		)
		(property "Description" ""
			(at 229.87 274.32 0)
			(effects
				(font
					(size 1.27 1.27)
				)
			)
		)
		(property "MPN" ""
			(at 229.87 274.32 0)
			(effects
				(font
					(size 1.27 1.27)
				)
				(hide yes)
			)
		)
		(property "Manufacturer" ""
			(at 229.87 274.32 0)
			(effects
				(font
					(size 1.27 1.27)
				)
				(hide yes)
			)
		)
		(property "Author" "Antmicro"
			(at 245.11 289.56 0)
			(effects
				(font
					(size 1.27 1.27)
					(thickness 0.15)
				)
				(justify left bottom)
				(hide yes)
			)
		)
		(property "License" "Apache-2.0"
			(at 245.11 292.1 0)
			(effects
				(font
					(size 1.27 1.27)
					(thickness 0.15)
				)
				(justify left bottom)
				(hide yes)
			)
		)
		(pin "1"
		)
		(instances
			(project "sodimm-ddr5-tester"
				(path ""
					(reference "TP66")
					(unit 1)
				)
			)
		)
	)
	(symbol
		(lib_id "antmicroResistors0402:R_47k_0402")
		(at 269.24 40.005 90)
		(unit 1)
		(exclude_from_sim no)
		(in_bom yes)
		(on_board yes)
		(dnp no)
		(property "Reference" "R172"
			(at 267.97 36.195 90)
			(effects
				(font
					(size 1.27 1.27)
				)
				(justify left)
			)
		)
		(property "Value" "R_47k_0402"
			(at 281.94 19.685 0)
			(effects
				(font
					(size 1.27 1.27)
					(thickness 0.15)
				)
				(justify left bottom)
				(hide yes)
			)
		)
		(property "Footprint" "antmicro-footprints:R_0402_1005Metric"
			(at 284.48 19.685 0)
			(effects
				(font
					(size 1.27 1.27)
					(thickness 0.15)
				)
				(justify left bottom)
				(hide yes)
			)
		)
		(property "Datasheet" "https://www.bourns.com/docs/product-datasheets/cr.pdf"
			(at 287.02 19.685 0)
			(effects
				(font
					(size 1.27 1.27)
					(thickness 0.15)
				)
				(justify left bottom)
				(hide yes)
			)
		)
		(property "Description" ""
			(at 269.24 40.005 0)
			(effects
				(font
					(size 1.27 1.27)
				)
			)
		)
		(property "Manufacturer" "Bourns"
			(at 292.1 19.685 0)
			(effects
				(font
					(size 1.27 1.27)
					(thickness 0.15)
				)
				(justify left bottom)
				(hide yes)
			)
		)
		(property "MPN" "CR0402-FX-4702GLF"
			(at 289.56 19.685 0)
			(effects
				(font
					(size 1.27 1.27)
					(thickness 0.15)
				)
				(justify left bottom)
				(hide yes)
			)
		)
		(property "Val" "47k"
			(at 267.97 38.735 90)
			(effects
				(font
					(size 1.27 1.27)
					(thickness 0.15)
				)
				(justify left)
			)
		)
		(property "License" "Apache-2.0"
			(at 294.64 19.685 0)
			(effects
				(font
					(size 1.27 1.27)
					(thickness 0.15)
				)
				(justify left bottom)
				(hide yes)
			)
		)
		(property "Author" "Antmicro"
			(at 297.18 19.685 0)
			(effects
				(font
					(size 1.27 1.27)
					(thickness 0.15)
				)
				(justify left bottom)
				(hide yes)
			)
		)
		(property "Tolerance" "1%"
			(at 279.4 19.685 0)
			(effects
				(font
					(size 1.27 1.27)
				)
				(justify left bottom)
				(hide yes)
			)
		)
		(pin "1"
		)
		(pin "2"
		)
		(instances
			(project "sodimm-ddr5-tester"
				(path ""
					(reference "R172")
					(unit 1)
				)
			)
		)
	)
	(symbol
		(lib_id "antmicropower:GND")
		(at 218.44 34.29 0)
		(unit 1)
		(exclude_from_sim no)
		(in_bom yes)
		(on_board yes)
		(dnp no)
		(property "Reference" "#PWR0330"
			(at 218.44 40.64 0)
			(effects
				(font
					(size 1.27 1.27)
				)
				(hide yes)
			)
		)
		(property "Value" "GND"
			(at 216.535 38.735 0)
			(effects
				(font
					(size 1.27 1.27)
					(thickness 0.15)
				)
				(justify left bottom)
			)
		)
		(property "Footprint" ""
			(at 227.33 41.91 0)
			(effects
				(font
					(size 1.27 1.27)
					(thickness 0.15)
				)
				(justify left bottom)
				(hide yes)
			)
		)
		(property "Datasheet" ""
			(at 227.33 46.99 0)
			(effects
				(font
					(size 1.27 1.27)
					(thickness 0.15)
				)
				(justify left bottom)
				(hide yes)
			)
		)
		(property "Description" ""
			(at 227.33 49.53 0)
			(effects
				(font
					(size 1.27 1.27)
				)
				(justify left bottom)
				(hide yes)
			)
		)
		(property "Author" "Antmicro"
			(at 227.33 41.91 0)
			(effects
				(font
					(size 1.27 1.27)
					(thickness 0.15)
				)
				(justify left bottom)
				(hide yes)
			)
		)
		(property "License" "Apache-2.0"
			(at 227.33 44.45 0)
			(effects
				(font
					(size 1.27 1.27)
					(thickness 0.15)
				)
				(justify left bottom)
				(hide yes)
			)
		)
		(pin "1"
		)
		(instances
			(project "sodimm-ddr5-tester"
				(path ""
					(reference "#PWR0330")
					(unit 1)
				)
			)
		)
	)
	(symbol
		(lib_id "antmicropower:GND")
		(at 355.6 186.055 0)
		(unit 1)
		(exclude_from_sim no)
		(in_bom yes)
		(on_board yes)
		(dnp no)
		(fields_autoplaced yes)
		(property "Reference" "#PWR0337"
			(at 355.6 192.405 0)
			(effects
				(font
					(size 1.27 1.27)
				)
				(hide yes)
			)
		)
		(property "Value" "GND"
			(at 358.14 187.325 0)
			(effects
				(font
					(size 1.27 1.27)
					(thickness 0.15)
				)
				(justify left)
			)
		)
		(property "Footprint" ""
			(at 364.49 193.675 0)
			(effects
				(font
					(size 1.27 1.27)
					(thickness 0.15)
				)
				(justify left bottom)
				(hide yes)
			)
		)
		(property "Datasheet" ""
			(at 364.49 198.755 0)
			(effects
				(font
					(size 1.27 1.27)
					(thickness 0.15)
				)
				(justify left bottom)
				(hide yes)
			)
		)
		(property "Description" ""
			(at 364.49 201.295 0)
			(effects
				(font
					(size 1.27 1.27)
				)
				(justify left bottom)
				(hide yes)
			)
		)
		(property "Author" "Antmicro"
			(at 364.49 193.675 0)
			(effects
				(font
					(size 1.27 1.27)
					(thickness 0.15)
				)
				(justify left bottom)
				(hide yes)
			)
		)
		(property "License" "Apache-2.0"
			(at 364.49 196.215 0)
			(effects
				(font
					(size 1.27 1.27)
					(thickness 0.15)
				)
				(justify left bottom)
				(hide yes)
			)
		)
		(pin "1"
		)
		(instances
			(project "sodimm-ddr5-tester"
				(path ""
					(reference "#PWR0337")
					(unit 1)
				)
			)
		)
	)
	(symbol
		(lib_id "antmicroTestPoints:TP_1mm_SMD")
		(at 200.66 274.32 0)
		(unit 1)
		(exclude_from_sim no)
		(in_bom yes)
		(on_board yes)
		(dnp no)
		(property "Reference" "TP55"
			(at 207.264 274.32 0)
			(effects
				(font
					(size 1.27 1.27)
				)
			)
		)
		(property "Value" "TP_1mm_SMD"
			(at 215.9 281.94 0)
			(effects
				(font
					(size 1.27 1.27)
					(thickness 0.15)
				)
				(justify left bottom)
				(hide yes)
			)
		)
		(property "Footprint" "antmicro-footprints:TP_SMD_1mm"
			(at 215.9 284.48 0)
			(effects
				(font
					(size 1.27 1.27)
					(thickness 0.15)
				)
				(justify left bottom)
				(hide yes)
			)
		)
		(property "Datasheet" ""
			(at 215.9 287.02 0)
			(effects
				(font
					(size 1.27 1.27)
					(thickness 0.15)
				)
				(justify left bottom)
				(hide yes)
			)
		)
		(property "Description" ""
			(at 200.66 274.32 0)
			(effects
				(font
					(size 1.27 1.27)
				)
			)
		)
		(property "MPN" ""
			(at 200.66 274.32 0)
			(effects
				(font
					(size 1.27 1.27)
				)
				(hide yes)
			)
		)
		(property "Manufacturer" ""
			(at 200.66 274.32 0)
			(effects
				(font
					(size 1.27 1.27)
				)
				(hide yes)
			)
		)
		(property "Author" "Antmicro"
			(at 215.9 289.56 0)
			(effects
				(font
					(size 1.27 1.27)
					(thickness 0.15)
				)
				(justify left bottom)
				(hide yes)
			)
		)
		(property "License" "Apache-2.0"
			(at 215.9 292.1 0)
			(effects
				(font
					(size 1.27 1.27)
					(thickness 0.15)
				)
				(justify left bottom)
				(hide yes)
			)
		)
		(pin "1"
		)
		(instances
			(project "sodimm-ddr5-tester"
				(path ""
					(reference "TP55")
					(unit 1)
				)
			)
		)
	)
	(symbol
		(lib_id "antmicroResistors0402:R_0R_0402")
		(at 356.87 218.44 90)
		(unit 1)
		(exclude_from_sim no)
		(in_bom no)
		(on_board yes)
		(dnp yes)
		(property "Reference" "R158"
			(at 359.41 214.63 90)
			(effects
				(font
					(size 1.27 1.27)
				)
				(justify right)
			)
		)
		(property "Value" "R_0R_0402"
			(at 369.57 198.12 0)
			(effects
				(font
					(size 1.27 1.27)
					(thickness 0.15)
				)
				(justify left bottom)
				(hide yes)
			)
		)
		(property "Footprint" "antmicro-footprints:R_0402_1005Metric"
			(at 372.11 198.12 0)
			(effects
				(font
					(size 1.27 1.27)
					(thickness 0.15)
				)
				(justify left bottom)
				(hide yes)
			)
		)
		(property "Datasheet" "https://industrial.panasonic.com/cdbs/www-data/pdf/RDA0000/AOA0000C301.pdf"
			(at 374.65 198.12 0)
			(effects
				(font
					(size 1.27 1.27)
					(thickness 0.15)
				)
				(justify left bottom)
				(hide yes)
			)
		)
		(property "Description" ""
			(at 356.87 218.44 0)
			(effects
				(font
					(size 1.27 1.27)
				)
			)
		)
		(property "Manufacturer" "Panasonic"
			(at 379.73 198.12 0)
			(effects
				(font
					(size 1.27 1.27)
					(thickness 0.15)
				)
				(justify left bottom)
				(hide yes)
			)
		)
		(property "MPN" "ERJ2GE0R00X"
			(at 377.19 198.12 0)
			(effects
				(font
					(size 1.27 1.27)
					(thickness 0.15)
				)
				(justify left bottom)
				(hide yes)
			)
		)
		(property "Val" "0R"
			(at 359.41 217.17 90)
			(effects
				(font
					(size 1.27 1.27)
					(thickness 0.15)
				)
				(justify right)
			)
		)
		(property "License" "Apache-2.0"
			(at 382.27 198.12 0)
			(effects
				(font
					(size 1.27 1.27)
					(thickness 0.15)
				)
				(justify left bottom)
				(hide yes)
			)
		)
		(property "Author" "Antmicro"
			(at 384.81 198.12 0)
			(effects
				(font
					(size 1.27 1.27)
					(thickness 0.15)
				)
				(justify left bottom)
				(hide yes)
			)
		)
		(property "Tolerance" "~"
			(at 367.03 198.12 0)
			(effects
				(font
					(size 1.27 1.27)
				)
				(justify left bottom)
				(hide yes)
			)
		)
		(property "Current" "1A"
			(at 359.41 219.7099 90)
			(effects
				(font
					(size 1.27 1.27)
					(thickness 0.15)
				)
				(justify right)
				(hide yes)
			)
		)
		(pin "1"
		)
		(pin "2"
		)
		(instances
			(project "sodimm-ddr5-tester"
				(path ""
					(reference "R158")
					(unit 1)
				)
			)
		)
	)
	(symbol
		(lib_id "antmicroCapacitors0402:C_100n_0402")
		(at 180.34 252.73 270)
		(mirror x)
		(unit 1)
		(exclude_from_sim no)
		(in_bom yes)
		(on_board yes)
		(dnp no)
		(property "Reference" "C220"
			(at 179.07 248.285 90)
			(effects
				(font
					(size 1.27 1.27)
				)
				(justify right)
			)
		)
		(property "Value" "C_100n_0402"
			(at 170.18 232.41 0)
			(effects
				(font
					(size 1.27 1.27)
					(thickness 0.15)
				)
				(justify left bottom)
				(hide yes)
			)
		)
		(property "Footprint" "antmicro-footprints:C_0402_1005Metric"
			(at 167.64 232.41 0)
			(effects
				(font
					(size 1.27 1.27)
					(thickness 0.15)
				)
				(justify left bottom)
				(hide yes)
			)
		)
		(property "Datasheet" "https://www.murata.com/products/productdetail?partno=GRM155R61H104KE14%23"
			(at 165.1 232.41 0)
			(effects
				(font
					(size 1.27 1.27)
					(thickness 0.15)
				)
				(justify left bottom)
				(hide yes)
			)
		)
		(property "Description" ""
			(at 180.34 252.73 0)
			(effects
				(font
					(size 1.27 1.27)
				)
			)
		)
		(property "Manufacturer" "Murata"
			(at 160.02 232.41 0)
			(effects
				(font
					(size 1.27 1.27)
					(thickness 0.15)
				)
				(justify left bottom)
				(hide yes)
			)
		)
		(property "MPN" "GRM155R61H104KE14D"
			(at 162.56 232.41 0)
			(effects
				(font
					(size 1.27 1.27)
					(thickness 0.15)
				)
				(justify left bottom)
				(hide yes)
			)
		)
		(property "Val" "100n"
			(at 179.07 252.095 90)
			(effects
				(font
					(size 1.27 1.27)
					(thickness 0.15)
				)
				(justify right)
			)
		)
		(property "License" "Apache-2.0"
			(at 157.48 232.41 0)
			(effects
				(font
					(size 1.27 1.27)
					(thickness 0.15)
				)
				(justify left bottom)
				(hide yes)
			)
		)
		(property "Author" "Antmicro"
			(at 154.94 232.41 0)
			(effects
				(font
					(size 1.27 1.27)
					(thickness 0.15)
				)
				(justify left bottom)
				(hide yes)
			)
		)
		(property "Voltage" "50V"
			(at 152.4 232.41 0)
			(effects
				(font
					(size 1.27 1.27)
				)
				(justify left bottom)
				(hide yes)
			)
		)
		(property "Dielectric" "X5R"
			(at 149.86 232.41 0)
			(effects
				(font
					(size 1.27 1.27)
				)
				(justify left bottom)
				(hide yes)
			)
		)
		(pin "1"
		)
		(pin "2"
		)
		(instances
			(project "sodimm-ddr5-tester"
				(path ""
					(reference "C220")
					(unit 1)
				)
			)
		)
	)
	(symbol
		(lib_id "antmicroCapacitors0603:C_22u_0603")
		(at 276.86 165.735 90)
		(unit 1)
		(exclude_from_sim no)
		(in_bom yes)
		(on_board yes)
		(dnp no)
		(property "Reference" "C184"
			(at 277.495 161.29 90)
			(effects
				(font
					(size 1.27 1.27)
				)
				(justify right)
			)
		)
		(property "Value" "C_22u_0603"
			(at 287.02 145.415 0)
			(effects
				(font
					(size 1.27 1.27)
					(thickness 0.15)
				)
				(justify left bottom)
				(hide yes)
			)
		)
		(property "Footprint" "antmicro-footprints:C_0603_1608Metric"
			(at 289.56 145.415 0)
			(effects
				(font
					(size 1.27 1.27)
					(thickness 0.15)
				)
				(justify left bottom)
				(hide yes)
			)
		)
		(property "Datasheet" "https://www.murata.com/products/productdetail?partno=GRM188R60J226MEA0%23"
			(at 292.1 145.415 0)
			(effects
				(font
					(size 1.27 1.27)
					(thickness 0.15)
				)
				(justify left bottom)
				(hide yes)
			)
		)
		(property "Description" ""
			(at 276.86 165.735 0)
			(effects
				(font
					(size 1.27 1.27)
				)
			)
		)
		(property "Manufacturer" "Murata"
			(at 297.18 145.415 0)
			(effects
				(font
					(size 1.27 1.27)
					(thickness 0.15)
				)
				(justify left bottom)
				(hide yes)
			)
		)
		(property "MPN" "GRM188R60J226MEA0D"
			(at 294.64 145.415 0)
			(effects
				(font
					(size 1.27 1.27)
					(thickness 0.15)
				)
				(justify left bottom)
				(hide yes)
			)
		)
		(property "Val" "22u"
			(at 277.495 165.1 90)
			(effects
				(font
					(size 1.27 1.27)
					(thickness 0.15)
				)
				(justify right)
			)
		)
		(property "License" "Apache-2.0"
			(at 299.72 145.415 0)
			(effects
				(font
					(size 1.27 1.27)
					(thickness 0.15)
				)
				(justify left bottom)
				(hide yes)
			)
		)
		(property "Author" "Antmicro"
			(at 302.26 145.415 0)
			(effects
				(font
					(size 1.27 1.27)
					(thickness 0.15)
				)
				(justify left bottom)
				(hide yes)
			)
		)
		(property "Voltage" ""
			(at 304.8 145.415 0)
			(effects
				(font
					(size 1.27 1.27)
				)
				(justify left bottom)
				(hide yes)
			)
		)
		(property "Dielectric" ""
			(at 307.34 145.415 0)
			(effects
				(font
					(size 1.27 1.27)
				)
				(justify left bottom)
				(hide yes)
			)
		)
		(pin "1"
		)
		(pin "2"
		)
		(instances
			(project "sodimm-ddr5-tester"
				(path ""
					(reference "C184")
					(unit 1)
				)
			)
		)
	)
	(symbol
		(lib_id "antmicropower:GND")
		(at 366.395 59.055 0)
		(unit 1)
		(exclude_from_sim no)
		(in_bom yes)
		(on_board yes)
		(dnp no)
		(fields_autoplaced yes)
		(property "Reference" "#PWR0389"
			(at 366.395 65.405 0)
			(effects
				(font
					(size 1.27 1.27)
				)
				(hide yes)
			)
		)
		(property "Value" "GND"
			(at 368.3 60.325 0)
			(effects
				(font
					(size 1.27 1.27)
					(thickness 0.15)
				)
				(justify left)
			)
		)
		(property "Footprint" ""
			(at 375.285 66.675 0)
			(effects
				(font
					(size 1.27 1.27)
					(thickness 0.15)
				)
				(justify left bottom)
				(hide yes)
			)
		)
		(property "Datasheet" ""
			(at 375.285 71.755 0)
			(effects
				(font
					(size 1.27 1.27)
					(thickness 0.15)
				)
				(justify left bottom)
				(hide yes)
			)
		)
		(property "Description" ""
			(at 375.285 74.295 0)
			(effects
				(font
					(size 1.27 1.27)
				)
				(justify left bottom)
				(hide yes)
			)
		)
		(property "Author" "Antmicro"
			(at 375.285 66.675 0)
			(effects
				(font
					(size 1.27 1.27)
					(thickness 0.15)
				)
				(justify left bottom)
				(hide yes)
			)
		)
		(property "License" "Apache-2.0"
			(at 375.285 69.215 0)
			(effects
				(font
					(size 1.27 1.27)
					(thickness 0.15)
				)
				(justify left bottom)
				(hide yes)
			)
		)
		(pin "1"
		)
		(instances
			(project "sodimm-ddr5-tester"
				(path ""
					(reference "#PWR0389")
					(unit 1)
				)
			)
		)
	)
	(symbol
		(lib_id "antmicropower:+3V3_AON")
		(at 351.155 31.115 0)
		(unit 1)
		(exclude_from_sim no)
		(in_bom yes)
		(on_board yes)
		(dnp no)
		(fields_autoplaced yes)
		(property "Reference" "#PWR0382"
			(at 351.155 34.925 0)
			(effects
				(font
					(size 1.27 1.27)
				)
				(hide yes)
			)
		)
		(property "Value" "+3V3_AON"
			(at 351.155 25.4 0)
			(effects
				(font
					(size 1.27 1.27)
				)
			)
		)
		(property "Footprint" ""
			(at 351.155 31.115 0)
			(effects
				(font
					(size 1.27 1.27)
				)
				(hide yes)
			)
		)
		(property "Datasheet" ""
			(at 351.155 31.115 0)
			(effects
				(font
					(size 1.27 1.27)
				)
				(hide yes)
			)
		)
		(property "Description" ""
			(at 351.155 31.115 0)
			(effects
				(font
					(size 1.27 1.27)
				)
			)
		)
		(pin "1"
		)
		(instances
			(project "sodimm-ddr5-tester"
				(path ""
					(reference "#PWR0382")
					(unit 1)
				)
			)
		)
	)
	(symbol
		(lib_id "antmicropower:+3V3_AON")
		(at 269.24 31.75 0)
		(unit 1)
		(exclude_from_sim no)
		(in_bom yes)
		(on_board yes)
		(dnp no)
		(property "Reference" "#PWR0358"
			(at 269.24 35.56 0)
			(effects
				(font
					(size 1.27 1.27)
				)
				(hide yes)
			)
		)
		(property "Value" "+3V3_AON"
			(at 269.24 27.94 0)
			(effects
				(font
					(size 1.27 1.27)
				)
			)
		)
		(property "Footprint" ""
			(at 269.24 31.75 0)
			(effects
				(font
					(size 1.27 1.27)
				)
				(hide yes)
			)
		)
		(property "Datasheet" ""
			(at 269.24 31.75 0)
			(effects
				(font
					(size 1.27 1.27)
				)
				(hide yes)
			)
		)
		(property "Description" ""
			(at 269.24 31.75 0)
			(effects
				(font
					(size 1.27 1.27)
				)
			)
		)
		(pin "1"
		)
		(instances
			(project "sodimm-ddr5-tester"
				(path ""
					(reference "#PWR0358")
					(unit 1)
				)
			)
		)
	)
	(symbol
		(lib_id "antmicroCapacitorsmisc:C_22u_25V_0805")
		(at 215.9 164.465 90)
		(unit 1)
		(exclude_from_sim no)
		(in_bom yes)
		(on_board yes)
		(dnp no)
		(property "Reference" "C173"
			(at 216.535 160.02 90)
			(effects
				(font
					(size 1.27 1.27)
				)
				(justify right)
			)
		)
		(property "Value" "C_22u_25V_0805"
			(at 219.71 164.465 0)
			(effects
				(font
					(size 1.27 1.27)
				)
				(hide yes)
			)
		)
		(property "Footprint" "antmicro-footprints:C_0805_2012Metric"
			(at 210.82 159.385 0)
			(effects
				(font
					(size 1.27 1.27)
				)
				(justify left)
				(hide yes)
			)
		)
		(property "Datasheet" "https://product.samsungsem.com/mlcc/CL21A226MAYNNN.do"
			(at 215.9 164.465 0)
			(effects
				(font
					(size 1.27 1.27)
				)
				(hide yes)
			)
		)
		(property "Description" ""
			(at 215.9 164.465 0)
			(effects
				(font
					(size 1.27 1.27)
				)
			)
		)
		(property "Manufacturer" "Samsung Electro-Mechanics"
			(at 205.74 159.385 0)
			(effects
				(font
					(size 1.27 1.27)
				)
				(justify left)
				(hide yes)
			)
		)
		(property "MPN" "CL21A226MAYNNNE"
			(at 208.28 159.385 0)
			(effects
				(font
					(size 1.27 1.27)
				)
				(justify left)
				(hide yes)
			)
		)
		(property "Val" "22u_25V"
			(at 216.535 163.83 90)
			(effects
				(font
					(size 1.27 1.27)
				)
				(justify right)
			)
		)
		(property "License" "Apache-2.0"
			(at 238.76 144.145 0)
			(effects
				(font
					(size 1.27 1.27)
					(thickness 0.15)
				)
				(justify left bottom)
				(hide yes)
			)
		)
		(property "Author" "Antmicro"
			(at 241.3 144.145 0)
			(effects
				(font
					(size 1.27 1.27)
					(thickness 0.15)
				)
				(justify left bottom)
				(hide yes)
			)
		)
		(property "Voltage" ""
			(at 243.84 144.145 0)
			(effects
				(font
					(size 1.27 1.27)
				)
				(justify left bottom)
				(hide yes)
			)
		)
		(property "Dielectric" ""
			(at 246.38 144.145 0)
			(effects
				(font
					(size 1.27 1.27)
				)
				(justify left bottom)
				(hide yes)
			)
		)
		(pin "1"
		)
		(pin "2"
		)
		(instances
			(project "sodimm-ddr5-tester"
				(path ""
					(reference "C173")
					(unit 1)
				)
			)
		)
	)
	(symbol
		(lib_id "antmicropower:GND")
		(at 37.465 212.09 0)
		(unit 1)
		(exclude_from_sim no)
		(in_bom yes)
		(on_board yes)
		(dnp no)
		(fields_autoplaced yes)
		(property "Reference" "#PWR0295"
			(at 37.465 218.44 0)
			(effects
				(font
					(size 1.27 1.27)
				)
				(hide yes)
			)
		)
		(property "Value" "GND"
			(at 39.37 213.36 0)
			(effects
				(font
					(size 1.27 1.27)
					(thickness 0.15)
				)
				(justify left)
			)
		)
		(property "Footprint" ""
			(at 46.355 219.71 0)
			(effects
				(font
					(size 1.27 1.27)
					(thickness 0.15)
				)
				(justify left bottom)
				(hide yes)
			)
		)
		(property "Datasheet" ""
			(at 46.355 224.79 0)
			(effects
				(font
					(size 1.27 1.27)
					(thickness 0.15)
				)
				(justify left bottom)
				(hide yes)
			)
		)
		(property "Description" ""
			(at 46.355 227.33 0)
			(effects
				(font
					(size 1.27 1.27)
				)
				(justify left bottom)
				(hide yes)
			)
		)
		(property "Author" "Antmicro"
			(at 46.355 219.71 0)
			(effects
				(font
					(size 1.27 1.27)
					(thickness 0.15)
				)
				(justify left bottom)
				(hide yes)
			)
		)
		(property "License" "Apache-2.0"
			(at 46.355 222.25 0)
			(effects
				(font
					(size 1.27 1.27)
					(thickness 0.15)
				)
				(justify left bottom)
				(hide yes)
			)
		)
		(pin "1"
		)
		(instances
			(project "sodimm-ddr5-tester"
				(path ""
					(reference "#PWR0295")
					(unit 1)
				)
			)
		)
	)
	(symbol
		(lib_id "antmicroResistors0402:R_47k_0402")
		(at 388.62 43.815 90)
		(unit 1)
		(exclude_from_sim no)
		(in_bom yes)
		(on_board yes)
		(dnp no)
		(property "Reference" "R187"
			(at 389.89 40.005 90)
			(effects
				(font
					(size 1.27 1.27)
				)
				(justify right)
			)
		)
		(property "Value" "R_47k_0402"
			(at 401.32 23.495 0)
			(effects
				(font
					(size 1.27 1.27)
					(thickness 0.15)
				)
				(justify left bottom)
				(hide yes)
			)
		)
		(property "Footprint" "antmicro-footprints:R_0402_1005Metric"
			(at 403.86 23.495 0)
			(effects
				(font
					(size 1.27 1.27)
					(thickness 0.15)
				)
				(justify left bottom)
				(hide yes)
			)
		)
		(property "Datasheet" "https://www.bourns.com/docs/product-datasheets/cr.pdf"
			(at 406.4 23.495 0)
			(effects
				(font
					(size 1.27 1.27)
					(thickness 0.15)
				)
				(justify left bottom)
				(hide yes)
			)
		)
		(property "Description" ""
			(at 388.62 43.815 0)
			(effects
				(font
					(size 1.27 1.27)
				)
			)
		)
		(property "Manufacturer" "Bourns"
			(at 411.48 23.495 0)
			(effects
				(font
					(size 1.27 1.27)
					(thickness 0.15)
				)
				(justify left bottom)
				(hide yes)
			)
		)
		(property "MPN" "CR0402-FX-4702GLF"
			(at 408.94 23.495 0)
			(effects
				(font
					(size 1.27 1.27)
					(thickness 0.15)
				)
				(justify left bottom)
				(hide yes)
			)
		)
		(property "Val" "47k"
			(at 389.89 42.545 90)
			(effects
				(font
					(size 1.27 1.27)
					(thickness 0.15)
				)
				(justify right)
			)
		)
		(property "License" "Apache-2.0"
			(at 414.02 23.495 0)
			(effects
				(font
					(size 1.27 1.27)
					(thickness 0.15)
				)
				(justify left bottom)
				(hide yes)
			)
		)
		(property "Author" "Antmicro"
			(at 416.56 23.495 0)
			(effects
				(font
					(size 1.27 1.27)
					(thickness 0.15)
				)
				(justify left bottom)
				(hide yes)
			)
		)
		(property "Tolerance" "1%"
			(at 398.78 23.495 0)
			(effects
				(font
					(size 1.27 1.27)
				)
				(justify left bottom)
				(hide yes)
			)
		)
		(pin "1"
		)
		(pin "2"
		)
		(instances
			(project "sodimm-ddr5-tester"
				(path ""
					(reference "R187")
					(unit 1)
				)
			)
		)
	)
	(symbol
		(lib_id "antmicropower:+3V3")
		(at 298.45 97.155 0)
		(unit 1)
		(exclude_from_sim no)
		(in_bom yes)
		(on_board yes)
		(dnp no)
		(fields_autoplaced yes)
		(property "Reference" "#PWR0366"
			(at 298.45 100.965 0)
			(effects
				(font
					(size 1.27 1.27)
				)
				(hide yes)
			)
		)
		(property "Value" "+3V3"
			(at 295.275 94.615 0)
			(effects
				(font
					(size 1.27 1.27)
					(thickness 0.15)
				)
				(justify left bottom)
			)
		)
		(property "Footprint" ""
			(at 313.69 104.775 0)
			(effects
				(font
					(size 1.27 1.27)
					(thickness 0.15)
				)
				(justify left bottom)
				(hide yes)
			)
		)
		(property "Datasheet" ""
			(at 313.69 107.315 0)
			(effects
				(font
					(size 1.27 1.27)
					(thickness 0.15)
				)
				(justify left bottom)
				(hide yes)
			)
		)
		(property "Description" ""
			(at 298.45 97.155 0)
			(effects
				(font
					(size 1.27 1.27)
				)
			)
		)
		(property "Author" "Antmicro"
			(at 313.69 99.695 0)
			(effects
				(font
					(size 1.27 1.27)
					(thickness 0.15)
				)
				(justify left bottom)
				(hide yes)
			)
		)
		(property "License" "Apache-2.0"
			(at 313.69 102.235 0)
			(effects
				(font
					(size 1.27 1.27)
					(thickness 0.15)
				)
				(justify left bottom)
				(hide yes)
			)
		)
		(pin "1"
		)
		(instances
			(project "sodimm-ddr5-tester"
				(path ""
					(reference "#PWR0366")
					(unit 1)
				)
			)
		)
	)
	(symbol
		(lib_id "antmicropower:PWR_FLAG")
		(at 123.825 215.265 0)
		(unit 1)
		(exclude_from_sim no)
		(in_bom yes)
		(on_board yes)
		(dnp no)
		(fields_autoplaced yes)
		(property "Reference" "#FLG0112"
			(at 123.825 213.36 0)
			(effects
				(font
					(size 1.27 1.27)
				)
				(hide yes)
			)
		)
		(property "Value" "PWR_FLAG"
			(at 123.825 211.6892 0)
			(effects
				(font
					(size 1.27 1.27)
				)
			)
		)
		(property "Footprint" ""
			(at 123.825 215.265 0)
			(effects
				(font
					(size 1.27 1.27)
				)
				(hide yes)
			)
		)
		(property "Datasheet" ""
			(at 123.825 215.265 0)
			(effects
				(font
					(size 1.27 1.27)
				)
				(hide yes)
			)
		)
		(property "Description" ""
			(at 123.825 215.265 0)
			(effects
				(font
					(size 1.27 1.27)
				)
			)
		)
		(pin "1"
		)
		(instances
			(project "sodimm-ddr5-tester"
				(path ""
					(reference "#FLG0112")
					(unit 1)
				)
			)
		)
	)
	(symbol
		(lib_id "antmicroCapacitors0603:C_22u_0603")
		(at 86.995 187.325 90)
		(unit 1)
		(exclude_from_sim no)
		(in_bom yes)
		(on_board yes)
		(dnp no)
		(fields_autoplaced yes)
		(property "Reference" "C187"
			(at 89.3191 183.948 90)
			(effects
				(font
					(size 1.27 1.27)
				)
				(justify right)
			)
		)
		(property "Value" "C_22u_0603"
			(at 97.155 167.005 0)
			(effects
				(font
					(size 1.27 1.27)
					(thickness 0.15)
				)
				(justify left bottom)
				(hide yes)
			)
		)
		(property "Footprint" "antmicro-footprints:C_0603_1608Metric"
			(at 99.695 167.005 0)
			(effects
				(font
					(size 1.27 1.27)
					(thickness 0.15)
				)
				(justify left bottom)
				(hide yes)
			)
		)
		(property "Datasheet" "https://www.murata.com/products/productdetail?partno=GRM188R60J226MEA0%23"
			(at 102.235 167.005 0)
			(effects
				(font
					(size 1.27 1.27)
					(thickness 0.15)
				)
				(justify left bottom)
				(hide yes)
			)
		)
		(property "Description" ""
			(at 86.995 187.325 0)
			(effects
				(font
					(size 1.27 1.27)
				)
			)
		)
		(property "Manufacturer" "Murata"
			(at 107.315 167.005 0)
			(effects
				(font
					(size 1.27 1.27)
					(thickness 0.15)
				)
				(justify left bottom)
				(hide yes)
			)
		)
		(property "MPN" "GRM188R60J226MEA0D"
			(at 104.775 167.005 0)
			(effects
				(font
					(size 1.27 1.27)
					(thickness 0.15)
				)
				(justify left bottom)
				(hide yes)
			)
		)
		(property "Val" "22u"
			(at 89.3191 186.4783 90)
			(effects
				(font
					(size 1.27 1.27)
					(thickness 0.15)
				)
				(justify right)
			)
		)
		(property "License" "Apache-2.0"
			(at 109.855 167.005 0)
			(effects
				(font
					(size 1.27 1.27)
					(thickness 0.15)
				)
				(justify left bottom)
				(hide yes)
			)
		)
		(property "Author" "Antmicro"
			(at 112.395 167.005 0)
			(effects
				(font
					(size 1.27 1.27)
					(thickness 0.15)
				)
				(justify left bottom)
				(hide yes)
			)
		)
		(property "Voltage" ""
			(at 114.935 167.005 0)
			(effects
				(font
					(size 1.27 1.27)
				)
				(justify left bottom)
				(hide yes)
			)
		)
		(property "Dielectric" ""
			(at 117.475 167.005 0)
			(effects
				(font
					(size 1.27 1.27)
				)
				(justify left bottom)
				(hide yes)
			)
		)
		(pin "1"
		)
		(pin "2"
		)
		(instances
			(project "sodimm-ddr5-tester"
				(path ""
					(reference "C187")
					(unit 1)
				)
			)
		)
	)
	(symbol
		(lib_id "antmicroResistors0402:R_0R_0402")
		(at 283.21 259.08 0)
		(unit 1)
		(exclude_from_sim no)
		(in_bom yes)
		(on_board yes)
		(dnp no)
		(property "Reference" "R137"
			(at 290.83 257.81 0)
			(effects
				(font
					(size 1.27 1.27)
					(thickness 0.15)
				)
			)
		)
		(property "Value" "R_0R_0402"
			(at 303.53 271.78 0)
			(effects
				(font
					(size 1.27 1.27)
					(thickness 0.15)
				)
				(justify left bottom)
				(hide yes)
			)
		)
		(property "Footprint" "antmicro-footprints:R_0402_1005Metric"
			(at 303.53 274.32 0)
			(effects
				(font
					(size 1.27 1.27)
					(thickness 0.15)
				)
				(justify left bottom)
				(hide yes)
			)
		)
		(property "Datasheet" "https://industrial.panasonic.com/cdbs/www-data/pdf/RDA0000/AOA0000C301.pdf"
			(at 303.53 276.86 0)
			(effects
				(font
					(size 1.27 1.27)
					(thickness 0.15)
				)
				(justify left bottom)
				(hide yes)
			)
		)
		(property "Description" ""
			(at 283.21 259.08 0)
			(effects
				(font
					(size 1.27 1.27)
				)
			)
		)
		(property "MPN" "ERJ2GE0R00X"
			(at 303.53 279.4 0)
			(effects
				(font
					(size 1.27 1.27)
					(thickness 0.15)
				)
				(justify left bottom)
				(hide yes)
			)
		)
		(property "Manufacturer" "Panasonic"
			(at 303.53 281.94 0)
			(effects
				(font
					(size 1.27 1.27)
					(thickness 0.15)
				)
				(justify left bottom)
				(hide yes)
			)
		)
		(property "License" "Apache-2.0"
			(at 303.53 284.48 0)
			(effects
				(font
					(size 1.27 1.27)
					(thickness 0.15)
				)
				(justify left bottom)
				(hide yes)
			)
		)
		(property "Author" "Antmicro"
			(at 303.53 287.02 0)
			(effects
				(font
					(size 1.27 1.27)
					(thickness 0.15)
				)
				(justify left bottom)
				(hide yes)
			)
		)
		(property "Val" "0R"
			(at 281.94 257.81 0)
			(effects
				(font
					(size 1.27 1.27)
					(thickness 0.15)
				)
			)
		)
		(property "Tolerance" "~"
			(at 303.53 269.24 0)
			(effects
				(font
					(size 1.27 1.27)
				)
				(justify left bottom)
				(hide yes)
			)
		)
		(property "Current" "1A"
			(at 303.53 289.56 0)
			(effects
				(font
					(size 1.27 1.27)
					(thickness 0.15)
				)
				(justify left bottom)
				(hide yes)
			)
		)
		(pin "1"
		)
		(pin "2"
		)
		(instances
			(project "sodimm-ddr5-tester"
				(path ""
					(reference "R137")
					(unit 1)
				)
			)
		)
	)
	(symbol
		(lib_id "antmicroResistors0402:R_10k_0402")
		(at 227.965 247.015 90)
		(unit 1)
		(exclude_from_sim no)
		(in_bom yes)
		(on_board yes)
		(dnp no)
		(fields_autoplaced yes)
		(property "Reference" "R170"
			(at 229.616 243.6444 90)
			(effects
				(font
					(size 1.27 1.27)
					(thickness 0.15)
				)
				(justify right)
			)
		)
		(property "Value" "R_10k_0402"
			(at 240.665 226.695 0)
			(effects
				(font
					(size 1.27 1.27)
					(thickness 0.15)
				)
				(justify left bottom)
				(hide yes)
			)
		)
		(property "Footprint" "antmicro-footprints:R_0402_1005Metric"
			(at 243.205 226.695 0)
			(effects
				(font
					(size 1.27 1.27)
					(thickness 0.15)
				)
				(justify left bottom)
				(hide yes)
			)
		)
		(property "Datasheet" "https://www.bourns.com/docs/product-datasheets/cr.pdf"
			(at 245.745 226.695 0)
			(effects
				(font
					(size 1.27 1.27)
					(thickness 0.15)
				)
				(justify left bottom)
				(hide yes)
			)
		)
		(property "Description" ""
			(at 227.965 247.015 0)
			(effects
				(font
					(size 1.27 1.27)
				)
			)
		)
		(property "MPN" "CR0402-FX-1002GLF"
			(at 248.285 226.695 0)
			(effects
				(font
					(size 1.27 1.27)
					(thickness 0.15)
				)
				(justify left bottom)
				(hide yes)
			)
		)
		(property "Manufacturer" "Bourns"
			(at 250.825 226.695 0)
			(effects
				(font
					(size 1.27 1.27)
					(thickness 0.15)
				)
				(justify left bottom)
				(hide yes)
			)
		)
		(property "License" "Apache-2.0"
			(at 253.365 226.695 0)
			(effects
				(font
					(size 1.27 1.27)
					(thickness 0.15)
				)
				(justify left bottom)
				(hide yes)
			)
		)
		(property "Author" "Antmicro"
			(at 255.905 226.695 0)
			(effects
				(font
					(size 1.27 1.27)
					(thickness 0.15)
				)
				(justify left bottom)
				(hide yes)
			)
		)
		(property "Val" "10k"
			(at 229.616 246.1681 90)
			(effects
				(font
					(size 1.27 1.27)
					(thickness 0.15)
				)
				(justify right)
			)
		)
		(property "Tolerance" "1%"
			(at 238.125 226.695 0)
			(effects
				(font
					(size 1.27 1.27)
				)
				(justify left bottom)
				(hide yes)
			)
		)
		(pin "1"
		)
		(pin "2"
		)
		(instances
			(project "sodimm-ddr5-tester"
				(path ""
					(reference "R170")
					(unit 1)
				)
			)
		)
	)
	(symbol
		(lib_id "antmicroResistors0402:R_47k_0402")
		(at 243.84 45.72 90)
		(unit 1)
		(exclude_from_sim no)
		(in_bom yes)
		(on_board yes)
		(dnp no)
		(property "Reference" "R160"
			(at 242.57 41.91 90)
			(effects
				(font
					(size 1.27 1.27)
				)
				(justify left)
			)
		)
		(property "Value" "R_47k_0402"
			(at 256.54 25.4 0)
			(effects
				(font
					(size 1.27 1.27)
					(thickness 0.15)
				)
				(justify left bottom)
				(hide yes)
			)
		)
		(property "Footprint" "antmicro-footprints:R_0402_1005Metric"
			(at 259.08 25.4 0)
			(effects
				(font
					(size 1.27 1.27)
					(thickness 0.15)
				)
				(justify left bottom)
				(hide yes)
			)
		)
		(property "Datasheet" "https://www.bourns.com/docs/product-datasheets/cr.pdf"
			(at 261.62 25.4 0)
			(effects
				(font
					(size 1.27 1.27)
					(thickness 0.15)
				)
				(justify left bottom)
				(hide yes)
			)
		)
		(property "Description" ""
			(at 243.84 45.72 0)
			(effects
				(font
					(size 1.27 1.27)
				)
			)
		)
		(property "Manufacturer" "Bourns"
			(at 266.7 25.4 0)
			(effects
				(font
					(size 1.27 1.27)
					(thickness 0.15)
				)
				(justify left bottom)
				(hide yes)
			)
		)
		(property "MPN" "CR0402-FX-4702GLF"
			(at 264.16 25.4 0)
			(effects
				(font
					(size 1.27 1.27)
					(thickness 0.15)
				)
				(justify left bottom)
				(hide yes)
			)
		)
		(property "Val" "47k"
			(at 242.57 44.45 90)
			(effects
				(font
					(size 1.27 1.27)
					(thickness 0.15)
				)
				(justify left)
			)
		)
		(property "License" "Apache-2.0"
			(at 269.24 25.4 0)
			(effects
				(font
					(size 1.27 1.27)
					(thickness 0.15)
				)
				(justify left bottom)
				(hide yes)
			)
		)
		(property "Author" "Antmicro"
			(at 271.78 25.4 0)
			(effects
				(font
					(size 1.27 1.27)
					(thickness 0.15)
				)
				(justify left bottom)
				(hide yes)
			)
		)
		(property "Tolerance" "1%"
			(at 254 25.4 0)
			(effects
				(font
					(size 1.27 1.27)
				)
				(justify left bottom)
				(hide yes)
			)
		)
		(pin "1"
		)
		(pin "2"
		)
		(instances
			(project "sodimm-ddr5-tester"
				(path ""
					(reference "R160")
					(unit 1)
				)
			)
		)
	)
	(symbol
		(lib_id "antmicropower:+3V3_AON")
		(at 212.725 25.4 0)
		(unit 1)
		(exclude_from_sim no)
		(in_bom yes)
		(on_board yes)
		(dnp no)
		(property "Reference" "#PWR0329"
			(at 212.725 29.21 0)
			(effects
				(font
					(size 1.27 1.27)
				)
				(hide yes)
			)
		)
		(property "Value" "+3V3_AON"
			(at 212.725 21.59 0)
			(effects
				(font
					(size 1.27 1.27)
				)
			)
		)
		(property "Footprint" ""
			(at 212.725 25.4 0)
			(effects
				(font
					(size 1.27 1.27)
				)
				(hide yes)
			)
		)
		(property "Datasheet" ""
			(at 212.725 25.4 0)
			(effects
				(font
					(size 1.27 1.27)
				)
				(hide yes)
			)
		)
		(property "Description" ""
			(at 212.725 25.4 0)
			(effects
				(font
					(size 1.27 1.27)
				)
			)
		)
		(pin "1"
		)
		(instances
			(project "sodimm-ddr5-tester"
				(path ""
					(reference "#PWR0329")
					(unit 1)
				)
			)
		)
	)
	(symbol
		(lib_id "antmicroShuntsJumpers:Net-Tie_P0.127mm")
		(at 313.055 162.56 90)
		(unit 1)
		(exclude_from_sim no)
		(in_bom no)
		(on_board yes)
		(dnp no)
		(fields_autoplaced yes)
		(property "Reference" "NT13"
			(at 311.785 162.56 0)
			(effects
				(font
					(size 1.27 1.27)
				)
				(hide yes)
			)
		)
		(property "Value" "Net-Tie_P0.127mm"
			(at 320.675 140.97 0)
			(effects
				(font
					(size 1.27 1.27)
					(thickness 0.15)
				)
				(justify left bottom)
				(hide yes)
			)
		)
		(property "Footprint" "antmicro-footprints:NetTie-2_SMD_Pad0.127mm"
			(at 325.755 140.97 0)
			(effects
				(font
					(size 1.27 1.27)
					(thickness 0.15)
				)
				(justify left bottom)
				(hide yes)
			)
		)
		(property "Datasheet" ""
			(at 328.295 140.97 0)
			(effects
				(font
					(size 1.27 1.27)
					(thickness 0.15)
				)
				(justify left bottom)
				(hide yes)
			)
		)
		(property "Description" ""
			(at 313.055 162.56 0)
			(effects
				(font
					(size 1.27 1.27)
				)
			)
		)
		(property "MPN" ""
			(at 323.215 140.97 0)
			(effects
				(font
					(size 1.27 1.27)
					(thickness 0.15)
				)
				(justify left bottom)
			)
		)
		(property "Manufacturer" ""
			(at 330.835 140.97 0)
			(effects
				(font
					(size 1.27 1.27)
					(thickness 0.15)
				)
				(justify left bottom)
				(hide yes)
			)
		)
		(property "Author" "Antmicro"
			(at 333.375 140.97 0)
			(effects
				(font
					(size 1.27 1.27)
					(thickness 0.15)
				)
				(justify left bottom)
				(hide yes)
			)
		)
		(property "License" "Apache-2.0"
			(at 335.915 140.97 0)
			(effects
				(font
					(size 1.27 1.27)
					(thickness 0.15)
				)
				(justify left bottom)
				(hide yes)
			)
		)
		(pin "1"
		)
		(pin "2"
		)
		(instances
			(project "sodimm-ddr5-tester"
				(path ""
					(reference "NT13")
					(unit 1)
				)
			)
		)
	)
	(symbol
		(lib_id "antmicroTestPoints:TP_1mm_SMD")
		(at 185.42 278.13 90)
		(unit 1)
		(exclude_from_sim no)
		(in_bom yes)
		(on_board yes)
		(dnp no)
		(property "Reference" "TP36"
			(at 185.42 273.1572 90)
			(effects
				(font
					(size 1.27 1.27)
				)
			)
		)
		(property "Value" "TP_1mm_SMD"
			(at 193.04 262.89 0)
			(effects
				(font
					(size 1.27 1.27)
					(thickness 0.15)
				)
				(justify left bottom)
				(hide yes)
			)
		)
		(property "Footprint" "antmicro-footprints:TP_SMD_1mm"
			(at 195.58 262.89 0)
			(effects
				(font
					(size 1.27 1.27)
					(thickness 0.15)
				)
				(justify left bottom)
				(hide yes)
			)
		)
		(property "Datasheet" ""
			(at 198.12 262.89 0)
			(effects
				(font
					(size 1.27 1.27)
					(thickness 0.15)
				)
				(justify left bottom)
				(hide yes)
			)
		)
		(property "Description" ""
			(at 185.42 278.13 0)
			(effects
				(font
					(size 1.27 1.27)
				)
			)
		)
		(property "MPN" ""
			(at 185.42 278.13 0)
			(effects
				(font
					(size 1.27 1.27)
				)
				(hide yes)
			)
		)
		(property "Manufacturer" ""
			(at 185.42 278.13 0)
			(effects
				(font
					(size 1.27 1.27)
				)
				(hide yes)
			)
		)
		(property "Author" "Antmicro"
			(at 200.66 262.89 0)
			(effects
				(font
					(size 1.27 1.27)
					(thickness 0.15)
				)
				(justify left bottom)
				(hide yes)
			)
		)
		(property "License" "Apache-2.0"
			(at 203.2 262.89 0)
			(effects
				(font
					(size 1.27 1.27)
					(thickness 0.15)
				)
				(justify left bottom)
				(hide yes)
			)
		)
		(pin "1"
		)
		(instances
			(project "sodimm-ddr5-tester"
				(path ""
					(reference "TP36")
					(unit 1)
				)
			)
		)
	)
	(symbol
		(lib_id "antmicropower:GND")
		(at 215.9 167.005 0)
		(unit 1)
		(exclude_from_sim no)
		(in_bom yes)
		(on_board yes)
		(dnp no)
		(property "Reference" "#PWR0290"
			(at 215.9 173.355 0)
			(effects
				(font
					(size 1.27 1.27)
				)
				(hide yes)
			)
		)
		(property "Value" "GND"
			(at 213.995 171.45 0)
			(effects
				(font
					(size 1.27 1.27)
					(thickness 0.15)
				)
				(justify left bottom)
			)
		)
		(property "Footprint" ""
			(at 224.79 174.625 0)
			(effects
				(font
					(size 1.27 1.27)
					(thickness 0.15)
				)
				(justify left bottom)
				(hide yes)
			)
		)
		(property "Datasheet" ""
			(at 224.79 179.705 0)
			(effects
				(font
					(size 1.27 1.27)
					(thickness 0.15)
				)
				(justify left bottom)
				(hide yes)
			)
		)
		(property "Description" ""
			(at 224.79 182.245 0)
			(effects
				(font
					(size 1.27 1.27)
				)
				(justify left bottom)
				(hide yes)
			)
		)
		(property "Author" "Antmicro"
			(at 224.79 174.625 0)
			(effects
				(font
					(size 1.27 1.27)
					(thickness 0.15)
				)
				(justify left bottom)
				(hide yes)
			)
		)
		(property "License" "Apache-2.0"
			(at 224.79 177.165 0)
			(effects
				(font
					(size 1.27 1.27)
					(thickness 0.15)
				)
				(justify left bottom)
				(hide yes)
			)
		)
		(pin "1"
		)
		(instances
			(project "sodimm-ddr5-tester"
				(path ""
					(reference "#PWR0290")
					(unit 1)
				)
			)
		)
	)
	(symbol
		(lib_id "antmicroCapacitors0603:C_22u_0603")
		(at 89.535 114.3 90)
		(unit 1)
		(exclude_from_sim no)
		(in_bom yes)
		(on_board yes)
		(dnp no)
		(property "Reference" "C213"
			(at 90.17 109.855 90)
			(effects
				(font
					(size 1.27 1.27)
				)
				(justify right)
			)
		)
		(property "Value" "C_22u_0603"
			(at 99.695 93.98 0)
			(effects
				(font
					(size 1.27 1.27)
					(thickness 0.15)
				)
				(justify left bottom)
				(hide yes)
			)
		)
		(property "Footprint" "antmicro-footprints:C_0603_1608Metric"
			(at 102.235 93.98 0)
			(effects
				(font
					(size 1.27 1.27)
					(thickness 0.15)
				)
				(justify left bottom)
				(hide yes)
			)
		)
		(property "Datasheet" "https://www.murata.com/products/productdetail?partno=GRM188R60J226MEA0%23"
			(at 104.775 93.98 0)
			(effects
				(font
					(size 1.27 1.27)
					(thickness 0.15)
				)
				(justify left bottom)
				(hide yes)
			)
		)
		(property "Description" ""
			(at 89.535 114.3 0)
			(effects
				(font
					(size 1.27 1.27)
				)
			)
		)
		(property "Manufacturer" "Murata"
			(at 109.855 93.98 0)
			(effects
				(font
					(size 1.27 1.27)
					(thickness 0.15)
				)
				(justify left bottom)
				(hide yes)
			)
		)
		(property "MPN" "GRM188R60J226MEA0D"
			(at 107.315 93.98 0)
			(effects
				(font
					(size 1.27 1.27)
					(thickness 0.15)
				)
				(justify left bottom)
				(hide yes)
			)
		)
		(property "Val" "22u"
			(at 90.17 113.665 90)
			(effects
				(font
					(size 1.27 1.27)
					(thickness 0.15)
				)
				(justify right)
			)
		)
		(property "License" "Apache-2.0"
			(at 112.395 93.98 0)
			(effects
				(font
					(size 1.27 1.27)
					(thickness 0.15)
				)
				(justify left bottom)
				(hide yes)
			)
		)
		(property "Author" "Antmicro"
			(at 114.935 93.98 0)
			(effects
				(font
					(size 1.27 1.27)
					(thickness 0.15)
				)
				(justify left bottom)
				(hide yes)
			)
		)
		(property "Voltage" ""
			(at 117.475 93.98 0)
			(effects
				(font
					(size 1.27 1.27)
				)
				(justify left bottom)
				(hide yes)
			)
		)
		(property "Dielectric" ""
			(at 120.015 93.98 0)
			(effects
				(font
					(size 1.27 1.27)
				)
				(justify left bottom)
				(hide yes)
			)
		)
		(pin "1"
		)
		(pin "2"
		)
		(instances
			(project "sodimm-ddr5-tester"
				(path ""
					(reference "C213")
					(unit 1)
				)
			)
		)
	)
	(symbol
		(lib_id "antmicroPMICVoltageRegulatorsDCDCSwitchingRegulators:MP8869S")
		(at 64.135 101.6 0)
		(unit 1)
		(exclude_from_sim no)
		(in_bom yes)
		(on_board yes)
		(dnp no)
		(fields_autoplaced yes)
		(property "Reference" "U27"
			(at 66.1544 100.4484 0)
			(effects
				(font
					(size 1.27 1.27)
				)
				(justify left)
			)
		)
		(property "Value" "MP8869S"
			(at 66.1544 102.9787 0)
			(effects
				(font
					(size 1.27 1.27)
					(thickness 0.15)
				)
				(justify left)
			)
		)
		(property "Footprint" "antmicro-footprints:MPS_QFN-14_MP8869S"
			(at 89.535 113.03 0)
			(effects
				(font
					(size 1.27 1.27)
					(thickness 0.15)
				)
				(justify left bottom)
				(hide yes)
			)
		)
		(property "Datasheet" "https://www.mouser.com/datasheet/2/277/MP8869S-2946178.pdf"
			(at 89.535 115.57 0)
			(effects
				(font
					(size 1.27 1.27)
					(thickness 0.15)
				)
				(justify left bottom)
				(hide yes)
			)
		)
		(property "Description" ""
			(at 64.135 101.6 0)
			(effects
				(font
					(size 1.27 1.27)
				)
			)
		)
		(property "MPN" "MP8869SGL-P"
			(at 89.535 118.11 0)
			(effects
				(font
					(size 1.27 1.27)
					(thickness 0.15)
				)
				(justify left bottom)
				(hide yes)
			)
		)
		(property "Manufacturer" "Monolithic Power Systems"
			(at 89.535 120.65 0)
			(effects
				(font
					(size 1.27 1.27)
					(thickness 0.15)
				)
				(justify left bottom)
				(hide yes)
			)
		)
		(property "Author" "Antmicro"
			(at 89.535 123.19 0)
			(effects
				(font
					(size 1.27 1.27)
					(thickness 0.15)
				)
				(justify left bottom)
				(hide yes)
			)
		)
		(property "License" "Apache-2.0"
			(at 89.535 125.73 0)
			(effects
				(font
					(size 1.27 1.27)
					(thickness 0.15)
				)
				(justify left bottom)
				(hide yes)
			)
		)
		(pin "1"
		)
		(pin "10"
		)
		(pin "11"
		)
		(pin "12"
		)
		(pin "13"
		)
		(pin "14"
		)
		(pin "2"
		)
		(pin "3"
		)
		(pin "4"
		)
		(pin "5"
		)
		(pin "6"
		)
		(pin "7"
		)
		(pin "8"
		)
		(pin "9"
		)
		(instances
			(project "sodimm-ddr5-tester"
				(path ""
					(reference "U27")
					(unit 1)
				)
			)
		)
	)
	(symbol
		(lib_id "antmicropower:GND")
		(at 95.885 76.835 0)
		(unit 1)
		(exclude_from_sim no)
		(in_bom yes)
		(on_board yes)
		(dnp no)
		(property "Reference" "#PWR0299"
			(at 95.885 83.185 0)
			(effects
				(font
					(size 1.27 1.27)
				)
				(hide yes)
			)
		)
		(property "Value" "GND"
			(at 94.234 80.772 0)
			(effects
				(font
					(size 1.27 1.27)
					(thickness 0.15)
				)
				(justify left)
			)
		)
		(property "Footprint" ""
			(at 104.775 84.455 0)
			(effects
				(font
					(size 1.27 1.27)
					(thickness 0.15)
				)
				(justify left bottom)
				(hide yes)
			)
		)
		(property "Datasheet" ""
			(at 104.775 89.535 0)
			(effects
				(font
					(size 1.27 1.27)
					(thickness 0.15)
				)
				(justify left bottom)
				(hide yes)
			)
		)
		(property "Description" ""
			(at 104.775 92.075 0)
			(effects
				(font
					(size 1.27 1.27)
				)
				(justify left bottom)
				(hide yes)
			)
		)
		(property "Author" "Antmicro"
			(at 104.775 84.455 0)
			(effects
				(font
					(size 1.27 1.27)
					(thickness 0.15)
				)
				(justify left bottom)
				(hide yes)
			)
		)
		(property "License" "Apache-2.0"
			(at 104.775 86.995 0)
			(effects
				(font
					(size 1.27 1.27)
					(thickness 0.15)
				)
				(justify left bottom)
				(hide yes)
			)
		)
		(pin "1"
		)
		(instances
			(project "sodimm-ddr5-tester"
				(path ""
					(reference "#PWR0299")
					(unit 1)
				)
			)
		)
	)
	(symbol
		(lib_id "antmicroCapacitorsmisc:C_22u_25V_0805")
		(at 29.21 102.87 90)
		(unit 1)
		(exclude_from_sim no)
		(in_bom yes)
		(on_board yes)
		(dnp no)
		(property "Reference" "C202"
			(at 29.845 98.425 90)
			(effects
				(font
					(size 1.27 1.27)
				)
				(justify right)
			)
		)
		(property "Value" "C_22u_25V_0805"
			(at 39.37 82.55 0)
			(effects
				(font
					(size 1.27 1.27)
					(thickness 0.15)
				)
				(justify left bottom)
				(hide yes)
			)
		)
		(property "Footprint" "antmicro-footprints:C_0805_2012Metric"
			(at 41.91 82.55 0)
			(effects
				(font
					(size 1.27 1.27)
					(thickness 0.15)
				)
				(justify left bottom)
				(hide yes)
			)
		)
		(property "Datasheet" "https://product.samsungsem.com/mlcc/CL21A226MAYNNN.do"
			(at 44.45 82.55 0)
			(effects
				(font
					(size 1.27 1.27)
					(thickness 0.15)
				)
				(justify left bottom)
				(hide yes)
			)
		)
		(property "Description" ""
			(at 29.21 102.87 0)
			(effects
				(font
					(size 1.27 1.27)
				)
			)
		)
		(property "Manufacturer" "Samsung Electro-Mechanics"
			(at 49.53 82.55 0)
			(effects
				(font
					(size 1.27 1.27)
					(thickness 0.15)
				)
				(justify left bottom)
				(hide yes)
			)
		)
		(property "MPN" "CL21A226MAYNNNE"
			(at 46.99 82.55 0)
			(effects
				(font
					(size 1.27 1.27)
					(thickness 0.15)
				)
				(justify left bottom)
				(hide yes)
			)
		)
		(property "Val" "22u_25V"
			(at 29.845 102.235 90)
			(effects
				(font
					(size 1.27 1.27)
					(thickness 0.15)
				)
				(justify right)
			)
		)
		(property "License" "Apache-2.0"
			(at 52.07 82.55 0)
			(effects
				(font
					(size 1.27 1.27)
					(thickness 0.15)
				)
				(justify left bottom)
				(hide yes)
			)
		)
		(property "Author" "Antmicro"
			(at 54.61 82.55 0)
			(effects
				(font
					(size 1.27 1.27)
					(thickness 0.15)
				)
				(justify left bottom)
				(hide yes)
			)
		)
		(property "Voltage" ""
			(at 57.15 82.55 0)
			(effects
				(font
					(size 1.27 1.27)
				)
				(justify left bottom)
				(hide yes)
			)
		)
		(property "Dielectric" ""
			(at 59.69 82.55 0)
			(effects
				(font
					(size 1.27 1.27)
				)
				(justify left bottom)
				(hide yes)
			)
		)
		(pin "1"
		)
		(pin "2"
		)
		(instances
			(project "sodimm-ddr5-tester"
				(path ""
					(reference "C202")
					(unit 1)
				)
			)
		)
	)
	(symbol
		(lib_id "antmicroCapacitors0402:C_100n_0402")
		(at 34.29 62.865 90)
		(unit 1)
		(exclude_from_sim no)
		(in_bom yes)
		(on_board yes)
		(dnp no)
		(fields_autoplaced yes)
		(property "Reference" "C170"
			(at 36.83 59.0485 90)
			(effects
				(font
					(size 1.27 1.27)
				)
				(justify right)
			)
		)
		(property "Value" "C_100n_0402"
			(at 44.45 42.545 0)
			(effects
				(font
					(size 1.27 1.27)
					(thickness 0.15)
				)
				(justify left bottom)
				(hide yes)
			)
		)
		(property "Footprint" "antmicro-footprints:C_0402_1005Metric"
			(at 46.99 42.545 0)
			(effects
				(font
					(size 1.27 1.27)
					(thickness 0.15)
				)
				(justify left bottom)
				(hide yes)
			)
		)
		(property "Datasheet" "https://www.murata.com/products/productdetail?partno=GRM155R61H104KE14%23"
			(at 49.53 42.545 0)
			(effects
				(font
					(size 1.27 1.27)
					(thickness 0.15)
				)
				(justify left bottom)
				(hide yes)
			)
		)
		(property "Description" ""
			(at 34.29 62.865 0)
			(effects
				(font
					(size 1.27 1.27)
				)
			)
		)
		(property "Manufacturer" "Murata"
			(at 54.61 42.545 0)
			(effects
				(font
					(size 1.27 1.27)
					(thickness 0.15)
				)
				(justify left bottom)
				(hide yes)
			)
		)
		(property "MPN" "GRM155R61H104KE14D"
			(at 52.07 42.545 0)
			(effects
				(font
					(size 1.27 1.27)
					(thickness 0.15)
				)
				(justify left bottom)
				(hide yes)
			)
		)
		(property "Val" "100n"
			(at 36.83 61.5885 90)
			(effects
				(font
					(size 1.27 1.27)
					(thickness 0.15)
				)
				(justify right)
			)
		)
		(property "License" "Apache-2.0"
			(at 57.15 42.545 0)
			(effects
				(font
					(size 1.27 1.27)
					(thickness 0.15)
				)
				(justify left bottom)
				(hide yes)
			)
		)
		(property "Author" "Antmicro"
			(at 59.69 42.545 0)
			(effects
				(font
					(size 1.27 1.27)
					(thickness 0.15)
				)
				(justify left bottom)
				(hide yes)
			)
		)
		(property "Voltage" "50V"
			(at 62.23 42.545 0)
			(effects
				(font
					(size 1.27 1.27)
				)
				(justify left bottom)
				(hide yes)
			)
		)
		(property "Dielectric" "X5R"
			(at 64.77 42.545 0)
			(effects
				(font
					(size 1.27 1.27)
				)
				(justify left bottom)
				(hide yes)
			)
		)
		(pin "1"
		)
		(pin "2"
		)
		(instances
			(project "sodimm-ddr5-tester"
				(path ""
					(reference "C170")
					(unit 1)
				)
			)
		)
	)
	(symbol
		(lib_id "antmicroCapacitors0603:C_1u_25V_0603")
		(at 92.71 40.005 90)
		(unit 1)
		(exclude_from_sim no)
		(in_bom yes)
		(on_board yes)
		(dnp no)
		(property "Reference" "C179"
			(at 84.455 40.0147 90)
			(effects
				(font
					(size 1.27 1.27)
				)
				(justify right)
			)
		)
		(property "Value" "C_1u_25V_0603"
			(at 102.87 19.685 0)
			(effects
				(font
					(size 1.27 1.27)
					(thickness 0.15)
				)
				(justify left bottom)
				(hide yes)
			)
		)
		(property "Footprint" "antmicro-footprints:C_0603_1608Metric"
			(at 105.41 19.685 0)
			(effects
				(font
					(size 1.27 1.27)
					(thickness 0.15)
				)
				(justify left bottom)
				(hide yes)
			)
		)
		(property "Datasheet" "https://product.samsungsem.com/mlcc/CL10A105KA8NNN.do"
			(at 107.95 19.685 0)
			(effects
				(font
					(size 1.27 1.27)
					(thickness 0.15)
				)
				(justify left bottom)
				(hide yes)
			)
		)
		(property "Description" ""
			(at 92.71 40.005 0)
			(effects
				(font
					(size 1.27 1.27)
				)
			)
		)
		(property "Manufacturer" "Samsung Electro-Mechanics"
			(at 113.03 19.685 0)
			(effects
				(font
					(size 1.27 1.27)
					(thickness 0.15)
				)
				(justify left bottom)
				(hide yes)
			)
		)
		(property "MPN" "CL10A105KA8NNNC"
			(at 110.49 19.685 0)
			(effects
				(font
					(size 1.27 1.27)
					(thickness 0.15)
				)
				(justify left bottom)
				(hide yes)
			)
		)
		(property "Val" "1u/25V"
			(at 84.455 42.545 90)
			(effects
				(font
					(size 1.27 1.27)
					(thickness 0.15)
				)
				(justify right)
			)
		)
		(property "License" "Apache-2.0"
			(at 115.57 19.685 0)
			(effects
				(font
					(size 1.27 1.27)
					(thickness 0.15)
				)
				(justify left bottom)
				(hide yes)
			)
		)
		(property "Author" "Antmicro"
			(at 118.11 19.685 0)
			(effects
				(font
					(size 1.27 1.27)
					(thickness 0.15)
				)
				(justify left bottom)
				(hide yes)
			)
		)
		(property "Voltage" ""
			(at 120.65 19.685 0)
			(effects
				(font
					(size 1.27 1.27)
				)
				(justify left bottom)
				(hide yes)
			)
		)
		(property "Dielectric" ""
			(at 123.19 19.685 0)
			(effects
				(font
					(size 1.27 1.27)
				)
				(justify left bottom)
				(hide yes)
			)
		)
		(pin "1"
		)
		(pin "2"
		)
		(instances
			(project "sodimm-ddr5-tester"
				(path ""
					(reference "C179")
					(unit 1)
				)
			)
		)
	)
	(symbol
		(lib_id "antmicroCapacitors0402:C_100n_0402")
		(at 346.71 57.15 90)
		(unit 1)
		(exclude_from_sim no)
		(in_bom yes)
		(on_board yes)
		(dnp no)
		(property "Reference" "C209"
			(at 347.345 52.705 90)
			(effects
				(font
					(size 1.27 1.27)
				)
				(justify right)
			)
		)
		(property "Value" "C_100n_0402"
			(at 356.87 36.83 0)
			(effects
				(font
					(size 1.27 1.27)
					(thickness 0.15)
				)
				(justify left bottom)
				(hide yes)
			)
		)
		(property "Footprint" "antmicro-footprints:C_0402_1005Metric"
			(at 359.41 36.83 0)
			(effects
				(font
					(size 1.27 1.27)
					(thickness 0.15)
				)
				(justify left bottom)
				(hide yes)
			)
		)
		(property "Datasheet" "https://www.murata.com/products/productdetail?partno=GRM155R61H104KE14%23"
			(at 361.95 36.83 0)
			(effects
				(font
					(size 1.27 1.27)
					(thickness 0.15)
				)
				(justify left bottom)
				(hide yes)
			)
		)
		(property "Description" ""
			(at 346.71 57.15 0)
			(effects
				(font
					(size 1.27 1.27)
				)
			)
		)
		(property "Manufacturer" "Murata"
			(at 367.03 36.83 0)
			(effects
				(font
					(size 1.27 1.27)
					(thickness 0.15)
				)
				(justify left bottom)
				(hide yes)
			)
		)
		(property "MPN" "GRM155R61H104KE14D"
			(at 364.49 36.83 0)
			(effects
				(font
					(size 1.27 1.27)
					(thickness 0.15)
				)
				(justify left bottom)
				(hide yes)
			)
		)
		(property "Val" "100n"
			(at 347.345 56.515 90)
			(effects
				(font
					(size 1.27 1.27)
					(thickness 0.15)
				)
				(justify right)
			)
		)
		(property "License" "Apache-2.0"
			(at 369.57 36.83 0)
			(effects
				(font
					(size 1.27 1.27)
					(thickness 0.15)
				)
				(justify left bottom)
				(hide yes)
			)
		)
		(property "Author" "Antmicro"
			(at 372.11 36.83 0)
			(effects
				(font
					(size 1.27 1.27)
					(thickness 0.15)
				)
				(justify left bottom)
				(hide yes)
			)
		)
		(property "Voltage" "50V"
			(at 374.65 36.83 0)
			(effects
				(font
					(size 1.27 1.27)
				)
				(justify left bottom)
				(hide yes)
			)
		)
		(property "Dielectric" "X5R"
			(at 377.19 36.83 0)
			(effects
				(font
					(size 1.27 1.27)
				)
				(justify left bottom)
				(hide yes)
			)
		)
		(pin "1"
		)
		(pin "2"
		)
		(instances
			(project "sodimm-ddr5-tester"
				(path ""
					(reference "C209")
					(unit 1)
				)
			)
		)
	)
	(symbol
		(lib_id "antmicropower:GND")
		(at 21.59 186.055 0)
		(unit 1)
		(exclude_from_sim no)
		(in_bom yes)
		(on_board yes)
		(dnp no)
		(fields_autoplaced yes)
		(property "Reference" "#PWR0288"
			(at 21.59 192.405 0)
			(effects
				(font
					(size 1.27 1.27)
				)
				(hide yes)
			)
		)
		(property "Value" "GND"
			(at 24.13 187.325 0)
			(effects
				(font
					(size 1.27 1.27)
					(thickness 0.15)
				)
				(justify left)
			)
		)
		(property "Footprint" ""
			(at 30.48 193.675 0)
			(effects
				(font
					(size 1.27 1.27)
					(thickness 0.15)
				)
				(justify left bottom)
				(hide yes)
			)
		)
		(property "Datasheet" ""
			(at 30.48 198.755 0)
			(effects
				(font
					(size 1.27 1.27)
					(thickness 0.15)
				)
				(justify left bottom)
				(hide yes)
			)
		)
		(property "Description" ""
			(at 30.48 201.295 0)
			(effects
				(font
					(size 1.27 1.27)
				)
				(justify left bottom)
				(hide yes)
			)
		)
		(property "Author" "Antmicro"
			(at 30.48 193.675 0)
			(effects
				(font
					(size 1.27 1.27)
					(thickness 0.15)
				)
				(justify left bottom)
				(hide yes)
			)
		)
		(property "License" "Apache-2.0"
			(at 30.48 196.215 0)
			(effects
				(font
					(size 1.27 1.27)
					(thickness 0.15)
				)
				(justify left bottom)
				(hide yes)
			)
		)
		(pin "1"
		)
		(instances
			(project "sodimm-ddr5-tester"
				(path ""
					(reference "#PWR0288")
					(unit 1)
				)
			)
		)
	)
	(symbol
		(lib_id "antmicroTestPoints:TP_1mm_SMD")
		(at 290.83 274.32 0)
		(unit 1)
		(exclude_from_sim no)
		(in_bom yes)
		(on_board yes)
		(dnp no)
		(property "Reference" "TP59"
			(at 297.688 274.32 0)
			(effects
				(font
					(size 1.27 1.27)
				)
			)
		)
		(property "Value" "TP_1mm_SMD"
			(at 306.07 281.94 0)
			(effects
				(font
					(size 1.27 1.27)
					(thickness 0.15)
				)
				(justify left bottom)
				(hide yes)
			)
		)
		(property "Footprint" "antmicro-footprints:TP_SMD_1mm"
			(at 306.07 284.48 0)
			(effects
				(font
					(size 1.27 1.27)
					(thickness 0.15)
				)
				(justify left bottom)
				(hide yes)
			)
		)
		(property "Datasheet" ""
			(at 306.07 287.02 0)
			(effects
				(font
					(size 1.27 1.27)
					(thickness 0.15)
				)
				(justify left bottom)
				(hide yes)
			)
		)
		(property "Description" ""
			(at 290.83 274.32 0)
			(effects
				(font
					(size 1.27 1.27)
				)
			)
		)
		(property "MPN" ""
			(at 290.83 274.32 0)
			(effects
				(font
					(size 1.27 1.27)
				)
				(hide yes)
			)
		)
		(property "Manufacturer" ""
			(at 290.83 274.32 0)
			(effects
				(font
					(size 1.27 1.27)
				)
				(hide yes)
			)
		)
		(property "Author" "Antmicro"
			(at 306.07 289.56 0)
			(effects
				(font
					(size 1.27 1.27)
					(thickness 0.15)
				)
				(justify left bottom)
				(hide yes)
			)
		)
		(property "License" "Apache-2.0"
			(at 306.07 292.1 0)
			(effects
				(font
					(size 1.27 1.27)
					(thickness 0.15)
				)
				(justify left bottom)
				(hide yes)
			)
		)
		(pin "1"
		)
		(instances
			(project "sodimm-ddr5-tester"
				(path ""
					(reference "TP59")
					(unit 1)
				)
			)
		)
	)
	(symbol
		(lib_id "antmicropower:GND")
		(at 180.34 254 0)
		(mirror y)
		(unit 1)
		(exclude_from_sim no)
		(in_bom yes)
		(on_board yes)
		(dnp no)
		(fields_autoplaced yes)
		(property "Reference" "#PWR0395"
			(at 180.34 260.35 0)
			(effects
				(font
					(size 1.27 1.27)
				)
				(hide yes)
			)
		)
		(property "Value" "GND"
			(at 182.245 255.27 0)
			(effects
				(font
					(size 1.27 1.27)
					(thickness 0.15)
				)
				(justify right)
			)
		)
		(property "Footprint" ""
			(at 171.45 261.62 0)
			(effects
				(font
					(size 1.27 1.27)
					(thickness 0.15)
				)
				(justify left bottom)
				(hide yes)
			)
		)
		(property "Datasheet" ""
			(at 171.45 266.7 0)
			(effects
				(font
					(size 1.27 1.27)
					(thickness 0.15)
				)
				(justify left bottom)
				(hide yes)
			)
		)
		(property "Description" ""
			(at 171.45 269.24 0)
			(effects
				(font
					(size 1.27 1.27)
				)
				(justify left bottom)
				(hide yes)
			)
		)
		(property "Author" "Antmicro"
			(at 171.45 261.62 0)
			(effects
				(font
					(size 1.27 1.27)
					(thickness 0.15)
				)
				(justify left bottom)
				(hide yes)
			)
		)
		(property "License" "Apache-2.0"
			(at 171.45 264.16 0)
			(effects
				(font
					(size 1.27 1.27)
					(thickness 0.15)
				)
				(justify left bottom)
				(hide yes)
			)
		)
		(pin "1"
		)
		(instances
			(project "sodimm-ddr5-tester"
				(path ""
					(reference "#PWR0395")
					(unit 1)
				)
			)
		)
	)
	(symbol
		(lib_id "antmicropower:VDC")
		(at 215.9 156.21 0)
		(unit 1)
		(exclude_from_sim no)
		(in_bom yes)
		(on_board yes)
		(dnp no)
		(fields_autoplaced yes)
		(property "Reference" "#PWR0289"
			(at 215.9 158.75 0)
			(effects
				(font
					(size 1.27 1.27)
				)
				(hide yes)
			)
		)
		(property "Value" "VDC"
			(at 215.9 151.13 0)
			(effects
				(font
					(size 1.27 1.27)
				)
			)
		)
		(property "Footprint" ""
			(at 215.9 156.21 0)
			(effects
				(font
					(size 1.27 1.27)
				)
				(hide yes)
			)
		)
		(property "Datasheet" ""
			(at 215.9 156.21 0)
			(effects
				(font
					(size 1.27 1.27)
				)
				(hide yes)
			)
		)
		(property "Description" ""
			(at 215.9 156.21 0)
			(effects
				(font
					(size 1.27 1.27)
				)
			)
		)
		(pin "1"
		)
		(instances
			(project "sodimm-ddr5-tester"
				(path ""
					(reference "#PWR0289")
					(unit 1)
				)
			)
		)
	)
	(symbol
		(lib_id "antmicropower:PWR_FLAG")
		(at 123.825 157.48 0)
		(unit 1)
		(exclude_from_sim no)
		(in_bom yes)
		(on_board yes)
		(dnp no)
		(fields_autoplaced yes)
		(property "Reference" "#FLG0111"
			(at 123.825 155.575 0)
			(effects
				(font
					(size 1.27 1.27)
				)
				(hide yes)
			)
		)
		(property "Value" "PWR_FLAG"
			(at 123.825 153.9042 0)
			(effects
				(font
					(size 1.27 1.27)
				)
			)
		)
		(property "Footprint" ""
			(at 123.825 157.48 0)
			(effects
				(font
					(size 1.27 1.27)
				)
				(hide yes)
			)
		)
		(property "Datasheet" ""
			(at 123.825 157.48 0)
			(effects
				(font
					(size 1.27 1.27)
				)
				(hide yes)
			)
		)
		(property "Description" ""
			(at 123.825 157.48 0)
			(effects
				(font
					(size 1.27 1.27)
				)
			)
		)
		(pin "1"
		)
		(instances
			(project "sodimm-ddr5-tester"
				(path ""
					(reference "#FLG0111")
					(unit 1)
				)
			)
		)
	)
	(symbol
		(lib_id "antmicroCapacitors0603:C_22u_0603")
		(at 86.995 165.735 90)
		(unit 1)
		(exclude_from_sim no)
		(in_bom yes)
		(on_board yes)
		(dnp no)
		(fields_autoplaced yes)
		(property "Reference" "C186"
			(at 89.3191 162.358 90)
			(effects
				(font
					(size 1.27 1.27)
				)
				(justify right)
			)
		)
		(property "Value" "C_22u_0603"
			(at 97.155 145.415 0)
			(effects
				(font
					(size 1.27 1.27)
					(thickness 0.15)
				)
				(justify left bottom)
				(hide yes)
			)
		)
		(property "Footprint" "antmicro-footprints:C_0603_1608Metric"
			(at 99.695 145.415 0)
			(effects
				(font
					(size 1.27 1.27)
					(thickness 0.15)
				)
				(justify left bottom)
				(hide yes)
			)
		)
		(property "Datasheet" "https://www.murata.com/products/productdetail?partno=GRM188R60J226MEA0%23"
			(at 102.235 145.415 0)
			(effects
				(font
					(size 1.27 1.27)
					(thickness 0.15)
				)
				(justify left bottom)
				(hide yes)
			)
		)
		(property "Description" ""
			(at 86.995 165.735 0)
			(effects
				(font
					(size 1.27 1.27)
				)
			)
		)
		(property "Manufacturer" "Murata"
			(at 107.315 145.415 0)
			(effects
				(font
					(size 1.27 1.27)
					(thickness 0.15)
				)
				(justify left bottom)
				(hide yes)
			)
		)
		(property "MPN" "GRM188R60J226MEA0D"
			(at 104.775 145.415 0)
			(effects
				(font
					(size 1.27 1.27)
					(thickness 0.15)
				)
				(justify left bottom)
				(hide yes)
			)
		)
		(property "Val" "22u"
			(at 89.3191 164.8883 90)
			(effects
				(font
					(size 1.27 1.27)
					(thickness 0.15)
				)
				(justify right)
			)
		)
		(property "License" "Apache-2.0"
			(at 109.855 145.415 0)
			(effects
				(font
					(size 1.27 1.27)
					(thickness 0.15)
				)
				(justify left bottom)
				(hide yes)
			)
		)
		(property "Author" "Antmicro"
			(at 112.395 145.415 0)
			(effects
				(font
					(size 1.27 1.27)
					(thickness 0.15)
				)
				(justify left bottom)
				(hide yes)
			)
		)
		(property "Voltage" ""
			(at 114.935 145.415 0)
			(effects
				(font
					(size 1.27 1.27)
				)
				(justify left bottom)
				(hide yes)
			)
		)
		(property "Dielectric" ""
			(at 117.475 145.415 0)
			(effects
				(font
					(size 1.27 1.27)
				)
				(justify left bottom)
				(hide yes)
			)
		)
		(pin "1"
		)
		(pin "2"
		)
		(instances
			(project "sodimm-ddr5-tester"
				(path ""
					(reference "C186")
					(unit 1)
				)
			)
		)
	)
	(symbol
		(lib_id "antmicroPowerMeasurement:PAC1954T-E_VQFN")
		(at 366.395 98.425 0)
		(unit 1)
		(exclude_from_sim no)
		(in_bom yes)
		(on_board yes)
		(dnp no)
		(fields_autoplaced yes)
		(property "Reference" "U30"
			(at 379.095 90.805 0)
			(effects
				(font
					(size 1.27 1.27)
				)
			)
		)
		(property "Value" "PAC1954T-E_VQFN"
			(at 379.095 93.345 0)
			(effects
				(font
					(size 1.27 1.27)
					(thickness 0.15)
				)
			)
		)
		(property "Footprint" "antmicro-footprints:VQFN-16-1EP_3x3mm_P0.5mm_EP1.1x1.1mm"
			(at 404.495 106.045 0)
			(effects
				(font
					(size 1.27 1.27)
					(thickness 0.15)
				)
				(justify left bottom)
				(hide yes)
			)
		)
		(property "Datasheet" "https://ww1.microchip.com/downloads/aemDocuments/documents/MSLD/ProductDocuments/DataSheets/PAC195X-Family-Data-Sheet-DS20006539.pdf"
			(at 404.495 108.585 0)
			(effects
				(font
					(size 1.27 1.27)
					(thickness 0.15)
				)
				(justify left bottom)
				(hide yes)
			)
		)
		(property "Description" ""
			(at 366.395 98.425 0)
			(effects
				(font
					(size 1.27 1.27)
				)
			)
		)
		(property "MPN" "PAC1954T-E/4MX"
			(at 379.095 93.345 0)
			(effects
				(font
					(size 1.27 1.27)
					(thickness 0.15)
				)
				(hide yes)
			)
		)
		(property "Manufacturer" "Microchip Technology"
			(at 404.495 113.665 0)
			(effects
				(font
					(size 1.27 1.27)
					(thickness 0.15)
				)
				(justify left bottom)
				(hide yes)
			)
		)
		(property "Author" "Antmicro"
			(at 404.495 116.205 0)
			(effects
				(font
					(size 1.27 1.27)
					(thickness 0.15)
				)
				(justify left bottom)
				(hide yes)
			)
		)
		(property "License" "Apache-2.0"
			(at 404.495 118.745 0)
			(effects
				(font
					(size 1.27 1.27)
					(thickness 0.15)
				)
				(justify left bottom)
				(hide yes)
			)
		)
		(pin "1"
		)
		(pin "10"
		)
		(pin "11"
		)
		(pin "12"
		)
		(pin "13"
		)
		(pin "14"
		)
		(pin "15"
		)
		(pin "16"
		)
		(pin "17"
		)
		(pin "2"
		)
		(pin "3"
		)
		(pin "4"
		)
		(pin "5"
		)
		(pin "6"
		)
		(pin "7"
		)
		(pin "8"
		)
		(pin "9"
		)
		(instances
			(project "sodimm-ddr5-tester"
				(path ""
					(reference "U30")
					(unit 1)
				)
			)
		)
	)
	(symbol
		(lib_id "antmicroCapacitors0603:C_22u_0603")
		(at 114.935 114.3 90)
		(unit 1)
		(exclude_from_sim no)
		(in_bom yes)
		(on_board yes)
		(dnp no)
		(property "Reference" "C219"
			(at 115.57 109.855 90)
			(effects
				(font
					(size 1.27 1.27)
				)
				(justify right)
			)
		)
		(property "Value" "C_22u_0603"
			(at 125.095 93.98 0)
			(effects
				(font
					(size 1.27 1.27)
					(thickness 0.15)
				)
				(justify left bottom)
				(hide yes)
			)
		)
		(property "Footprint" "antmicro-footprints:C_0603_1608Metric"
			(at 127.635 93.98 0)
			(effects
				(font
					(size 1.27 1.27)
					(thickness 0.15)
				)
				(justify left bottom)
				(hide yes)
			)
		)
		(property "Datasheet" "https://www.murata.com/products/productdetail?partno=GRM188R60J226MEA0%23"
			(at 130.175 93.98 0)
			(effects
				(font
					(size 1.27 1.27)
					(thickness 0.15)
				)
				(justify left bottom)
				(hide yes)
			)
		)
		(property "Description" ""
			(at 114.935 114.3 0)
			(effects
				(font
					(size 1.27 1.27)
				)
			)
		)
		(property "Manufacturer" "Murata"
			(at 135.255 93.98 0)
			(effects
				(font
					(size 1.27 1.27)
					(thickness 0.15)
				)
				(justify left bottom)
				(hide yes)
			)
		)
		(property "MPN" "GRM188R60J226MEA0D"
			(at 132.715 93.98 0)
			(effects
				(font
					(size 1.27 1.27)
					(thickness 0.15)
				)
				(justify left bottom)
				(hide yes)
			)
		)
		(property "Val" "22u"
			(at 115.57 113.665 90)
			(effects
				(font
					(size 1.27 1.27)
					(thickness 0.15)
				)
				(justify right)
			)
		)
		(property "License" "Apache-2.0"
			(at 137.795 93.98 0)
			(effects
				(font
					(size 1.27 1.27)
					(thickness 0.15)
				)
				(justify left bottom)
				(hide yes)
			)
		)
		(property "Author" "Antmicro"
			(at 140.335 93.98 0)
			(effects
				(font
					(size 1.27 1.27)
					(thickness 0.15)
				)
				(justify left bottom)
				(hide yes)
			)
		)
		(property "Voltage" ""
			(at 142.875 93.98 0)
			(effects
				(font
					(size 1.27 1.27)
				)
				(justify left bottom)
				(hide yes)
			)
		)
		(property "Dielectric" ""
			(at 145.415 93.98 0)
			(effects
				(font
					(size 1.27 1.27)
				)
				(justify left bottom)
				(hide yes)
			)
		)
		(pin "1"
		)
		(pin "2"
		)
		(instances
			(project "sodimm-ddr5-tester"
				(path ""
					(reference "C219")
					(unit 1)
				)
			)
		)
	)
	(symbol
		(lib_id "antmicropower:GND")
		(at 236.22 127 0)
		(unit 1)
		(exclude_from_sim no)
		(in_bom yes)
		(on_board yes)
		(dnp no)
		(property "Reference" "#PWR0303"
			(at 236.22 133.35 0)
			(effects
				(font
					(size 1.27 1.27)
				)
				(hide yes)
			)
		)
		(property "Value" "GND"
			(at 234.315 131.445 0)
			(effects
				(font
					(size 1.27 1.27)
					(thickness 0.15)
				)
				(justify left bottom)
			)
		)
		(property "Footprint" ""
			(at 245.11 134.62 0)
			(effects
				(font
					(size 1.27 1.27)
					(thickness 0.15)
				)
				(justify left bottom)
				(hide yes)
			)
		)
		(property "Datasheet" ""
			(at 245.11 139.7 0)
			(effects
				(font
					(size 1.27 1.27)
					(thickness 0.15)
				)
				(justify left bottom)
				(hide yes)
			)
		)
		(property "Description" ""
			(at 245.11 142.24 0)
			(effects
				(font
					(size 1.27 1.27)
				)
				(justify left bottom)
				(hide yes)
			)
		)
		(property "Author" "Antmicro"
			(at 245.11 134.62 0)
			(effects
				(font
					(size 1.27 1.27)
					(thickness 0.15)
				)
				(justify left bottom)
				(hide yes)
			)
		)
		(property "License" "Apache-2.0"
			(at 245.11 137.16 0)
			(effects
				(font
					(size 1.27 1.27)
					(thickness 0.15)
				)
				(justify left bottom)
				(hide yes)
			)
		)
		(pin "1"
		)
		(instances
			(project "sodimm-ddr5-tester"
				(path ""
					(reference "#PWR0303")
					(unit 1)
				)
			)
		)
	)
	(symbol
		(lib_id "antmicropower:GND")
		(at 17.145 167.64 0)
		(unit 1)
		(exclude_from_sim no)
		(in_bom yes)
		(on_board yes)
		(dnp no)
		(fields_autoplaced yes)
		(property "Reference" "#PWR0287"
			(at 17.145 173.99 0)
			(effects
				(font
					(size 1.27 1.27)
				)
				(hide yes)
			)
		)
		(property "Value" "GND"
			(at 19.05 168.91 0)
			(effects
				(font
					(size 1.27 1.27)
					(thickness 0.15)
				)
				(justify left)
			)
		)
		(property "Footprint" ""
			(at 26.035 175.26 0)
			(effects
				(font
					(size 1.27 1.27)
					(thickness 0.15)
				)
				(justify left bottom)
				(hide yes)
			)
		)
		(property "Datasheet" ""
			(at 26.035 180.34 0)
			(effects
				(font
					(size 1.27 1.27)
					(thickness 0.15)
				)
				(justify left bottom)
				(hide yes)
			)
		)
		(property "Description" ""
			(at 26.035 182.88 0)
			(effects
				(font
					(size 1.27 1.27)
				)
				(justify left bottom)
				(hide yes)
			)
		)
		(property "Author" "Antmicro"
			(at 26.035 175.26 0)
			(effects
				(font
					(size 1.27 1.27)
					(thickness 0.15)
				)
				(justify left bottom)
				(hide yes)
			)
		)
		(property "License" "Apache-2.0"
			(at 26.035 177.8 0)
			(effects
				(font
					(size 1.27 1.27)
					(thickness 0.15)
				)
				(justify left bottom)
				(hide yes)
			)
		)
		(pin "1"
		)
		(instances
			(project "sodimm-ddr5-tester"
				(path ""
					(reference "#PWR0287")
					(unit 1)
				)
			)
		)
	)
	(symbol
		(lib_id "antmicroTestPoints:TP_1206_SMD_RCW-0C")
		(at 375.285 243.205 0)
		(unit 1)
		(exclude_from_sim no)
		(in_bom yes)
		(on_board yes)
		(dnp no)
		(fields_autoplaced yes)
		(property "Reference" "TP20"
			(at 379.857 242.3744 0)
			(effects
				(font
					(size 1.27 1.27)
					(thickness 0.15)
				)
				(justify left)
			)
		)
		(property "Value" "TP_1206_SMD_RCW-0C"
			(at 379.857 244.8981 0)
			(effects
				(font
					(size 1.27 1.27)
					(thickness 0.15)
				)
				(justify left)
			)
		)
		(property "Footprint" "antmicro-footprints:TP_1206_SMD_RCW-0C"
			(at 393.065 253.365 0)
			(effects
				(font
					(size 1.27 1.27)
					(thickness 0.15)
				)
				(justify left bottom)
				(hide yes)
			)
		)
		(property "Datasheet" "https://www.te.com/commerce/DocumentDelivery/DDEController?Action=srchrtrv&DocNm=1773266&DocType=DS&DocLang=English"
			(at 393.065 255.905 0)
			(effects
				(font
					(size 1.27 1.27)
					(thickness 0.15)
				)
				(justify left bottom)
				(hide yes)
			)
		)
		(property "Description" ""
			(at 375.285 243.205 0)
			(effects
				(font
					(size 1.27 1.27)
				)
			)
		)
		(property "MPN" "RCW-0C"
			(at 393.065 258.445 0)
			(effects
				(font
					(size 1.27 1.27)
					(thickness 0.15)
				)
				(justify left bottom)
				(hide yes)
			)
		)
		(property "Manufacturer" "TE Connectivity"
			(at 393.065 260.985 0)
			(effects
				(font
					(size 1.27 1.27)
					(thickness 0.15)
				)
				(justify left bottom)
				(hide yes)
			)
		)
		(property "Author" "Antmicro"
			(at 393.065 263.525 0)
			(effects
				(font
					(size 1.27 1.27)
					(thickness 0.15)
				)
				(justify left bottom)
				(hide yes)
			)
		)
		(property "License" "Apache-2.0"
			(at 393.065 266.065 0)
			(effects
				(font
					(size 1.27 1.27)
					(thickness 0.15)
				)
				(justify left bottom)
				(hide yes)
			)
		)
		(pin "1"
		)
		(instances
			(project "sodimm-ddr5-tester"
				(path ""
					(reference "TP20")
					(unit 1)
				)
			)
		)
	)
	(symbol
		(lib_id "antmicroCapacitors0402:C_100n_0402")
		(at 353.06 128.905 270)
		(unit 1)
		(exclude_from_sim no)
		(in_bom yes)
		(on_board yes)
		(dnp no)
		(fields_autoplaced yes)
		(property "Reference" "C214"
			(at 350.52 130.1813 90)
			(effects
				(font
					(size 1.27 1.27)
				)
				(justify right)
			)
		)
		(property "Value" "C_100n_0402"
			(at 342.9 149.225 0)
			(effects
				(font
					(size 1.27 1.27)
					(thickness 0.15)
				)
				(justify left bottom)
				(hide yes)
			)
		)
		(property "Footprint" "antmicro-footprints:C_0402_1005Metric"
			(at 340.36 149.225 0)
			(effects
				(font
					(size 1.27 1.27)
					(thickness 0.15)
				)
				(justify left bottom)
				(hide yes)
			)
		)
		(property "Datasheet" "https://www.murata.com/products/productdetail?partno=GRM155R61H104KE14%23"
			(at 337.82 149.225 0)
			(effects
				(font
					(size 1.27 1.27)
					(thickness 0.15)
				)
				(justify left bottom)
				(hide yes)
			)
		)
		(property "Description" ""
			(at 353.06 128.905 0)
			(effects
				(font
					(size 1.27 1.27)
				)
			)
		)
		(property "Manufacturer" "Murata"
			(at 332.74 149.225 0)
			(effects
				(font
					(size 1.27 1.27)
					(thickness 0.15)
				)
				(justify left bottom)
				(hide yes)
			)
		)
		(property "MPN" "GRM155R61H104KE14D"
			(at 335.28 149.225 0)
			(effects
				(font
					(size 1.27 1.27)
					(thickness 0.15)
				)
				(justify left bottom)
				(hide yes)
			)
		)
		(property "Val" "100n"
			(at 350.52 133.3562 90)
			(effects
				(font
					(size 1.27 1.27)
					(thickness 0.15)
				)
				(justify right)
			)
		)
		(property "License" "Apache-2.0"
			(at 330.2 149.225 0)
			(effects
				(font
					(size 1.27 1.27)
					(thickness 0.15)
				)
				(justify left bottom)
				(hide yes)
			)
		)
		(property "Author" "Antmicro"
			(at 327.66 149.225 0)
			(effects
				(font
					(size 1.27 1.27)
					(thickness 0.15)
				)
				(justify left bottom)
				(hide yes)
			)
		)
		(property "Voltage" "50V"
			(at 325.12 149.225 0)
			(effects
				(font
					(size 1.27 1.27)
				)
				(justify left bottom)
				(hide yes)
			)
		)
		(property "Dielectric" "X5R"
			(at 322.58 149.225 0)
			(effects
				(font
					(size 1.27 1.27)
				)
				(justify left bottom)
				(hide yes)
			)
		)
		(pin "1"
		)
		(pin "2"
		)
		(instances
			(project "sodimm-ddr5-tester"
				(path ""
					(reference "C214")
					(unit 1)
				)
			)
		)
	)
	(symbol
		(lib_id "antmicroTestPoints:TP_1mm_SMD")
		(at 180.34 278.13 270)
		(unit 1)
		(exclude_from_sim no)
		(in_bom yes)
		(on_board yes)
		(dnp no)
		(property "Reference" "TP31"
			(at 180.34 283.1028 90)
			(effects
				(font
					(size 1.27 1.27)
				)
			)
		)
		(property "Value" "TP_1mm_SMD"
			(at 172.72 293.37 0)
			(effects
				(font
					(size 1.27 1.27)
					(thickness 0.15)
				)
				(justify left bottom)
				(hide yes)
			)
		)
		(property "Footprint" "antmicro-footprints:TP_SMD_1mm"
			(at 170.18 293.37 0)
			(effects
				(font
					(size 1.27 1.27)
					(thickness 0.15)
				)
				(justify left bottom)
				(hide yes)
			)
		)
		(property "Datasheet" ""
			(at 167.64 293.37 0)
			(effects
				(font
					(size 1.27 1.27)
					(thickness 0.15)
				)
				(justify left bottom)
				(hide yes)
			)
		)
		(property "Description" ""
			(at 180.34 278.13 0)
			(effects
				(font
					(size 1.27 1.27)
				)
			)
		)
		(property "MPN" ""
			(at 180.34 278.13 0)
			(effects
				(font
					(size 1.27 1.27)
				)
				(hide yes)
			)
		)
		(property "Manufacturer" ""
			(at 180.34 278.13 0)
			(effects
				(font
					(size 1.27 1.27)
				)
				(hide yes)
			)
		)
		(property "Author" "Antmicro"
			(at 165.1 293.37 0)
			(effects
				(font
					(size 1.27 1.27)
					(thickness 0.15)
				)
				(justify left bottom)
				(hide yes)
			)
		)
		(property "License" "Apache-2.0"
			(at 162.56 293.37 0)
			(effects
				(font
					(size 1.27 1.27)
					(thickness 0.15)
				)
				(justify left bottom)
				(hide yes)
			)
		)
		(pin "1"
		)
		(instances
			(project "sodimm-ddr5-tester"
				(path ""
					(reference "TP31")
					(unit 1)
				)
			)
		)
	)
	(symbol
		(lib_id "antmicroTransistorsFETsMOSFETsSingle:SI7613DN-T1-GE3")
		(at 88.265 62.865 90)
		(unit 1)
		(exclude_from_sim no)
		(in_bom yes)
		(on_board yes)
		(dnp no)
		(fields_autoplaced yes)
		(property "Reference" "Q13"
			(at 85.725 49.5214 90)
			(effects
				(font
					(size 1.27 1.27)
				)
			)
		)
		(property "Value" "SI7613DN-T1-GE3"
			(at 85.725 52.0517 90)
			(effects
				(font
					(size 1.27 1.27)
					(thickness 0.15)
				)
			)
		)
		(property "Footprint" "antmicro-footprints:Vishay_PowerPAK_1212-8_Single"
			(at 86.995 47.625 0)
			(effects
				(font
					(size 1.27 1.27)
					(thickness 0.15)
				)
				(justify left bottom)
				(hide yes)
			)
		)
		(property "Datasheet" "https://www.vishay.com/docs/64809/si7613dn.pdf"
			(at 89.535 47.625 0)
			(effects
				(font
					(size 1.27 1.27)
					(thickness 0.15)
				)
				(justify left bottom)
				(hide yes)
			)
		)
		(property "Description" ""
			(at 88.265 62.865 0)
			(effects
				(font
					(size 1.27 1.27)
				)
			)
		)
		(property "MPN" "SI7613DN-T1-GE3"
			(at 93.345 47.625 0)
			(effects
				(font
					(size 1.27 1.27)
					(thickness 0.15)
				)
				(justify left bottom)
				(hide yes)
			)
		)
		(property "Manufacturer" "Vishay"
			(at 95.885 47.625 0)
			(effects
				(font
					(size 1.27 1.27)
					(thickness 0.15)
				)
				(justify left bottom)
				(hide yes)
			)
		)
		(property "Author" "Antmicro"
			(at 98.425 47.625 0)
			(effects
				(font
					(size 1.27 1.27)
					(thickness 0.15)
				)
				(justify left bottom)
				(hide yes)
			)
		)
		(property "License" "Apache-2.0"
			(at 100.965 47.625 0)
			(effects
				(font
					(size 1.27 1.27)
					(thickness 0.15)
				)
				(justify left bottom)
				(hide yes)
			)
		)
		(pin "1"
		)
		(pin "2"
		)
		(pin "3"
		)
		(pin "4"
		)
		(pin "5"
		)
		(instances
			(project "sodimm-ddr5-tester"
				(path ""
					(reference "Q13")
					(unit 1)
				)
			)
		)
	)
	(symbol
		(lib_id "antmicropower:PWR_FLAG")
		(at 316.865 157.48 0)
		(unit 1)
		(exclude_from_sim no)
		(in_bom yes)
		(on_board yes)
		(dnp no)
		(fields_autoplaced yes)
		(property "Reference" "#FLG0116"
			(at 316.865 155.575 0)
			(effects
				(font
					(size 1.27 1.27)
				)
				(hide yes)
			)
		)
		(property "Value" "PWR_FLAG"
			(at 316.865 153.9042 0)
			(effects
				(font
					(size 1.27 1.27)
				)
			)
		)
		(property "Footprint" ""
			(at 316.865 157.48 0)
			(effects
				(font
					(size 1.27 1.27)
				)
				(hide yes)
			)
		)
		(property "Datasheet" ""
			(at 316.865 157.48 0)
			(effects
				(font
					(size 1.27 1.27)
				)
				(hide yes)
			)
		)
		(property "Description" ""
			(at 316.865 157.48 0)
			(effects
				(font
					(size 1.27 1.27)
				)
			)
		)
		(pin "1"
		)
		(instances
			(project "sodimm-ddr5-tester"
				(path ""
					(reference "#FLG0116")
					(unit 1)
				)
			)
		)
	)
	(symbol
		(lib_id "antmicroWire2BoardConnectors:JST_SH_1x4_BM04B-SRSS-TB-LF-SN")
		(at 249.555 250.825 0)
		(unit 1)
		(exclude_from_sim no)
		(in_bom yes)
		(on_board yes)
		(dnp no)
		(property "Reference" "J8"
			(at 252.222 248.158 0)
			(effects
				(font
					(size 1.27 1.27)
					(thickness 0.15)
				)
				(justify left)
			)
		)
		(property "Value" "JST_SH_1x4_BM04B-SRSS-TB-LF-SN"
			(at 269.875 258.445 0)
			(effects
				(font
					(size 1.27 1.27)
					(thickness 0.15)
				)
				(justify left bottom)
				(hide yes)
			)
		)
		(property "Footprint" "antmicro-footprints:Conn_JST_SH_1x4_BM04B-SRSS-TB-LF-SN"
			(at 269.875 260.985 0)
			(effects
				(font
					(size 1.27 1.27)
					(thickness 0.15)
				)
				(justify left bottom)
				(hide yes)
			)
		)
		(property "Datasheet" "https://www.jst-mfg.com/product/pdf/eng/eSH.pdf"
			(at 269.875 263.525 0)
			(effects
				(font
					(size 1.27 1.27)
					(thickness 0.15)
				)
				(justify left bottom)
				(hide yes)
			)
		)
		(property "Description" ""
			(at 249.555 250.825 0)
			(effects
				(font
					(size 1.27 1.27)
				)
			)
		)
		(property "MPN" "BM04B-SRSS-TB(LF)(SN) "
			(at 257.048 267.97 90)
			(effects
				(font
					(size 1.27 1.27)
					(thickness 0.15)
				)
				(justify left)
			)
		)
		(property "Manufacturer" "JST Automotive Connectors"
			(at 269.875 268.605 0)
			(effects
				(font
					(size 1.27 1.27)
					(thickness 0.15)
				)
				(justify left bottom)
				(hide yes)
			)
		)
		(property "Author" "Antmicro"
			(at 269.875 271.145 0)
			(effects
				(font
					(size 1.27 1.27)
					(thickness 0.15)
				)
				(justify left bottom)
				(hide yes)
			)
		)
		(property "License" "Apache-2.0"
			(at 269.875 273.685 0)
			(effects
				(font
					(size 1.27 1.27)
					(thickness 0.15)
				)
				(justify left bottom)
				(hide yes)
			)
		)
		(pin "1"
		)
		(pin "2"
		)
		(pin "3"
		)
		(pin "4"
		)
		(pin "MP"
		)
		(instances
			(project "sodimm-ddr5-tester"
				(path ""
					(reference "J8")
					(unit 1)
				)
			)
		)
	)
	(symbol
		(lib_id "antmicroCapacitors0402:C_100n_0402")
		(at 286.893 34.29 90)
		(mirror x)
		(unit 1)
		(exclude_from_sim no)
		(in_bom yes)
		(on_board yes)
		(dnp no)
		(fields_autoplaced yes)
		(property "Reference" "C203"
			(at 284.5689 36.0057 90)
			(effects
				(font
					(size 1.27 1.27)
				)
				(justify left)
			)
		)
		(property "Value" "C_100n_0402"
			(at 297.053 54.61 0)
			(effects
				(font
					(size 1.27 1.27)
					(thickness 0.15)
				)
				(justify left bottom)
				(hide yes)
			)
		)
		(property "Footprint" "antmicro-footprints:C_0402_1005Metric"
			(at 299.593 54.61 0)
			(effects
				(font
					(size 1.27 1.27)
					(thickness 0.15)
				)
				(justify left bottom)
				(hide yes)
			)
		)
		(property "Datasheet" "https://www.murata.com/products/productdetail?partno=GRM155R61H104KE14%23"
			(at 302.133 54.61 0)
			(effects
				(font
					(size 1.27 1.27)
					(thickness 0.15)
				)
				(justify left bottom)
				(hide yes)
			)
		)
		(property "Description" ""
			(at 286.893 34.29 0)
			(effects
				(font
					(size 1.27 1.27)
				)
			)
		)
		(property "Manufacturer" "Murata"
			(at 307.213 54.61 0)
			(effects
				(font
					(size 1.27 1.27)
					(thickness 0.15)
				)
				(justify left bottom)
				(hide yes)
			)
		)
		(property "MPN" "GRM155R61H104KE14D"
			(at 304.673 54.61 0)
			(effects
				(font
					(size 1.27 1.27)
					(thickness 0.15)
				)
				(justify left bottom)
				(hide yes)
			)
		)
		(property "Val" "100n"
			(at 284.5689 38.7642 90)
			(effects
				(font
					(size 1.27 1.27)
					(thickness 0.15)
				)
				(justify left)
			)
		)
		(property "License" "Apache-2.0"
			(at 309.753 54.61 0)
			(effects
				(font
					(size 1.27 1.27)
					(thickness 0.15)
				)
				(justify left bottom)
				(hide yes)
			)
		)
		(property "Author" "Antmicro"
			(at 312.293 54.61 0)
			(effects
				(font
					(size 1.27 1.27)
					(thickness 0.15)
				)
				(justify left bottom)
				(hide yes)
			)
		)
		(property "Voltage" "50V"
			(at 314.833 54.61 0)
			(effects
				(font
					(size 1.27 1.27)
				)
				(justify left bottom)
				(hide yes)
			)
		)
		(property "Dielectric" "X5R"
			(at 317.373 54.61 0)
			(effects
				(font
					(size 1.27 1.27)
				)
				(justify left bottom)
				(hide yes)
			)
		)
		(pin "1"
		)
		(pin "2"
		)
		(instances
			(project "sodimm-ddr5-tester"
				(path ""
					(reference "C203")
					(unit 1)
				)
			)
		)
	)
	(symbol
		(lib_id "antmicroShuntsJumpers:Net-Tie_P0.127mm")
		(at 110.49 162.56 90)
		(unit 1)
		(exclude_from_sim no)
		(in_bom no)
		(on_board yes)
		(dnp no)
		(fields_autoplaced yes)
		(property "Reference" "NT1"
			(at 109.22 162.56 0)
			(effects
				(font
					(size 1.27 1.27)
				)
				(hide yes)
			)
		)
		(property "Value" "Net-Tie_P0.127mm"
			(at 118.11 140.97 0)
			(effects
				(font
					(size 1.27 1.27)
					(thickness 0.15)
				)
				(justify left bottom)
				(hide yes)
			)
		)
		(property "Footprint" "antmicro-footprints:NetTie-2_SMD_Pad0.127mm"
			(at 123.19 140.97 0)
			(effects
				(font
					(size 1.27 1.27)
					(thickness 0.15)
				)
				(justify left bottom)
				(hide yes)
			)
		)
		(property "Datasheet" ""
			(at 125.73 140.97 0)
			(effects
				(font
					(size 1.27 1.27)
					(thickness 0.15)
				)
				(justify left bottom)
				(hide yes)
			)
		)
		(property "Description" ""
			(at 110.49 162.56 0)
			(effects
				(font
					(size 1.27 1.27)
				)
			)
		)
		(property "MPN" ""
			(at 120.65 140.97 0)
			(effects
				(font
					(size 1.27 1.27)
					(thickness 0.15)
				)
				(justify left bottom)
			)
		)
		(property "Manufacturer" ""
			(at 128.27 140.97 0)
			(effects
				(font
					(size 1.27 1.27)
					(thickness 0.15)
				)
				(justify left bottom)
				(hide yes)
			)
		)
		(property "Author" "Antmicro"
			(at 130.81 140.97 0)
			(effects
				(font
					(size 1.27 1.27)
					(thickness 0.15)
				)
				(justify left bottom)
				(hide yes)
			)
		)
		(property "License" "Apache-2.0"
			(at 133.35 140.97 0)
			(effects
				(font
					(size 1.27 1.27)
					(thickness 0.15)
				)
				(justify left bottom)
				(hide yes)
			)
		)
		(pin "1"
		)
		(pin "2"
		)
		(instances
			(project "sodimm-ddr5-tester"
				(path ""
					(reference "NT1")
					(unit 1)
				)
			)
		)
	)
	(symbol
		(lib_id "antmicroTransistorsFETsMOSFETsSingle:BSS138PW,115")
		(at 261.62 53.34 0)
		(unit 1)
		(exclude_from_sim no)
		(in_bom yes)
		(on_board yes)
		(dnp no)
		(property "Reference" "Q16"
			(at 271.526 52.07 0)
			(effects
				(font
					(size 1.27 1.27)
					(thickness 0.15)
				)
				(justify left)
			)
		)
		(property "Value" "BSS138PW,115"
			(at 284.48 62.23 0)
			(effects
				(font
					(size 1.27 1.27)
					(thickness 0.15)
				)
				(justify left bottom)
				(hide yes)
			)
		)
		(property "Footprint" "antmicro-footprints:SC70-3"
			(at 284.48 64.77 0)
			(effects
				(font
					(size 1.27 1.27)
					(thickness 0.15)
				)
				(justify left bottom)
				(hide yes)
			)
		)
		(property "Datasheet" "https://assets.nexperia.com/documents/data-sheet/BSS138PW.pdf"
			(at 284.48 67.31 0)
			(effects
				(font
					(size 1.27 1.27)
					(thickness 0.15)
				)
				(justify left bottom)
				(hide yes)
			)
		)
		(property "Description" "Power MOSFET, N Channel, 60 V, 320 mA, 0.9 ohm, SOT-323, Surface Mount"
			(at 284.48 80.01 0)
			(effects
				(font
					(size 1.27 1.27)
				)
				(justify left bottom)
				(hide yes)
			)
		)
		(property "MPN" "BSS138PW,115"
			(at 269.494 54.356 0)
			(effects
				(font
					(size 1.27 1.27)
					(thickness 0.15)
				)
				(justify left)
			)
		)
		(property "Manufacturer" "Nexperia"
			(at 284.48 72.39 0)
			(effects
				(font
					(size 1.27 1.27)
					(thickness 0.15)
				)
				(justify left bottom)
				(hide yes)
			)
		)
		(property "Author" "Antmicro"
			(at 284.48 74.93 0)
			(effects
				(font
					(size 1.27 1.27)
					(thickness 0.15)
				)
				(justify left bottom)
				(hide yes)
			)
		)
		(property "License" "Apache-2.0"
			(at 284.48 77.47 0)
			(effects
				(font
					(size 1.27 1.27)
					(thickness 0.15)
				)
				(justify left bottom)
				(hide yes)
			)
		)
		(pin "3"
		)
		(pin "2"
		)
		(pin "1"
		)
		(instances
			(project "sodimm-ddr5-tester"
				(path ""
					(reference "Q16")
					(unit 1)
				)
			)
		)
	)
	(symbol
		(lib_id "antmicropower:GND")
		(at 189.865 186.69 0)
		(unit 1)
		(exclude_from_sim no)
		(in_bom yes)
		(on_board yes)
		(dnp no)
		(fields_autoplaced yes)
		(property "Reference" "#PWR0342"
			(at 189.865 193.04 0)
			(effects
				(font
					(size 1.27 1.27)
				)
				(hide yes)
			)
		)
		(property "Value" "GND"
			(at 191.77 187.96 0)
			(effects
				(font
					(size 1.27 1.27)
					(thickness 0.15)
				)
				(justify left)
			)
		)
		(property "Footprint" ""
			(at 198.755 194.31 0)
			(effects
				(font
					(size 1.27 1.27)
					(thickness 0.15)
				)
				(justify left bottom)
				(hide yes)
			)
		)
		(property "Datasheet" ""
			(at 198.755 199.39 0)
			(effects
				(font
					(size 1.27 1.27)
					(thickness 0.15)
				)
				(justify left bottom)
				(hide yes)
			)
		)
		(property "Description" ""
			(at 198.755 201.93 0)
			(effects
				(font
					(size 1.27 1.27)
				)
				(justify left bottom)
				(hide yes)
			)
		)
		(property "Author" "Antmicro"
			(at 198.755 194.31 0)
			(effects
				(font
					(size 1.27 1.27)
					(thickness 0.15)
				)
				(justify left bottom)
				(hide yes)
			)
		)
		(property "License" "Apache-2.0"
			(at 198.755 196.85 0)
			(effects
				(font
					(size 1.27 1.27)
					(thickness 0.15)
				)
				(justify left bottom)
				(hide yes)
			)
		)
		(pin "1"
		)
		(instances
			(project "sodimm-ddr5-tester"
				(path ""
					(reference "#PWR0342")
					(unit 1)
				)
			)
		)
	)
	(symbol
		(lib_id "antmicropower:GND")
		(at 292.735 60.325 0)
		(unit 1)
		(exclude_from_sim no)
		(in_bom yes)
		(on_board yes)
		(dnp no)
		(fields_autoplaced yes)
		(property "Reference" "#PWR0371"
			(at 292.735 66.675 0)
			(effects
				(font
					(size 1.27 1.27)
				)
				(hide yes)
			)
		)
		(property "Value" "GND"
			(at 294.64 61.595 0)
			(effects
				(font
					(size 1.27 1.27)
					(thickness 0.15)
				)
				(justify left)
			)
		)
		(property "Footprint" ""
			(at 301.625 67.945 0)
			(effects
				(font
					(size 1.27 1.27)
					(thickness 0.15)
				)
				(justify left bottom)
				(hide yes)
			)
		)
		(property "Datasheet" ""
			(at 301.625 73.025 0)
			(effects
				(font
					(size 1.27 1.27)
					(thickness 0.15)
				)
				(justify left bottom)
				(hide yes)
			)
		)
		(property "Description" ""
			(at 301.625 75.565 0)
			(effects
				(font
					(size 1.27 1.27)
				)
				(justify left bottom)
				(hide yes)
			)
		)
		(property "Author" "Antmicro"
			(at 301.625 67.945 0)
			(effects
				(font
					(size 1.27 1.27)
					(thickness 0.15)
				)
				(justify left bottom)
				(hide yes)
			)
		)
		(property "License" "Apache-2.0"
			(at 301.625 70.485 0)
			(effects
				(font
					(size 1.27 1.27)
					(thickness 0.15)
				)
				(justify left bottom)
				(hide yes)
			)
		)
		(pin "1"
		)
		(instances
			(project "sodimm-ddr5-tester"
				(path ""
					(reference "#PWR0371")
					(unit 1)
				)
			)
		)
	)
	(symbol
		(lib_id "antmicroPMICPowerSequencers:MAX16150A_SOT")
		(at 213.36 45.72 0)
		(unit 1)
		(exclude_from_sim no)
		(in_bom yes)
		(on_board yes)
		(dnp no)
		(fields_autoplaced yes)
		(property "Reference" "U22"
			(at 217.17 41.91 0)
			(effects
				(font
					(size 1.27 1.27)
				)
			)
		)
		(property "Value" "MAX16150A_SOT"
			(at 222.25 54.61 0)
			(effects
				(font
					(size 1.27 1.27)
					(thickness 0.15)
				)
			)
		)
		(property "Footprint" "antmicro-footprints:SOT-23-6"
			(at 245.11 54.61 0)
			(effects
				(font
					(size 1.27 1.27)
					(thickness 0.15)
				)
				(justify left bottom)
				(hide yes)
			)
		)
		(property "Datasheet" "https://datasheets.maximintegrated.com/en/ds/MAX16150.pdf"
			(at 245.11 57.15 0)
			(effects
				(font
					(size 1.27 1.27)
					(thickness 0.15)
				)
				(justify left bottom)
				(hide yes)
			)
		)
		(property "Description" ""
			(at 213.36 45.72 0)
			(effects
				(font
					(size 1.27 1.27)
				)
			)
		)
		(property "Manufacturer" "Maxim Integrated Products"
			(at 245.11 59.69 0)
			(effects
				(font
					(size 1.27 1.27)
					(thickness 0.15)
				)
				(justify left bottom)
				(hide yes)
			)
		)
		(property "MPN" "MAX16150AUT+T"
			(at 245.11 62.23 0)
			(effects
				(font
					(size 1.27 1.27)
					(thickness 0.15)
				)
				(justify left bottom)
				(hide yes)
			)
		)
		(property "License" "Apache-2.0"
			(at 245.11 64.77 0)
			(effects
				(font
					(size 1.27 1.27)
					(thickness 0.15)
				)
				(justify left bottom)
				(hide yes)
			)
		)
		(property "Author" "Antmicro"
			(at 245.11 67.31 0)
			(effects
				(font
					(size 1.27 1.27)
					(thickness 0.15)
				)
				(justify left bottom)
				(hide yes)
			)
		)
		(pin "1"
		)
		(pin "2"
		)
		(pin "3"
		)
		(pin "4"
		)
		(pin "5"
		)
		(pin "6"
		)
		(instances
			(project "sodimm-ddr5-tester"
				(path ""
					(reference "U22")
					(unit 1)
				)
			)
		)
	)
	(symbol
		(lib_id "antmicroShuntsJumpers:Net-Tie_P0.127mm")
		(at 305.435 217.17 90)
		(unit 1)
		(exclude_from_sim no)
		(in_bom no)
		(on_board yes)
		(dnp no)
		(fields_autoplaced yes)
		(property "Reference" "NT8"
			(at 304.165 217.17 0)
			(effects
				(font
					(size 1.27 1.27)
				)
				(hide yes)
			)
		)
		(property "Value" "Net-Tie_P0.127mm"
			(at 313.055 195.58 0)
			(effects
				(font
					(size 1.27 1.27)
					(thickness 0.15)
				)
				(justify left bottom)
				(hide yes)
			)
		)
		(property "Footprint" "antmicro-footprints:NetTie-2_SMD_Pad0.127mm"
			(at 318.135 195.58 0)
			(effects
				(font
					(size 1.27 1.27)
					(thickness 0.15)
				)
				(justify left bottom)
				(hide yes)
			)
		)
		(property "Datasheet" ""
			(at 320.675 195.58 0)
			(effects
				(font
					(size 1.27 1.27)
					(thickness 0.15)
				)
				(justify left bottom)
				(hide yes)
			)
		)
		(property "Description" ""
			(at 305.435 217.17 0)
			(effects
				(font
					(size 1.27 1.27)
				)
			)
		)
		(property "MPN" ""
			(at 315.595 195.58 0)
			(effects
				(font
					(size 1.27 1.27)
					(thickness 0.15)
				)
				(justify left bottom)
			)
		)
		(property "Manufacturer" ""
			(at 323.215 195.58 0)
			(effects
				(font
					(size 1.27 1.27)
					(thickness 0.15)
				)
				(justify left bottom)
				(hide yes)
			)
		)
		(property "Author" "Antmicro"
			(at 325.755 195.58 0)
			(effects
				(font
					(size 1.27 1.27)
					(thickness 0.15)
				)
				(justify left bottom)
				(hide yes)
			)
		)
		(property "License" "Apache-2.0"
			(at 328.295 195.58 0)
			(effects
				(font
					(size 1.27 1.27)
					(thickness 0.15)
				)
				(justify left bottom)
				(hide yes)
			)
		)
		(pin "1"
		)
		(pin "2"
		)
		(instances
			(project "sodimm-ddr5-tester"
				(path ""
					(reference "NT8")
					(unit 1)
				)
			)
		)
	)
	(symbol
		(lib_id "antmicroCapacitors0603:C_22u_0603")
		(at 78.105 187.325 90)
		(unit 1)
		(exclude_from_sim no)
		(in_bom yes)
		(on_board yes)
		(dnp no)
		(property "Reference" "C183"
			(at 78.74 182.88 90)
			(effects
				(font
					(size 1.27 1.27)
				)
				(justify right)
			)
		)
		(property "Value" "C_22u_0603"
			(at 88.265 167.005 0)
			(effects
				(font
					(size 1.27 1.27)
					(thickness 0.15)
				)
				(justify left bottom)
				(hide yes)
			)
		)
		(property "Footprint" "antmicro-footprints:C_0603_1608Metric"
			(at 90.805 167.005 0)
			(effects
				(font
					(size 1.27 1.27)
					(thickness 0.15)
				)
				(justify left bottom)
				(hide yes)
			)
		)
		(property "Datasheet" "https://www.murata.com/products/productdetail?partno=GRM188R60J226MEA0%23"
			(at 93.345 167.005 0)
			(effects
				(font
					(size 1.27 1.27)
					(thickness 0.15)
				)
				(justify left bottom)
				(hide yes)
			)
		)
		(property "Description" ""
			(at 78.105 187.325 0)
			(effects
				(font
					(size 1.27 1.27)
				)
			)
		)
		(property "Manufacturer" "Murata"
			(at 98.425 167.005 0)
			(effects
				(font
					(size 1.27 1.27)
					(thickness 0.15)
				)
				(justify left bottom)
				(hide yes)
			)
		)
		(property "MPN" "GRM188R60J226MEA0D"
			(at 95.885 167.005 0)
			(effects
				(font
					(size 1.27 1.27)
					(thickness 0.15)
				)
				(justify left bottom)
				(hide yes)
			)
		)
		(property "Val" "22u"
			(at 78.74 186.69 90)
			(effects
				(font
					(size 1.27 1.27)
					(thickness 0.15)
				)
				(justify right)
			)
		)
		(property "License" "Apache-2.0"
			(at 100.965 167.005 0)
			(effects
				(font
					(size 1.27 1.27)
					(thickness 0.15)
				)
				(justify left bottom)
				(hide yes)
			)
		)
		(property "Author" "Antmicro"
			(at 103.505 167.005 0)
			(effects
				(font
					(size 1.27 1.27)
					(thickness 0.15)
				)
				(justify left bottom)
				(hide yes)
			)
		)
		(property "Voltage" ""
			(at 106.045 167.005 0)
			(effects
				(font
					(size 1.27 1.27)
				)
				(justify left bottom)
				(hide yes)
			)
		)
		(property "Dielectric" ""
			(at 108.585 167.005 0)
			(effects
				(font
					(size 1.27 1.27)
				)
				(justify left bottom)
				(hide yes)
			)
		)
		(pin "1"
		)
		(pin "2"
		)
		(instances
			(project "sodimm-ddr5-tester"
				(path ""
					(reference "C183")
					(unit 1)
				)
			)
		)
	)
	(symbol
		(lib_id "antmicropower:GND")
		(at 337.82 244.475 0)
		(mirror y)
		(unit 1)
		(exclude_from_sim no)
		(in_bom yes)
		(on_board yes)
		(dnp no)
		(fields_autoplaced yes)
		(property "Reference" "#PWR0340"
			(at 337.82 250.825 0)
			(effects
				(font
					(size 1.27 1.27)
				)
				(hide yes)
			)
		)
		(property "Value" "GND"
			(at 340.36 245.745 0)
			(effects
				(font
					(size 1.27 1.27)
					(thickness 0.15)
				)
				(justify right)
			)
		)
		(property "Footprint" ""
			(at 328.93 252.095 0)
			(effects
				(font
					(size 1.27 1.27)
					(thickness 0.15)
				)
				(justify left bottom)
				(hide yes)
			)
		)
		(property "Datasheet" ""
			(at 328.93 257.175 0)
			(effects
				(font
					(size 1.27 1.27)
					(thickness 0.15)
				)
				(justify left bottom)
				(hide yes)
			)
		)
		(property "Description" ""
			(at 328.93 259.715 0)
			(effects
				(font
					(size 1.27 1.27)
				)
				(justify left bottom)
				(hide yes)
			)
		)
		(property "Author" "Antmicro"
			(at 328.93 252.095 0)
			(effects
				(font
					(size 1.27 1.27)
					(thickness 0.15)
				)
				(justify left bottom)
				(hide yes)
			)
		)
		(property "License" "Apache-2.0"
			(at 328.93 254.635 0)
			(effects
				(font
					(size 1.27 1.27)
					(thickness 0.15)
				)
				(justify left bottom)
				(hide yes)
			)
		)
		(pin "1"
		)
		(instances
			(project "sodimm-ddr5-tester"
				(path ""
					(reference "#PWR0340")
					(unit 1)
				)
			)
		)
	)
	(symbol
		(lib_id "antmicroCapacitors0603:C_1u_25V_0603")
		(at 111.125 45.085 90)
		(mirror x)
		(unit 1)
		(exclude_from_sim no)
		(in_bom yes)
		(on_board yes)
		(dnp no)
		(property "Reference" "C181"
			(at 111.76 45.72 90)
			(effects
				(font
					(size 1.27 1.27)
				)
				(justify right)
			)
		)
		(property "Value" "C_1u_25V_0603"
			(at 121.285 65.405 0)
			(effects
				(font
					(size 1.27 1.27)
					(thickness 0.15)
				)
				(justify left bottom)
				(hide yes)
			)
		)
		(property "Footprint" "antmicro-footprints:C_0603_1608Metric"
			(at 123.825 65.405 0)
			(effects
				(font
					(size 1.27 1.27)
					(thickness 0.15)
				)
				(justify left bottom)
				(hide yes)
			)
		)
		(property "Datasheet" "https://product.samsungsem.com/mlcc/CL10A105KA8NNN.do"
			(at 126.365 65.405 0)
			(effects
				(font
					(size 1.27 1.27)
					(thickness 0.15)
				)
				(justify left bottom)
				(hide yes)
			)
		)
		(property "Description" ""
			(at 111.125 45.085 0)
			(effects
				(font
					(size 1.27 1.27)
				)
			)
		)
		(property "Manufacturer" "Samsung Electro-Mechanics"
			(at 131.445 65.405 0)
			(effects
				(font
					(size 1.27 1.27)
					(thickness 0.15)
				)
				(justify left bottom)
				(hide yes)
			)
		)
		(property "MPN" "CL10A105KA8NNNC"
			(at 128.905 65.405 0)
			(effects
				(font
					(size 1.27 1.27)
					(thickness 0.15)
				)
				(justify left bottom)
				(hide yes)
			)
		)
		(property "Val" "1u/25V"
			(at 111.76 49.53 90)
			(effects
				(font
					(size 1.27 1.27)
					(thickness 0.15)
				)
				(justify right)
			)
		)
		(property "License" "Apache-2.0"
			(at 133.985 65.405 0)
			(effects
				(font
					(size 1.27 1.27)
					(thickness 0.15)
				)
				(justify left bottom)
				(hide yes)
			)
		)
		(property "Author" "Antmicro"
			(at 136.525 65.405 0)
			(effects
				(font
					(size 1.27 1.27)
					(thickness 0.15)
				)
				(justify left bottom)
				(hide yes)
			)
		)
		(property "Voltage" ""
			(at 139.065 65.405 0)
			(effects
				(font
					(size 1.27 1.27)
				)
				(justify left bottom)
				(hide yes)
			)
		)
		(property "Dielectric" ""
			(at 141.605 65.405 0)
			(effects
				(font
					(size 1.27 1.27)
				)
				(justify left bottom)
				(hide yes)
			)
		)
		(pin "1"
		)
		(pin "2"
		)
		(instances
			(project "sodimm-ddr5-tester"
				(path ""
					(reference "C181")
					(unit 1)
				)
			)
		)
	)
	(symbol
		(lib_id "antmicroTestPoints:TP_1mm_SMD")
		(at 132.715 179.705 0)
		(unit 1)
		(exclude_from_sim no)
		(in_bom yes)
		(on_board yes)
		(dnp no)
		(fields_autoplaced yes)
		(property "Reference" "TP15"
			(at 137.287 180.1388 0)
			(effects
				(font
					(size 1.27 1.27)
				)
				(justify left)
			)
		)
		(property "Value" "TP_1mm_SMD"
			(at 147.955 187.325 0)
			(effects
				(font
					(size 1.27 1.27)
					(thickness 0.15)
				)
				(justify left bottom)
				(hide yes)
			)
		)
		(property "Footprint" "antmicro-footprints:TP_SMD_1mm"
			(at 147.955 189.865 0)
			(effects
				(font
					(size 1.27 1.27)
					(thickness 0.15)
				)
				(justify left bottom)
				(hide yes)
			)
		)
		(property "Datasheet" ""
			(at 147.955 192.405 0)
			(effects
				(font
					(size 1.27 1.27)
					(thickness 0.15)
				)
				(justify left bottom)
				(hide yes)
			)
		)
		(property "Description" ""
			(at 132.715 179.705 0)
			(effects
				(font
					(size 1.27 1.27)
				)
			)
		)
		(property "MPN" ""
			(at 132.715 179.705 0)
			(effects
				(font
					(size 1.27 1.27)
				)
				(hide yes)
			)
		)
		(property "Manufacturer" ""
			(at 132.715 179.705 0)
			(effects
				(font
					(size 1.27 1.27)
				)
				(hide yes)
			)
		)
		(property "Author" "Antmicro"
			(at 147.955 194.945 0)
			(effects
				(font
					(size 1.27 1.27)
					(thickness 0.15)
				)
				(justify left bottom)
				(hide yes)
			)
		)
		(property "License" "Apache-2.0"
			(at 147.955 197.485 0)
			(effects
				(font
					(size 1.27 1.27)
					(thickness 0.15)
				)
				(justify left bottom)
				(hide yes)
			)
		)
		(pin "1"
		)
		(instances
			(project "sodimm-ddr5-tester"
				(path ""
					(reference "TP15")
					(unit 1)
				)
			)
		)
	)
	(symbol
		(lib_id "antmicroCapacitors0402:C_100n_0402")
		(at 218.44 33.02 90)
		(unit 1)
		(exclude_from_sim no)
		(in_bom yes)
		(on_board yes)
		(dnp no)
		(property "Reference" "C195"
			(at 219.71 28.575 90)
			(effects
				(font
					(size 1.27 1.27)
				)
				(justify right)
			)
		)
		(property "Value" "C_100n_0402"
			(at 228.6 12.7 0)
			(effects
				(font
					(size 1.27 1.27)
					(thickness 0.15)
				)
				(justify left bottom)
				(hide yes)
			)
		)
		(property "Footprint" "antmicro-footprints:C_0402_1005Metric"
			(at 231.14 12.7 0)
			(effects
				(font
					(size 1.27 1.27)
					(thickness 0.15)
				)
				(justify left bottom)
				(hide yes)
			)
		)
		(property "Datasheet" "https://www.murata.com/products/productdetail?partno=GRM155R61H104KE14%23"
			(at 233.68 12.7 0)
			(effects
				(font
					(size 1.27 1.27)
					(thickness 0.15)
				)
				(justify left bottom)
				(hide yes)
			)
		)
		(property "Description" ""
			(at 218.44 33.02 0)
			(effects
				(font
					(size 1.27 1.27)
				)
			)
		)
		(property "Manufacturer" "Murata"
			(at 238.76 12.7 0)
			(effects
				(font
					(size 1.27 1.27)
					(thickness 0.15)
				)
				(justify left bottom)
				(hide yes)
			)
		)
		(property "MPN" "GRM155R61H104KE14D"
			(at 236.22 12.7 0)
			(effects
				(font
					(size 1.27 1.27)
					(thickness 0.15)
				)
				(justify left bottom)
				(hide yes)
			)
		)
		(property "Val" "100n"
			(at 219.71 32.385 90)
			(effects
				(font
					(size 1.27 1.27)
					(thickness 0.15)
				)
				(justify right)
			)
		)
		(property "License" "Apache-2.0"
			(at 241.3 12.7 0)
			(effects
				(font
					(size 1.27 1.27)
					(thickness 0.15)
				)
				(justify left bottom)
				(hide yes)
			)
		)
		(property "Author" "Antmicro"
			(at 243.84 12.7 0)
			(effects
				(font
					(size 1.27 1.27)
					(thickness 0.15)
				)
				(justify left bottom)
				(hide yes)
			)
		)
		(property "Voltage" "50V"
			(at 246.38 12.7 0)
			(effects
				(font
					(size 1.27 1.27)
				)
				(justify left bottom)
				(hide yes)
			)
		)
		(property "Dielectric" "X5R"
			(at 248.92 12.7 0)
			(effects
				(font
					(size 1.27 1.27)
				)
				(justify left bottom)
				(hide yes)
			)
		)
		(pin "1"
		)
		(pin "2"
		)
		(instances
			(project "sodimm-ddr5-tester"
				(path ""
					(reference "C195")
					(unit 1)
				)
			)
		)
	)
	(symbol
		(lib_id "antmicropower:+1V0")
		(at 120.65 276.86 0)
		(unit 1)
		(exclude_from_sim no)
		(in_bom yes)
		(on_board yes)
		(dnp no)
		(fields_autoplaced yes)
		(property "Reference" "#PWR023"
			(at 120.65 280.67 0)
			(effects
				(font
					(size 1.27 1.27)
				)
				(hide yes)
			)
		)
		(property "Value" "+1V0"
			(at 120.65 273.304 0)
			(effects
				(font
					(size 1.27 1.27)
				)
			)
		)
		(property "Footprint" ""
			(at 120.65 276.86 0)
			(effects
				(font
					(size 1.27 1.27)
				)
				(hide yes)
			)
		)
		(property "Datasheet" ""
			(at 120.65 276.86 0)
			(effects
				(font
					(size 1.27 1.27)
				)
				(hide yes)
			)
		)
		(property "Description" ""
			(at 120.65 276.86 0)
			(effects
				(font
					(size 1.27 1.27)
				)
			)
		)
		(pin "1"
		)
		(instances
			(project "sodimm-ddr5-tester"
				(path ""
					(reference "#PWR023")
					(unit 1)
				)
			)
		)
	)
	(symbol
		(lib_id "antmicropower:PWR_FLAG")
		(at 50.165 93.98 0)
		(unit 1)
		(exclude_from_sim no)
		(in_bom yes)
		(on_board yes)
		(dnp no)
		(property "Reference" "#FLG0121"
			(at 50.165 92.075 0)
			(effects
				(font
					(size 1.27 1.27)
				)
				(hide yes)
			)
		)
		(property "Value" "PWR_FLAG"
			(at 50.165 90.4042 0)
			(effects
				(font
					(size 1.27 1.27)
				)
			)
		)
		(property "Footprint" ""
			(at 50.165 93.98 0)
			(effects
				(font
					(size 1.27 1.27)
				)
				(hide yes)
			)
		)
		(property "Datasheet" ""
			(at 50.165 93.98 0)
			(effects
				(font
					(size 1.27 1.27)
				)
				(hide yes)
			)
		)
		(property "Description" ""
			(at 50.165 93.98 0)
			(effects
				(font
					(size 1.27 1.27)
				)
			)
		)
		(pin "1"
		)
		(instances
			(project "sodimm-ddr5-tester"
				(path ""
					(reference "#FLG0121")
					(unit 1)
				)
			)
		)
	)
	(symbol
		(lib_id "antmicroResistors0402:R_47k_0402")
		(at 398.78 43.815 90)
		(unit 1)
		(exclude_from_sim no)
		(in_bom yes)
		(on_board yes)
		(dnp no)
		(property "Reference" "R190"
			(at 400.05 40.005 90)
			(effects
				(font
					(size 1.27 1.27)
				)
				(justify right)
			)
		)
		(property "Value" "R_47k_0402"
			(at 411.48 23.495 0)
			(effects
				(font
					(size 1.27 1.27)
					(thickness 0.15)
				)
				(justify left bottom)
				(hide yes)
			)
		)
		(property "Footprint" "antmicro-footprints:R_0402_1005Metric"
			(at 414.02 23.495 0)
			(effects
				(font
					(size 1.27 1.27)
					(thickness 0.15)
				)
				(justify left bottom)
				(hide yes)
			)
		)
		(property "Datasheet" "https://www.bourns.com/docs/product-datasheets/cr.pdf"
			(at 416.56 23.495 0)
			(effects
				(font
					(size 1.27 1.27)
					(thickness 0.15)
				)
				(justify left bottom)
				(hide yes)
			)
		)
		(property "Description" ""
			(at 398.78 43.815 0)
			(effects
				(font
					(size 1.27 1.27)
				)
			)
		)
		(property "Manufacturer" "Bourns"
			(at 421.64 23.495 0)
			(effects
				(font
					(size 1.27 1.27)
					(thickness 0.15)
				)
				(justify left bottom)
				(hide yes)
			)
		)
		(property "MPN" "CR0402-FX-4702GLF"
			(at 419.1 23.495 0)
			(effects
				(font
					(size 1.27 1.27)
					(thickness 0.15)
				)
				(justify left bottom)
				(hide yes)
			)
		)
		(property "Val" "47k"
			(at 400.05 42.545 90)
			(effects
				(font
					(size 1.27 1.27)
					(thickness 0.15)
				)
				(justify right)
			)
		)
		(property "License" "Apache-2.0"
			(at 424.18 23.495 0)
			(effects
				(font
					(size 1.27 1.27)
					(thickness 0.15)
				)
				(justify left bottom)
				(hide yes)
			)
		)
		(property "Author" "Antmicro"
			(at 426.72 23.495 0)
			(effects
				(font
					(size 1.27 1.27)
					(thickness 0.15)
				)
				(justify left bottom)
				(hide yes)
			)
		)
		(property "Tolerance" "1%"
			(at 408.94 23.495 0)
			(effects
				(font
					(size 1.27 1.27)
				)
				(justify left bottom)
				(hide yes)
			)
		)
		(pin "1"
		)
		(pin "2"
		)
		(instances
			(project "sodimm-ddr5-tester"
				(path ""
					(reference "R190")
					(unit 1)
				)
			)
		)
	)
	(symbol
		(lib_id "antmicroShuntsJumpers:Net-Tie_P0.127mm")
		(at 118.745 162.56 90)
		(unit 1)
		(exclude_from_sim no)
		(in_bom no)
		(on_board yes)
		(dnp no)
		(fields_autoplaced yes)
		(property "Reference" "NT9"
			(at 117.475 162.56 0)
			(effects
				(font
					(size 1.27 1.27)
				)
				(hide yes)
			)
		)
		(property "Value" "Net-Tie_P0.127mm"
			(at 126.365 140.97 0)
			(effects
				(font
					(size 1.27 1.27)
					(thickness 0.15)
				)
				(justify left bottom)
				(hide yes)
			)
		)
		(property "Footprint" "antmicro-footprints:NetTie-2_SMD_Pad0.127mm"
			(at 131.445 140.97 0)
			(effects
				(font
					(size 1.27 1.27)
					(thickness 0.15)
				)
				(justify left bottom)
				(hide yes)
			)
		)
		(property "Datasheet" ""
			(at 133.985 140.97 0)
			(effects
				(font
					(size 1.27 1.27)
					(thickness 0.15)
				)
				(justify left bottom)
				(hide yes)
			)
		)
		(property "Description" ""
			(at 118.745 162.56 0)
			(effects
				(font
					(size 1.27 1.27)
				)
			)
		)
		(property "MPN" ""
			(at 128.905 140.97 0)
			(effects
				(font
					(size 1.27 1.27)
					(thickness 0.15)
				)
				(justify left bottom)
			)
		)
		(property "Manufacturer" ""
			(at 136.525 140.97 0)
			(effects
				(font
					(size 1.27 1.27)
					(thickness 0.15)
				)
				(justify left bottom)
				(hide yes)
			)
		)
		(property "Author" "Antmicro"
			(at 139.065 140.97 0)
			(effects
				(font
					(size 1.27 1.27)
					(thickness 0.15)
				)
				(justify left bottom)
				(hide yes)
			)
		)
		(property "License" "Apache-2.0"
			(at 141.605 140.97 0)
			(effects
				(font
					(size 1.27 1.27)
					(thickness 0.15)
				)
				(justify left bottom)
				(hide yes)
			)
		)
		(pin "1"
		)
		(pin "2"
		)
		(instances
			(project "sodimm-ddr5-tester"
				(path ""
					(reference "NT9")
					(unit 1)
				)
			)
		)
	)
	(symbol
		(lib_id "antmicropower:+1V2_MGTAVTT")
		(at 170.18 276.86 0)
		(unit 1)
		(exclude_from_sim no)
		(in_bom yes)
		(on_board yes)
		(dnp no)
		(fields_autoplaced yes)
		(property "Reference" "#PWR041"
			(at 170.18 280.67 0)
			(effects
				(font
					(size 1.27 1.27)
				)
				(hide yes)
			)
		)
		(property "Value" "+1V2_MGTAVTT"
			(at 170.18 273.05 0)
			(effects
				(font
					(size 1.27 1.27)
				)
			)
		)
		(property "Footprint" ""
			(at 170.18 276.86 0)
			(effects
				(font
					(size 1.27 1.27)
				)
				(hide yes)
			)
		)
		(property "Datasheet" ""
			(at 170.18 276.86 0)
			(effects
				(font
					(size 1.27 1.27)
				)
				(hide yes)
			)
		)
		(property "Description" ""
			(at 170.18 276.86 0)
			(effects
				(font
					(size 1.27 1.27)
				)
			)
		)
		(pin "1"
		)
		(instances
			(project "sodimm-ddr5-tester"
				(path ""
					(reference "#PWR041")
					(unit 1)
				)
			)
		)
	)
	(symbol
		(lib_id "antmicropower:GND")
		(at 351.155 41.91 0)
		(unit 1)
		(exclude_from_sim no)
		(in_bom yes)
		(on_board yes)
		(dnp no)
		(fields_autoplaced yes)
		(property "Reference" "#PWR0383"
			(at 351.155 48.26 0)
			(effects
				(font
					(size 1.27 1.27)
				)
				(hide yes)
			)
		)
		(property "Value" "GND"
			(at 353.06 43.18 0)
			(effects
				(font
					(size 1.27 1.27)
					(thickness 0.15)
				)
				(justify left)
			)
		)
		(property "Footprint" ""
			(at 360.045 49.53 0)
			(effects
				(font
					(size 1.27 1.27)
					(thickness 0.15)
				)
				(justify left bottom)
				(hide yes)
			)
		)
		(property "Datasheet" ""
			(at 360.045 54.61 0)
			(effects
				(font
					(size 1.27 1.27)
					(thickness 0.15)
				)
				(justify left bottom)
				(hide yes)
			)
		)
		(property "Description" ""
			(at 360.045 57.15 0)
			(effects
				(font
					(size 1.27 1.27)
				)
				(justify left bottom)
				(hide yes)
			)
		)
		(property "Author" "Antmicro"
			(at 360.045 49.53 0)
			(effects
				(font
					(size 1.27 1.27)
					(thickness 0.15)
				)
				(justify left bottom)
				(hide yes)
			)
		)
		(property "License" "Apache-2.0"
			(at 360.045 52.07 0)
			(effects
				(font
					(size 1.27 1.27)
					(thickness 0.15)
				)
				(justify left bottom)
				(hide yes)
			)
		)
		(pin "1"
		)
		(instances
			(project "sodimm-ddr5-tester"
				(path ""
					(reference "#PWR0383")
					(unit 1)
				)
			)
		)
	)
	(symbol
		(lib_id "antmicroTestPoints:TP_1mm_SMD")
		(at 130.81 278.13 270)
		(unit 1)
		(exclude_from_sim no)
		(in_bom yes)
		(on_board yes)
		(dnp no)
		(property "Reference" "TP28"
			(at 130.81 283.1028 90)
			(effects
				(font
					(size 1.27 1.27)
				)
			)
		)
		(property "Value" "TP_1mm_SMD"
			(at 123.19 293.37 0)
			(effects
				(font
					(size 1.27 1.27)
					(thickness 0.15)
				)
				(justify left bottom)
				(hide yes)
			)
		)
		(property "Footprint" "antmicro-footprints:TP_SMD_1mm"
			(at 120.65 293.37 0)
			(effects
				(font
					(size 1.27 1.27)
					(thickness 0.15)
				)
				(justify left bottom)
				(hide yes)
			)
		)
		(property "Datasheet" ""
			(at 118.11 293.37 0)
			(effects
				(font
					(size 1.27 1.27)
					(thickness 0.15)
				)
				(justify left bottom)
				(hide yes)
			)
		)
		(property "Description" ""
			(at 130.81 278.13 0)
			(effects
				(font
					(size 1.27 1.27)
				)
			)
		)
		(property "MPN" ""
			(at 130.81 278.13 0)
			(effects
				(font
					(size 1.27 1.27)
				)
				(hide yes)
			)
		)
		(property "Manufacturer" ""
			(at 130.81 278.13 0)
			(effects
				(font
					(size 1.27 1.27)
				)
				(hide yes)
			)
		)
		(property "Author" "Antmicro"
			(at 115.57 293.37 0)
			(effects
				(font
					(size 1.27 1.27)
					(thickness 0.15)
				)
				(justify left bottom)
				(hide yes)
			)
		)
		(property "License" "Apache-2.0"
			(at 113.03 293.37 0)
			(effects
				(font
					(size 1.27 1.27)
					(thickness 0.15)
				)
				(justify left bottom)
				(hide yes)
			)
		)
		(pin "1"
		)
		(instances
			(project "sodimm-ddr5-tester"
				(path ""
					(reference "TP28")
					(unit 1)
				)
			)
		)
	)
	(symbol
		(lib_id "antmicropower:GND")
		(at 374.015 244.475 0)
		(mirror y)
		(unit 1)
		(exclude_from_sim no)
		(in_bom yes)
		(on_board yes)
		(dnp no)
		(fields_autoplaced yes)
		(property "Reference" "#PWR0339"
			(at 374.015 250.825 0)
			(effects
				(font
					(size 1.27 1.27)
				)
				(hide yes)
			)
		)
		(property "Value" "GND"
			(at 375.92 245.745 0)
			(effects
				(font
					(size 1.27 1.27)
					(thickness 0.15)
				)
				(justify right)
			)
		)
		(property "Footprint" ""
			(at 365.125 252.095 0)
			(effects
				(font
					(size 1.27 1.27)
					(thickness 0.15)
				)
				(justify left bottom)
				(hide yes)
			)
		)
		(property "Datasheet" ""
			(at 365.125 257.175 0)
			(effects
				(font
					(size 1.27 1.27)
					(thickness 0.15)
				)
				(justify left bottom)
				(hide yes)
			)
		)
		(property "Description" ""
			(at 365.125 259.715 0)
			(effects
				(font
					(size 1.27 1.27)
				)
				(justify left bottom)
				(hide yes)
			)
		)
		(property "Author" "Antmicro"
			(at 365.125 252.095 0)
			(effects
				(font
					(size 1.27 1.27)
					(thickness 0.15)
				)
				(justify left bottom)
				(hide yes)
			)
		)
		(property "License" "Apache-2.0"
			(at 365.125 254.635 0)
			(effects
				(font
					(size 1.27 1.27)
					(thickness 0.15)
				)
				(justify left bottom)
				(hide yes)
			)
		)
		(pin "1"
		)
		(instances
			(project "sodimm-ddr5-tester"
				(path ""
					(reference "#PWR0339")
					(unit 1)
				)
			)
		)
	)
	(symbol
		(lib_id "antmicroResistors0402:R_47k_0402")
		(at 379.095 43.815 90)
		(unit 1)
		(exclude_from_sim no)
		(in_bom yes)
		(on_board yes)
		(dnp no)
		(property "Reference" "R184"
			(at 380.365 40.005 90)
			(effects
				(font
					(size 1.27 1.27)
				)
				(justify right)
			)
		)
		(property "Value" "R_47k_0402"
			(at 391.795 23.495 0)
			(effects
				(font
					(size 1.27 1.27)
					(thickness 0.15)
				)
				(justify left bottom)
				(hide yes)
			)
		)
		(property "Footprint" "antmicro-footprints:R_0402_1005Metric"
			(at 394.335 23.495 0)
			(effects
				(font
					(size 1.27 1.27)
					(thickness 0.15)
				)
				(justify left bottom)
				(hide yes)
			)
		)
		(property "Datasheet" "https://www.bourns.com/docs/product-datasheets/cr.pdf"
			(at 396.875 23.495 0)
			(effects
				(font
					(size 1.27 1.27)
					(thickness 0.15)
				)
				(justify left bottom)
				(hide yes)
			)
		)
		(property "Description" ""
			(at 379.095 43.815 0)
			(effects
				(font
					(size 1.27 1.27)
				)
			)
		)
		(property "Manufacturer" "Bourns"
			(at 401.955 23.495 0)
			(effects
				(font
					(size 1.27 1.27)
					(thickness 0.15)
				)
				(justify left bottom)
				(hide yes)
			)
		)
		(property "MPN" "CR0402-FX-4702GLF"
			(at 399.415 23.495 0)
			(effects
				(font
					(size 1.27 1.27)
					(thickness 0.15)
				)
				(justify left bottom)
				(hide yes)
			)
		)
		(property "Val" "47k"
			(at 380.365 42.545 90)
			(effects
				(font
					(size 1.27 1.27)
					(thickness 0.15)
				)
				(justify right)
			)
		)
		(property "License" "Apache-2.0"
			(at 404.495 23.495 0)
			(effects
				(font
					(size 1.27 1.27)
					(thickness 0.15)
				)
				(justify left bottom)
				(hide yes)
			)
		)
		(property "Author" "Antmicro"
			(at 407.035 23.495 0)
			(effects
				(font
					(size 1.27 1.27)
					(thickness 0.15)
				)
				(justify left bottom)
				(hide yes)
			)
		)
		(property "Tolerance" "1%"
			(at 389.255 23.495 0)
			(effects
				(font
					(size 1.27 1.27)
				)
				(justify left bottom)
				(hide yes)
			)
		)
		(pin "1"
		)
		(pin "2"
		)
		(instances
			(project "sodimm-ddr5-tester"
				(path ""
					(reference "R184")
					(unit 1)
				)
			)
		)
	)
	(symbol
		(lib_id "antmicropower:GND")
		(at 92.71 43.815 0)
		(unit 1)
		(exclude_from_sim no)
		(in_bom yes)
		(on_board yes)
		(dnp no)
		(fields_autoplaced yes)
		(property "Reference" "#PWR0298"
			(at 92.71 50.165 0)
			(effects
				(font
					(size 1.27 1.27)
				)
				(hide yes)
			)
		)
		(property "Value" "GND"
			(at 95.25 45.085 0)
			(effects
				(font
					(size 1.27 1.27)
					(thickness 0.15)
				)
				(justify left)
			)
		)
		(property "Footprint" ""
			(at 101.6 51.435 0)
			(effects
				(font
					(size 1.27 1.27)
					(thickness 0.15)
				)
				(justify left bottom)
				(hide yes)
			)
		)
		(property "Datasheet" ""
			(at 101.6 56.515 0)
			(effects
				(font
					(size 1.27 1.27)
					(thickness 0.15)
				)
				(justify left bottom)
				(hide yes)
			)
		)
		(property "Description" ""
			(at 101.6 59.055 0)
			(effects
				(font
					(size 1.27 1.27)
				)
				(justify left bottom)
				(hide yes)
			)
		)
		(property "Author" "Antmicro"
			(at 101.6 51.435 0)
			(effects
				(font
					(size 1.27 1.27)
					(thickness 0.15)
				)
				(justify left bottom)
				(hide yes)
			)
		)
		(property "License" "Apache-2.0"
			(at 101.6 53.975 0)
			(effects
				(font
					(size 1.27 1.27)
					(thickness 0.15)
				)
				(justify left bottom)
				(hide yes)
			)
		)
		(pin "1"
		)
		(instances
			(project "sodimm-ddr5-tester"
				(path ""
					(reference "#PWR0298")
					(unit 1)
				)
			)
		)
	)
	(symbol
		(lib_id "antmicropower:GND")
		(at 146.685 52.705 0)
		(unit 1)
		(exclude_from_sim no)
		(in_bom yes)
		(on_board yes)
		(dnp no)
		(fields_autoplaced yes)
		(property "Reference" "#PWR0315"
			(at 146.685 59.055 0)
			(effects
				(font
					(size 1.27 1.27)
				)
				(hide yes)
			)
		)
		(property "Value" "GND"
			(at 149.225 53.975 0)
			(effects
				(font
					(size 1.27 1.27)
					(thickness 0.15)
				)
				(justify left)
			)
		)
		(property "Footprint" ""
			(at 155.575 60.325 0)
			(effects
				(font
					(size 1.27 1.27)
					(thickness 0.15)
				)
				(justify left bottom)
				(hide yes)
			)
		)
		(property "Datasheet" ""
			(at 155.575 65.405 0)
			(effects
				(font
					(size 1.27 1.27)
					(thickness 0.15)
				)
				(justify left bottom)
				(hide yes)
			)
		)
		(property "Description" ""
			(at 155.575 67.945 0)
			(effects
				(font
					(size 1.27 1.27)
				)
				(justify left bottom)
				(hide yes)
			)
		)
		(property "Author" "Antmicro"
			(at 155.575 60.325 0)
			(effects
				(font
					(size 1.27 1.27)
					(thickness 0.15)
				)
				(justify left bottom)
				(hide yes)
			)
		)
		(property "License" "Apache-2.0"
			(at 155.575 62.865 0)
			(effects
				(font
					(size 1.27 1.27)
					(thickness 0.15)
				)
				(justify left bottom)
				(hide yes)
			)
		)
		(pin "1"
		)
		(instances
			(project "sodimm-ddr5-tester"
				(path ""
					(reference "#PWR0315")
					(unit 1)
				)
			)
		)
	)
	(symbol
		(lib_id "antmicropower:+3V3")
		(at 325.755 156.21 0)
		(unit 1)
		(exclude_from_sim no)
		(in_bom yes)
		(on_board yes)
		(dnp no)
		(property "Reference" "#PWR0325"
			(at 325.755 160.02 0)
			(effects
				(font
					(size 1.27 1.27)
				)
				(hide yes)
			)
		)
		(property "Value" "+3V3"
			(at 322.58 153.67 0)
			(effects
				(font
					(size 1.27 1.27)
					(thickness 0.15)
				)
				(justify left bottom)
			)
		)
		(property "Footprint" ""
			(at 340.995 163.83 0)
			(effects
				(font
					(size 1.27 1.27)
					(thickness 0.15)
				)
				(justify left bottom)
				(hide yes)
			)
		)
		(property "Datasheet" ""
			(at 340.995 166.37 0)
			(effects
				(font
					(size 1.27 1.27)
					(thickness 0.15)
				)
				(justify left bottom)
				(hide yes)
			)
		)
		(property "Description" ""
			(at 325.755 156.21 0)
			(effects
				(font
					(size 1.27 1.27)
				)
			)
		)
		(property "Author" "Antmicro"
			(at 340.995 158.75 0)
			(effects
				(font
					(size 1.27 1.27)
					(thickness 0.15)
				)
				(justify left bottom)
				(hide yes)
			)
		)
		(property "License" "Apache-2.0"
			(at 340.995 161.29 0)
			(effects
				(font
					(size 1.27 1.27)
					(thickness 0.15)
				)
				(justify left bottom)
				(hide yes)
			)
		)
		(pin "1"
		)
		(instances
			(project "sodimm-ddr5-tester"
				(path ""
					(reference "#PWR0325")
					(unit 1)
				)
			)
		)
	)
	(symbol
		(lib_id "antmicroTestPoints:TP_1mm_SMD")
		(at 128.905 216.535 0)
		(unit 1)
		(exclude_from_sim no)
		(in_bom yes)
		(on_board yes)
		(dnp no)
		(fields_autoplaced yes)
		(property "Reference" "TP18"
			(at 133.477 216.9688 0)
			(effects
				(font
					(size 1.27 1.27)
				)
				(justify left)
			)
		)
		(property "Value" "TP_1mm_SMD"
			(at 144.145 224.155 0)
			(effects
				(font
					(size 1.27 1.27)
					(thickness 0.15)
				)
				(justify left bottom)
				(hide yes)
			)
		)
		(property "Footprint" "antmicro-footprints:TP_SMD_1mm"
			(at 144.145 226.695 0)
			(effects
				(font
					(size 1.27 1.27)
					(thickness 0.15)
				)
				(justify left bottom)
				(hide yes)
			)
		)
		(property "Datasheet" ""
			(at 144.145 229.235 0)
			(effects
				(font
					(size 1.27 1.27)
					(thickness 0.15)
				)
				(justify left bottom)
				(hide yes)
			)
		)
		(property "Description" ""
			(at 128.905 216.535 0)
			(effects
				(font
					(size 1.27 1.27)
				)
			)
		)
		(property "MPN" ""
			(at 128.905 216.535 0)
			(effects
				(font
					(size 1.27 1.27)
				)
				(hide yes)
			)
		)
		(property "Manufacturer" ""
			(at 128.905 216.535 0)
			(effects
				(font
					(size 1.27 1.27)
				)
				(hide yes)
			)
		)
		(property "Author" "Antmicro"
			(at 144.145 231.775 0)
			(effects
				(font
					(size 1.27 1.27)
					(thickness 0.15)
				)
				(justify left bottom)
				(hide yes)
			)
		)
		(property "License" "Apache-2.0"
			(at 144.145 234.315 0)
			(effects
				(font
					(size 1.27 1.27)
					(thickness 0.15)
				)
				(justify left bottom)
				(hide yes)
			)
		)
		(pin "1"
		)
		(instances
			(project "sodimm-ddr5-tester"
				(path ""
					(reference "TP18")
					(unit 1)
				)
			)
		)
	)
	(symbol
		(lib_id "antmicropower:GND")
		(at 50.165 130.81 0)
		(unit 1)
		(exclude_from_sim no)
		(in_bom yes)
		(on_board yes)
		(dnp no)
		(fields_autoplaced yes)
		(property "Reference" "#PWR0375"
			(at 50.165 137.16 0)
			(effects
				(font
					(size 1.27 1.27)
				)
				(hide yes)
			)
		)
		(property "Value" "GND"
			(at 52.07 132.08 0)
			(effects
				(font
					(size 1.27 1.27)
					(thickness 0.15)
				)
				(justify left)
			)
		)
		(property "Footprint" ""
			(at 59.055 138.43 0)
			(effects
				(font
					(size 1.27 1.27)
					(thickness 0.15)
				)
				(justify left bottom)
				(hide yes)
			)
		)
		(property "Datasheet" ""
			(at 59.055 143.51 0)
			(effects
				(font
					(size 1.27 1.27)
					(thickness 0.15)
				)
				(justify left bottom)
				(hide yes)
			)
		)
		(property "Description" ""
			(at 59.055 146.05 0)
			(effects
				(font
					(size 1.27 1.27)
				)
				(justify left bottom)
				(hide yes)
			)
		)
		(property "Author" "Antmicro"
			(at 59.055 138.43 0)
			(effects
				(font
					(size 1.27 1.27)
					(thickness 0.15)
				)
				(justify left bottom)
				(hide yes)
			)
		)
		(property "License" "Apache-2.0"
			(at 59.055 140.97 0)
			(effects
				(font
					(size 1.27 1.27)
					(thickness 0.15)
				)
				(justify left bottom)
				(hide yes)
			)
		)
		(pin "1"
		)
		(instances
			(project "sodimm-ddr5-tester"
				(path ""
					(reference "#PWR0375")
					(unit 1)
				)
			)
		)
	)
	(symbol
		(lib_id "antmicroCapacitors0402:C_100n_0402")
		(at 285.75 128.905 270)
		(unit 1)
		(exclude_from_sim no)
		(in_bom yes)
		(on_board yes)
		(dnp no)
		(property "Reference" "C199"
			(at 285.115 129.54 90)
			(effects
				(font
					(size 1.27 1.27)
				)
				(justify right)
			)
		)
		(property "Value" "C_100n_0402"
			(at 275.59 149.225 0)
			(effects
				(font
					(size 1.27 1.27)
					(thickness 0.15)
				)
				(justify left bottom)
				(hide yes)
			)
		)
		(property "Footprint" "antmicro-footprints:C_0402_1005Metric"
			(at 273.05 149.225 0)
			(effects
				(font
					(size 1.27 1.27)
					(thickness 0.15)
				)
				(justify left bottom)
				(hide yes)
			)
		)
		(property "Datasheet" "https://www.murata.com/products/productdetail?partno=GRM155R61H104KE14%23"
			(at 270.51 149.225 0)
			(effects
				(font
					(size 1.27 1.27)
					(thickness 0.15)
				)
				(justify left bottom)
				(hide yes)
			)
		)
		(property "Description" ""
			(at 285.75 128.905 0)
			(effects
				(font
					(size 1.27 1.27)
				)
			)
		)
		(property "Manufacturer" "Murata"
			(at 265.43 149.225 0)
			(effects
				(font
					(size 1.27 1.27)
					(thickness 0.15)
				)
				(justify left bottom)
				(hide yes)
			)
		)
		(property "MPN" "GRM155R61H104KE14D"
			(at 267.97 149.225 0)
			(effects
				(font
					(size 1.27 1.27)
					(thickness 0.15)
				)
				(justify left bottom)
				(hide yes)
			)
		)
		(property "Val" "100n"
			(at 285.115 133.35 90)
			(effects
				(font
					(size 1.27 1.27)
					(thickness 0.15)
				)
				(justify right)
			)
		)
		(property "License" "Apache-2.0"
			(at 262.89 149.225 0)
			(effects
				(font
					(size 1.27 1.27)
					(thickness 0.15)
				)
				(justify left bottom)
				(hide yes)
			)
		)
		(property "Author" "Antmicro"
			(at 260.35 149.225 0)
			(effects
				(font
					(size 1.27 1.27)
					(thickness 0.15)
				)
				(justify left bottom)
				(hide yes)
			)
		)
		(property "Voltage" "50V"
			(at 257.81 149.225 0)
			(effects
				(font
					(size 1.27 1.27)
				)
				(justify left bottom)
				(hide yes)
			)
		)
		(property "Dielectric" "X5R"
			(at 255.27 149.225 0)
			(effects
				(font
					(size 1.27 1.27)
				)
				(justify left bottom)
				(hide yes)
			)
		)
		(pin "1"
		)
		(pin "2"
		)
		(instances
			(project "sodimm-ddr5-tester"
				(path ""
					(reference "C199")
					(unit 1)
				)
			)
		)
	)
	(symbol
		(lib_id "antmicroTestPoints:TP_1mm_SMD")
		(at 200.66 281.94 0)
		(unit 1)
		(exclude_from_sim no)
		(in_bom yes)
		(on_board yes)
		(dnp no)
		(property "Reference" "TP29"
			(at 207.264 281.94 0)
			(effects
				(font
					(size 1.27 1.27)
				)
			)
		)
		(property "Value" "TP_1mm_SMD"
			(at 215.9 289.56 0)
			(effects
				(font
					(size 1.27 1.27)
					(thickness 0.15)
				)
				(justify left bottom)
				(hide yes)
			)
		)
		(property "Footprint" "antmicro-footprints:TP_SMD_1mm"
			(at 215.9 292.1 0)
			(effects
				(font
					(size 1.27 1.27)
					(thickness 0.15)
				)
				(justify left bottom)
				(hide yes)
			)
		)
		(property "Datasheet" ""
			(at 215.9 294.64 0)
			(effects
				(font
					(size 1.27 1.27)
					(thickness 0.15)
				)
				(justify left bottom)
				(hide yes)
			)
		)
		(property "Description" ""
			(at 200.66 281.94 0)
			(effects
				(font
					(size 1.27 1.27)
				)
			)
		)
		(property "MPN" ""
			(at 200.66 281.94 0)
			(effects
				(font
					(size 1.27 1.27)
				)
				(hide yes)
			)
		)
		(property "Manufacturer" ""
			(at 200.66 281.94 0)
			(effects
				(font
					(size 1.27 1.27)
				)
				(hide yes)
			)
		)
		(property "Author" "Antmicro"
			(at 215.9 297.18 0)
			(effects
				(font
					(size 1.27 1.27)
					(thickness 0.15)
				)
				(justify left bottom)
				(hide yes)
			)
		)
		(property "License" "Apache-2.0"
			(at 215.9 299.72 0)
			(effects
				(font
					(size 1.27 1.27)
					(thickness 0.15)
				)
				(justify left bottom)
				(hide yes)
			)
		)
		(pin "1"
		)
		(instances
			(project "sodimm-ddr5-tester"
				(path ""
					(reference "TP29")
					(unit 1)
				)
			)
		)
	)
	(symbol
		(lib_id "antmicroResistorsmisc:R_0R01_1206")
		(at 111.76 197.485 0)
		(unit 1)
		(exclude_from_sim no)
		(in_bom yes)
		(on_board yes)
		(dnp no)
		(property "Reference" "R143"
			(at 114.3 192.405 0)
			(effects
				(font
					(size 1.27 1.27)
				)
			)
		)
		(property "Value" "R_0R01_1206"
			(at 132.08 210.185 0)
			(effects
				(font
					(size 1.27 1.27)
					(thickness 0.15)
				)
				(justify left bottom)
				(hide yes)
			)
		)
		(property "Footprint" "antmicro-footprints:R_1206_3216Metric"
			(at 132.08 212.725 0)
			(effects
				(font
					(size 1.27 1.27)
					(thickness 0.15)
				)
				(justify left bottom)
				(hide yes)
			)
		)
		(property "Datasheet" "https://www.yageo.com/upload/media/product/productsearch/datasheet/rchip/PYu-RL_Group_521_RoHS_L_2.pdf"
			(at 132.08 215.265 0)
			(effects
				(font
					(size 1.27 1.27)
					(thickness 0.15)
				)
				(justify left bottom)
				(hide yes)
			)
		)
		(property "Description" ""
			(at 111.76 197.485 0)
			(effects
				(font
					(size 1.27 1.27)
				)
			)
		)
		(property "Manufacturer" "YAGEO"
			(at 132.08 220.345 0)
			(effects
				(font
					(size 1.27 1.27)
					(thickness 0.15)
				)
				(justify left bottom)
				(hide yes)
			)
		)
		(property "MPN" "RL1206FR-7W0R01L"
			(at 132.08 217.805 0)
			(effects
				(font
					(size 1.27 1.27)
					(thickness 0.15)
				)
				(justify left bottom)
				(hide yes)
			)
		)
		(property "Val" "0R01"
			(at 114.3 194.945 0)
			(effects
				(font
					(size 1.27 1.27)
					(thickness 0.15)
				)
			)
		)
		(property "License" "Apache-2.0"
			(at 132.08 222.885 0)
			(effects
				(font
					(size 1.27 1.27)
					(thickness 0.15)
				)
				(justify left bottom)
				(hide yes)
			)
		)
		(property "Author" "Antmicro"
			(at 132.08 225.425 0)
			(effects
				(font
					(size 1.27 1.27)
					(thickness 0.15)
				)
				(justify left bottom)
				(hide yes)
			)
		)
		(property "Tolerance" "1%"
			(at 132.08 207.645 0)
			(effects
				(font
					(size 1.27 1.27)
				)
				(justify left bottom)
				(hide yes)
			)
		)
		(pin "1"
		)
		(pin "2"
		)
		(instances
			(project "sodimm-ddr5-tester"
				(path ""
					(reference "R143")
					(unit 1)
				)
			)
		)
	)
	(symbol
		(lib_id "antmicroShuntsJumpers:Net-Tie_P0.127mm")
		(at 313.69 217.17 90)
		(unit 1)
		(exclude_from_sim no)
		(in_bom no)
		(on_board yes)
		(dnp no)
		(fields_autoplaced yes)
		(property "Reference" "NT16"
			(at 312.42 217.17 0)
			(effects
				(font
					(size 1.27 1.27)
				)
				(hide yes)
			)
		)
		(property "Value" "Net-Tie_P0.127mm"
			(at 321.31 195.58 0)
			(effects
				(font
					(size 1.27 1.27)
					(thickness 0.15)
				)
				(justify left bottom)
				(hide yes)
			)
		)
		(property "Footprint" "antmicro-footprints:NetTie-2_SMD_Pad0.127mm"
			(at 326.39 195.58 0)
			(effects
				(font
					(size 1.27 1.27)
					(thickness 0.15)
				)
				(justify left bottom)
				(hide yes)
			)
		)
		(property "Datasheet" ""
			(at 328.93 195.58 0)
			(effects
				(font
					(size 1.27 1.27)
					(thickness 0.15)
				)
				(justify left bottom)
				(hide yes)
			)
		)
		(property "Description" ""
			(at 313.69 217.17 0)
			(effects
				(font
					(size 1.27 1.27)
				)
			)
		)
		(property "MPN" ""
			(at 323.85 195.58 0)
			(effects
				(font
					(size 1.27 1.27)
					(thickness 0.15)
				)
				(justify left bottom)
			)
		)
		(property "Manufacturer" ""
			(at 331.47 195.58 0)
			(effects
				(font
					(size 1.27 1.27)
					(thickness 0.15)
				)
				(justify left bottom)
				(hide yes)
			)
		)
		(property "Author" "Antmicro"
			(at 334.01 195.58 0)
			(effects
				(font
					(size 1.27 1.27)
					(thickness 0.15)
				)
				(justify left bottom)
				(hide yes)
			)
		)
		(property "License" "Apache-2.0"
			(at 336.55 195.58 0)
			(effects
				(font
					(size 1.27 1.27)
					(thickness 0.15)
				)
				(justify left bottom)
				(hide yes)
			)
		)
		(pin "1"
		)
		(pin "2"
		)
		(instances
			(project "sodimm-ddr5-tester"
				(path ""
					(reference "NT16")
					(unit 1)
				)
			)
		)
	)
	(symbol
		(lib_id "antmicropower:GND")
		(at 86.995 208.915 0)
		(unit 1)
		(exclude_from_sim no)
		(in_bom yes)
		(on_board yes)
		(dnp no)
		(fields_autoplaced yes)
		(property "Reference" "#PWR0306"
			(at 86.995 215.265 0)
			(effects
				(font
					(size 1.27 1.27)
				)
				(hide yes)
			)
		)
		(property "Value" "GND"
			(at 88.9 210.185 0)
			(effects
				(font
					(size 1.27 1.27)
					(thickness 0.15)
				)
				(justify left)
			)
		)
		(property "Footprint" ""
			(at 95.885 216.535 0)
			(effects
				(font
					(size 1.27 1.27)
					(thickness 0.15)
				)
				(justify left bottom)
				(hide yes)
			)
		)
		(property "Datasheet" ""
			(at 95.885 221.615 0)
			(effects
				(font
					(size 1.27 1.27)
					(thickness 0.15)
				)
				(justify left bottom)
				(hide yes)
			)
		)
		(property "Description" ""
			(at 95.885 224.155 0)
			(effects
				(font
					(size 1.27 1.27)
				)
				(justify left bottom)
				(hide yes)
			)
		)
		(property "Author" "Antmicro"
			(at 95.885 216.535 0)
			(effects
				(font
					(size 1.27 1.27)
					(thickness 0.15)
				)
				(justify left bottom)
				(hide yes)
			)
		)
		(property "License" "Apache-2.0"
			(at 95.885 219.075 0)
			(effects
				(font
					(size 1.27 1.27)
					(thickness 0.15)
				)
				(justify left bottom)
				(hide yes)
			)
		)
		(pin "1"
		)
		(instances
			(project "sodimm-ddr5-tester"
				(path ""
					(reference "#PWR0306")
					(unit 1)
				)
			)
		)
	)
	(symbol
		(lib_id "antmicroPMICVoltageRegulatorsDCDCSwitchingRegulators:MPM54304GMN")
		(at 38.735 174.625 0)
		(unit 1)
		(exclude_from_sim no)
		(in_bom yes)
		(on_board yes)
		(dnp no)
		(fields_autoplaced yes)
		(property "Reference" "U19"
			(at 52.705 167.13 0)
			(effects
				(font
					(size 1.27 1.27)
					(thickness 0.15)
				)
			)
		)
		(property "Value" "MPM54304GMN"
			(at 52.705 169.6537 0)
			(effects
				(font
					(size 1.27 1.27)
					(thickness 0.15)
				)
			)
		)
		(property "Footprint" "antmicro-footprints:LGA-33_7x7mm_P0.65mm"
			(at 85.725 182.245 0)
			(effects
				(font
					(size 1.27 1.27)
					(thickness 0.15)
				)
				(justify left bottom)
				(hide yes)
			)
		)
		(property "Datasheet" "https://www.monolithicpower.com/en/documentview/productdocument/index/version/2/document_type/Datasheet/lang/en/sku/MPM54304/document_id/4982/"
			(at 85.725 184.785 0)
			(effects
				(font
					(size 1.27 1.27)
					(thickness 0.15)
				)
				(justify left bottom)
				(hide yes)
			)
		)
		(property "Description" ""
			(at 38.735 174.625 0)
			(effects
				(font
					(size 1.27 1.27)
				)
			)
		)
		(property "MPN" "MPM54304GMN-0000"
			(at 85.725 187.325 0)
			(effects
				(font
					(size 1.27 1.27)
					(thickness 0.15)
				)
				(justify left bottom)
				(hide yes)
			)
		)
		(property "Manufacturer" "Monolithic Power Systems"
			(at 85.725 189.865 0)
			(effects
				(font
					(size 1.27 1.27)
					(thickness 0.15)
				)
				(justify left bottom)
				(hide yes)
			)
		)
		(property "Author" "Antmicro"
			(at 85.725 192.405 0)
			(effects
				(font
					(size 1.27 1.27)
					(thickness 0.15)
				)
				(justify left bottom)
				(hide yes)
			)
		)
		(property "License" "Apache-2.0"
			(at 85.725 194.945 0)
			(effects
				(font
					(size 1.27 1.27)
					(thickness 0.15)
				)
				(justify left bottom)
				(hide yes)
			)
		)
		(pin "1"
		)
		(pin "10"
		)
		(pin "11"
		)
		(pin "12"
		)
		(pin "13"
		)
		(pin "14"
		)
		(pin "15"
		)
		(pin "16"
		)
		(pin "17"
		)
		(pin "18"
		)
		(pin "19"
		)
		(pin "2"
		)
		(pin "20"
		)
		(pin "21"
		)
		(pin "22"
		)
		(pin "23"
		)
		(pin "24"
		)
		(pin "25"
		)
		(pin "26"
		)
		(pin "27"
		)
		(pin "28"
		)
		(pin "29"
		)
		(pin "3"
		)
		(pin "30"
		)
		(pin "31"
		)
		(pin "32"
		)
		(pin "33"
		)
		(pin "4"
		)
		(pin "5"
		)
		(pin "6"
		)
		(pin "7"
		)
		(pin "8"
		)
		(pin "9"
		)
		(instances
			(project "sodimm-ddr5-tester"
				(path ""
					(reference "U19")
					(unit 1)
				)
			)
		)
	)
	(symbol
		(lib_id "antmicropower:VDC")
		(at 17.145 94.615 0)
		(unit 1)
		(exclude_from_sim no)
		(in_bom yes)
		(on_board yes)
		(dnp no)
		(fields_autoplaced yes)
		(property "Reference" "#PWR0362"
			(at 17.145 97.155 0)
			(effects
				(font
					(size 1.27 1.27)
				)
				(hide yes)
			)
		)
		(property "Value" "VDC"
			(at 17.145 89.535 0)
			(effects
				(font
					(size 1.27 1.27)
				)
			)
		)
		(property "Footprint" ""
			(at 17.145 94.615 0)
			(effects
				(font
					(size 1.27 1.27)
				)
				(hide yes)
			)
		)
		(property "Datasheet" ""
			(at 17.145 94.615 0)
			(effects
				(font
					(size 1.27 1.27)
				)
				(hide yes)
			)
		)
		(property "Description" ""
			(at 17.145 94.615 0)
			(effects
				(font
					(size 1.27 1.27)
				)
			)
		)
		(pin "1"
		)
		(instances
			(project "sodimm-ddr5-tester"
				(path ""
					(reference "#PWR0362")
					(unit 1)
				)
			)
		)
	)
	(symbol
		(lib_id "antmicropower:GND")
		(at 227.965 263.525 0)
		(unit 1)
		(exclude_from_sim no)
		(in_bom yes)
		(on_board yes)
		(dnp no)
		(property "Reference" "#PWR0350"
			(at 227.965 269.875 0)
			(effects
				(font
					(size 1.27 1.27)
				)
				(hide yes)
			)
		)
		(property "Value" "GND"
			(at 226.06 266.954 0)
			(effects
				(font
					(size 1.27 1.27)
					(thickness 0.15)
				)
				(justify left)
			)
		)
		(property "Footprint" ""
			(at 236.855 271.145 0)
			(effects
				(font
					(size 1.27 1.27)
					(thickness 0.15)
				)
				(justify left bottom)
				(hide yes)
			)
		)
		(property "Datasheet" ""
			(at 236.855 276.225 0)
			(effects
				(font
					(size 1.27 1.27)
					(thickness 0.15)
				)
				(justify left bottom)
				(hide yes)
			)
		)
		(property "Description" ""
			(at 236.855 278.765 0)
			(effects
				(font
					(size 1.27 1.27)
				)
				(justify left bottom)
				(hide yes)
			)
		)
		(property "Author" "Antmicro"
			(at 236.855 271.145 0)
			(effects
				(font
					(size 1.27 1.27)
					(thickness 0.15)
				)
				(justify left bottom)
				(hide yes)
			)
		)
		(property "License" "Apache-2.0"
			(at 236.855 273.685 0)
			(effects
				(font
					(size 1.27 1.27)
					(thickness 0.15)
				)
				(justify left bottom)
				(hide yes)
			)
		)
		(pin "1"
		)
		(instances
			(project "sodimm-ddr5-tester"
				(path ""
					(reference "#PWR0350")
					(unit 1)
				)
			)
		)
	)
	(symbol
		(lib_id "antmicropower:GND")
		(at 304.8 126.365 0)
		(unit 1)
		(exclude_from_sim no)
		(in_bom yes)
		(on_board yes)
		(dnp no)
		(fields_autoplaced yes)
		(property "Reference" "#PWR0370"
			(at 304.8 132.715 0)
			(effects
				(font
					(size 1.27 1.27)
				)
				(hide yes)
			)
		)
		(property "Value" "GND"
			(at 307.34 127.635 0)
			(effects
				(font
					(size 1.27 1.27)
					(thickness 0.15)
				)
				(justify left)
			)
		)
		(property "Footprint" ""
			(at 313.69 133.985 0)
			(effects
				(font
					(size 1.27 1.27)
					(thickness 0.15)
				)
				(justify left bottom)
				(hide yes)
			)
		)
		(property "Datasheet" ""
			(at 313.69 139.065 0)
			(effects
				(font
					(size 1.27 1.27)
					(thickness 0.15)
				)
				(justify left bottom)
				(hide yes)
			)
		)
		(property "Description" ""
			(at 313.69 141.605 0)
			(effects
				(font
					(size 1.27 1.27)
				)
				(justify left bottom)
				(hide yes)
			)
		)
		(property "Author" "Antmicro"
			(at 313.69 133.985 0)
			(effects
				(font
					(size 1.27 1.27)
					(thickness 0.15)
				)
				(justify left bottom)
				(hide yes)
			)
		)
		(property "License" "Apache-2.0"
			(at 313.69 136.525 0)
			(effects
				(font
					(size 1.27 1.27)
					(thickness 0.15)
				)
				(justify left bottom)
				(hide yes)
			)
		)
		(pin "1"
		)
		(instances
			(project "sodimm-ddr5-tester"
				(path ""
					(reference "#PWR0370")
					(unit 1)
				)
			)
		)
	)
	(symbol
		(lib_id "antmicropower:+5V")
		(at 326.39 178.435 0)
		(unit 1)
		(exclude_from_sim no)
		(in_bom yes)
		(on_board yes)
		(dnp no)
		(fields_autoplaced yes)
		(property "Reference" "#PWR0323"
			(at 326.39 182.245 0)
			(effects
				(font
					(size 1.27 1.27)
				)
				(hide yes)
			)
		)
		(property "Value" "+5V"
			(at 326.39 174.8606 0)
			(effects
				(font
					(size 1.27 1.27)
					(thickness 0.15)
				)
			)
		)
		(property "Footprint" ""
			(at 341.63 186.055 0)
			(effects
				(font
					(size 1.27 1.27)
					(thickness 0.15)
				)
				(justify left bottom)
				(hide yes)
			)
		)
		(property "Datasheet" ""
			(at 341.63 188.595 0)
			(effects
				(font
					(size 1.27 1.27)
					(thickness 0.15)
				)
				(justify left bottom)
				(hide yes)
			)
		)
		(property "Description" ""
			(at 326.39 178.435 0)
			(effects
				(font
					(size 1.27 1.27)
				)
			)
		)
		(property "Author" "Antmicro"
			(at 341.63 186.055 0)
			(effects
				(font
					(size 1.27 1.27)
					(thickness 0.15)
				)
				(justify left bottom)
				(hide yes)
			)
		)
		(property "License" "Apache-2.0"
			(at 341.63 188.595 0)
			(effects
				(font
					(size 1.27 1.27)
					(thickness 0.15)
				)
				(justify left bottom)
				(hide yes)
			)
		)
		(pin "1"
		)
		(instances
			(project "sodimm-ddr5-tester"
				(path ""
					(reference "#PWR0323")
					(unit 1)
				)
			)
		)
	)
	(symbol
		(lib_id "antmicroDataAcquisitionDigitaltoAnalogConvertersDAC:MCP4726A0T_DFN")
		(at 135.89 252.73 0)
		(unit 1)
		(exclude_from_sim no)
		(in_bom yes)
		(on_board yes)
		(dnp no)
		(fields_autoplaced yes)
		(property "Reference" "U29"
			(at 145.415 246.505 0)
			(effects
				(font
					(size 1.27 1.27)
					(thickness 0.15)
				)
			)
		)
		(property "Value" "MCP4726A0T_DFN"
			(at 168.91 260.35 0)
			(effects
				(font
					(size 1.27 1.27)
					(thickness 0.15)
				)
				(justify left bottom)
				(hide yes)
			)
		)
		(property "Footprint" "antmicro-footprints:DFN-6-1EP_2x2mm_P0.65mm_EP1x1.6mm"
			(at 168.91 262.89 0)
			(effects
				(font
					(size 1.27 1.27)
					(thickness 0.15)
				)
				(justify left bottom)
				(hide yes)
			)
		)
		(property "Datasheet" "https://ww1.microchip.com/downloads/en/DeviceDoc/22272C.pdf"
			(at 168.91 265.43 0)
			(effects
				(font
					(size 1.27 1.27)
					(thickness 0.15)
				)
				(justify left bottom)
				(hide yes)
			)
		)
		(property "Description" ""
			(at 135.89 252.73 0)
			(effects
				(font
					(size 1.27 1.27)
				)
			)
		)
		(property "MPN" "MCP4726A0T-E/MAY"
			(at 145.415 249.0287 0)
			(effects
				(font
					(size 1.27 1.27)
					(thickness 0.15)
				)
			)
		)
		(property "Manufacturer" "Microchip Technology"
			(at 168.91 267.97 0)
			(effects
				(font
					(size 1.27 1.27)
					(thickness 0.15)
				)
				(justify left bottom)
				(hide yes)
			)
		)
		(property "Author" "Antmicro"
			(at 168.91 270.51 0)
			(effects
				(font
					(size 1.27 1.27)
					(thickness 0.15)
				)
				(justify left bottom)
				(hide yes)
			)
		)
		(property "License" "Apache-2.0"
			(at 168.91 273.05 0)
			(effects
				(font
					(size 1.27 1.27)
					(thickness 0.15)
				)
				(justify left bottom)
				(hide yes)
			)
		)
		(pin "1"
		)
		(pin "2"
		)
		(pin "3"
		)
		(pin "4"
		)
		(pin "5"
		)
		(pin "6"
		)
		(pin "7"
		)
		(instances
			(project "sodimm-ddr5-tester"
				(path ""
					(reference "U29")
					(unit 1)
				)
			)
		)
	)
	(symbol
		(lib_id "antmicroCapacitors0402:C_10u_6.3V_0402")
		(at 114.935 256.54 90)
		(unit 1)
		(exclude_from_sim no)
		(in_bom yes)
		(on_board yes)
		(dnp no)
		(fields_autoplaced yes)
		(property "Reference" "C207"
			(at 117.2591 253.163 90)
			(effects
				(font
					(size 1.27 1.27)
					(thickness 0.15)
				)
				(justify right)
			)
		)
		(property "Value" "C_10u_6.3V_0402"
			(at 125.095 236.22 0)
			(effects
				(font
					(size 1.27 1.27)
					(thickness 0.15)
				)
				(justify left bottom)
				(hide yes)
			)
		)
		(property "Footprint" "antmicro-footprints:C_0402_1005Metric"
			(at 127.635 236.22 0)
			(effects
				(font
					(size 1.27 1.27)
					(thickness 0.15)
				)
				(justify left bottom)
				(hide yes)
			)
		)
		(property "Datasheet" "https://www.murata.com/products/productdetail?partno=GRM155R60J106ME15%23"
			(at 130.175 236.22 0)
			(effects
				(font
					(size 1.27 1.27)
					(thickness 0.15)
				)
				(justify left bottom)
				(hide yes)
			)
		)
		(property "Description" ""
			(at 114.935 256.54 0)
			(effects
				(font
					(size 1.27 1.27)
				)
			)
		)
		(property "MPN" "GRM155R60J106ME15D"
			(at 132.715 236.22 0)
			(effects
				(font
					(size 1.27 1.27)
					(thickness 0.15)
				)
				(justify left bottom)
				(hide yes)
			)
		)
		(property "Manufacturer" "Murata"
			(at 135.255 236.22 0)
			(effects
				(font
					(size 1.27 1.27)
					(thickness 0.15)
				)
				(justify left bottom)
				(hide yes)
			)
		)
		(property "License" "Apache-2.0"
			(at 137.795 236.22 0)
			(effects
				(font
					(size 1.27 1.27)
					(thickness 0.15)
				)
				(justify left bottom)
				(hide yes)
			)
		)
		(property "Author" "Antmicro"
			(at 140.335 236.22 0)
			(effects
				(font
					(size 1.27 1.27)
					(thickness 0.15)
				)
				(justify left bottom)
				(hide yes)
			)
		)
		(property "Val" "10u"
			(at 117.2591 255.6867 90)
			(effects
				(font
					(size 1.27 1.27)
					(thickness 0.15)
				)
				(justify right)
			)
		)
		(property "Voltage" "6.3V"
			(at 142.875 236.22 0)
			(effects
				(font
					(size 1.27 1.27)
				)
				(justify left bottom)
				(hide yes)
			)
		)
		(property "Dielectric" "X5R"
			(at 145.415 236.22 0)
			(effects
				(font
					(size 1.27 1.27)
				)
				(justify left bottom)
				(hide yes)
			)
		)
		(pin "1"
		)
		(pin "2"
		)
		(instances
			(project "sodimm-ddr5-tester"
				(path ""
					(reference "C207")
					(unit 1)
				)
			)
		)
	)
	(symbol
		(lib_id "antmicroCapacitors0603:C_22u_0603")
		(at 106.045 114.3 90)
		(unit 1)
		(exclude_from_sim no)
		(in_bom yes)
		(on_board yes)
		(dnp no)
		(property "Reference" "C217"
			(at 106.68 109.855 90)
			(effects
				(font
					(size 1.27 1.27)
				)
				(justify right)
			)
		)
		(property "Value" "C_22u_0603"
			(at 116.205 93.98 0)
			(effects
				(font
					(size 1.27 1.27)
					(thickness 0.15)
				)
				(justify left bottom)
				(hide yes)
			)
		)
		(property "Footprint" "antmicro-footprints:C_0603_1608Metric"
			(at 118.745 93.98 0)
			(effects
				(font
					(size 1.27 1.27)
					(thickness 0.15)
				)
				(justify left bottom)
				(hide yes)
			)
		)
		(property "Datasheet" "https://www.murata.com/products/productdetail?partno=GRM188R60J226MEA0%23"
			(at 121.285 93.98 0)
			(effects
				(font
					(size 1.27 1.27)
					(thickness 0.15)
				)
				(justify left bottom)
				(hide yes)
			)
		)
		(property "Description" ""
			(at 106.045 114.3 0)
			(effects
				(font
					(size 1.27 1.27)
				)
			)
		)
		(property "Manufacturer" "Murata"
			(at 126.365 93.98 0)
			(effects
				(font
					(size 1.27 1.27)
					(thickness 0.15)
				)
				(justify left bottom)
				(hide yes)
			)
		)
		(property "MPN" "GRM188R60J226MEA0D"
			(at 123.825 93.98 0)
			(effects
				(font
					(size 1.27 1.27)
					(thickness 0.15)
				)
				(justify left bottom)
				(hide yes)
			)
		)
		(property "Val" "22u"
			(at 106.68 113.665 90)
			(effects
				(font
					(size 1.27 1.27)
					(thickness 0.15)
				)
				(justify right)
			)
		)
		(property "License" "Apache-2.0"
			(at 128.905 93.98 0)
			(effects
				(font
					(size 1.27 1.27)
					(thickness 0.15)
				)
				(justify left bottom)
				(hide yes)
			)
		)
		(property "Author" "Antmicro"
			(at 131.445 93.98 0)
			(effects
				(font
					(size 1.27 1.27)
					(thickness 0.15)
				)
				(justify left bottom)
				(hide yes)
			)
		)
		(property "Voltage" ""
			(at 133.985 93.98 0)
			(effects
				(font
					(size 1.27 1.27)
				)
				(justify left bottom)
				(hide yes)
			)
		)
		(property "Dielectric" ""
			(at 136.525 93.98 0)
			(effects
				(font
					(size 1.27 1.27)
				)
				(justify left bottom)
				(hide yes)
			)
		)
		(pin "1"
		)
		(pin "2"
		)
		(instances
			(project "sodimm-ddr5-tester"
				(path ""
					(reference "C217")
					(unit 1)
				)
			)
		)
	)
	(symbol
		(lib_id "antmicroTVSDiodes:ESDA25P35-1U1M")
		(at 50.165 30.48 90)
		(unit 1)
		(exclude_from_sim no)
		(in_bom yes)
		(on_board yes)
		(dnp no)
		(property "Reference" "D16"
			(at 50.8 30.48 90)
			(effects
				(font
					(size 1.27 1.27)
				)
				(justify right)
			)
		)
		(property "Value" "ESDA25P35-1U1M"
			(at 38.735 36.83 90)
			(effects
				(font
					(size 1.27 1.27)
					(thickness 0.15)
				)
				(justify right)
			)
		)
		(property "Footprint" "antmicro-footprints:ESDA25P35-1U1M"
			(at 60.325 6.35 0)
			(effects
				(font
					(size 1.27 1.27)
					(thickness 0.15)
				)
				(justify left bottom)
				(hide yes)
			)
		)
		(property "Datasheet" "https://www.st.com/resource/en/datasheet/esda25p35-1u1m.pdf"
			(at 62.865 6.35 0)
			(effects
				(font
					(size 1.27 1.27)
					(thickness 0.15)
				)
				(justify left bottom)
				(hide yes)
			)
		)
		(property "Description" ""
			(at 50.165 30.48 0)
			(effects
				(font
					(size 1.27 1.27)
				)
			)
		)
		(property "MPN" "ESDA25P35-1U1M"
			(at 65.405 6.35 0)
			(effects
				(font
					(size 1.27 1.27)
					(thickness 0.15)
				)
				(justify left bottom)
				(hide yes)
			)
		)
		(property "Manufacturer" "STMicroelectronics"
			(at 67.945 6.35 0)
			(effects
				(font
					(size 1.27 1.27)
					(thickness 0.15)
				)
				(justify left bottom)
				(hide yes)
			)
		)
		(property "Author" "Antmicro"
			(at 70.485 6.35 0)
			(effects
				(font
					(size 1.27 1.27)
					(thickness 0.15)
				)
				(justify left bottom)
				(hide yes)
			)
		)
		(property "License" "Apache-2.0"
			(at 73.025 6.35 0)
			(effects
				(font
					(size 1.27 1.27)
					(thickness 0.15)
				)
				(justify left bottom)
				(hide yes)
			)
		)
		(pin "1"
		)
		(pin "2"
		)
		(instances
			(project "sodimm-ddr5-tester"
				(path ""
					(reference "D16")
					(unit 1)
				)
			)
		)
	)
	(symbol
		(lib_id "antmicroCapacitorsmisc:C_22u_25V_0805")
		(at 17.145 164.465 90)
		(unit 1)
		(exclude_from_sim no)
		(in_bom yes)
		(on_board yes)
		(dnp no)
		(property "Reference" "C171"
			(at 17.78 160.02 90)
			(effects
				(font
					(size 1.27 1.27)
				)
				(justify right)
			)
		)
		(property "Value" "C_22u_25V_0805"
			(at 20.955 164.465 0)
			(effects
				(font
					(size 1.27 1.27)
				)
				(hide yes)
			)
		)
		(property "Footprint" "antmicro-footprints:C_0805_2012Metric"
			(at 12.065 159.385 0)
			(effects
				(font
					(size 1.27 1.27)
				)
				(justify left)
				(hide yes)
			)
		)
		(property "Datasheet" "https://product.samsungsem.com/mlcc/CL21A226MAYNNN.do"
			(at 17.145 164.465 0)
			(effects
				(font
					(size 1.27 1.27)
				)
				(hide yes)
			)
		)
		(property "Description" ""
			(at 17.145 164.465 0)
			(effects
				(font
					(size 1.27 1.27)
				)
			)
		)
		(property "Manufacturer" "Samsung Electro-Mechanics"
			(at 6.985 159.385 0)
			(effects
				(font
					(size 1.27 1.27)
				)
				(justify left)
				(hide yes)
			)
		)
		(property "MPN" "CL21A226MAYNNNE"
			(at 9.525 159.385 0)
			(effects
				(font
					(size 1.27 1.27)
				)
				(justify left)
				(hide yes)
			)
		)
		(property "Val" "22u_25V"
			(at 17.78 163.83 90)
			(effects
				(font
					(size 1.27 1.27)
				)
				(justify right)
			)
		)
		(property "License" "Apache-2.0"
			(at 40.005 144.145 0)
			(effects
				(font
					(size 1.27 1.27)
					(thickness 0.15)
				)
				(justify left bottom)
				(hide yes)
			)
		)
		(property "Author" "Antmicro"
			(at 42.545 144.145 0)
			(effects
				(font
					(size 1.27 1.27)
					(thickness 0.15)
				)
				(justify left bottom)
				(hide yes)
			)
		)
		(property "Voltage" ""
			(at 45.085 144.145 0)
			(effects
				(font
					(size 1.27 1.27)
				)
				(justify left bottom)
				(hide yes)
			)
		)
		(property "Dielectric" ""
			(at 47.625 144.145 0)
			(effects
				(font
					(size 1.27 1.27)
				)
				(justify left bottom)
				(hide yes)
			)
		)
		(pin "1"
		)
		(pin "2"
		)
		(instances
			(project "sodimm-ddr5-tester"
				(path ""
					(reference "C171")
					(unit 1)
				)
			)
		)
	)
	(symbol
		(lib_id "antmicroResistors0402:R_0R_0402")
		(at 190.5 212.09 90)
		(unit 1)
		(exclude_from_sim no)
		(in_bom no)
		(on_board yes)
		(dnp yes)
		(property "Reference" "R165"
			(at 192.405 208.28 90)
			(effects
				(font
					(size 1.27 1.27)
				)
				(justify right)
			)
		)
		(property "Value" "R_0R_0402"
			(at 203.2 191.77 0)
			(effects
				(font
					(size 1.27 1.27)
					(thickness 0.15)
				)
				(justify left bottom)
				(hide yes)
			)
		)
		(property "Footprint" "antmicro-footprints:R_0402_1005Metric"
			(at 205.74 191.77 0)
			(effects
				(font
					(size 1.27 1.27)
					(thickness 0.15)
				)
				(justify left bottom)
				(hide yes)
			)
		)
		(property "Datasheet" "https://industrial.panasonic.com/cdbs/www-data/pdf/RDA0000/AOA0000C301.pdf"
			(at 208.28 191.77 0)
			(effects
				(font
					(size 1.27 1.27)
					(thickness 0.15)
				)
				(justify left bottom)
				(hide yes)
			)
		)
		(property "Description" ""
			(at 190.5 212.09 0)
			(effects
				(font
					(size 1.27 1.27)
				)
			)
		)
		(property "Manufacturer" "Panasonic"
			(at 213.36 191.77 0)
			(effects
				(font
					(size 1.27 1.27)
					(thickness 0.15)
				)
				(justify left bottom)
				(hide yes)
			)
		)
		(property "MPN" "ERJ2GE0R00X"
			(at 210.82 191.77 0)
			(effects
				(font
					(size 1.27 1.27)
					(thickness 0.15)
				)
				(justify left bottom)
				(hide yes)
			)
		)
		(property "Val" "0R"
			(at 192.405 210.82 90)
			(effects
				(font
					(size 1.27 1.27)
					(thickness 0.15)
				)
				(justify right)
			)
		)
		(property "License" "Apache-2.0"
			(at 215.9 191.77 0)
			(effects
				(font
					(size 1.27 1.27)
					(thickness 0.15)
				)
				(justify left bottom)
				(hide yes)
			)
		)
		(property "Author" "Antmicro"
			(at 218.44 191.77 0)
			(effects
				(font
					(size 1.27 1.27)
					(thickness 0.15)
				)
				(justify left bottom)
				(hide yes)
			)
		)
		(property "Tolerance" "~"
			(at 200.66 191.77 0)
			(effects
				(font
					(size 1.27 1.27)
				)
				(justify left bottom)
				(hide yes)
			)
		)
		(property "Current" "1A"
			(at 192.405 213.3599 90)
			(effects
				(font
					(size 1.27 1.27)
					(thickness 0.15)
				)
				(justify right)
				(hide yes)
			)
		)
		(pin "1"
		)
		(pin "2"
		)
		(instances
			(project "sodimm-ddr5-tester"
				(path ""
					(reference "R165")
					(unit 1)
				)
			)
		)
	)
	(symbol
		(lib_id "antmicroShuntsJumpers:Net-Tie_P0.127mm")
		(at 110.49 201.93 90)
		(unit 1)
		(exclude_from_sim no)
		(in_bom no)
		(on_board yes)
		(dnp no)
		(fields_autoplaced yes)
		(property "Reference" "NT3"
			(at 109.22 201.93 0)
			(effects
				(font
					(size 1.27 1.27)
				)
				(hide yes)
			)
		)
		(property "Value" "Net-Tie_P0.127mm"
			(at 118.11 180.34 0)
			(effects
				(font
					(size 1.27 1.27)
					(thickness 0.15)
				)
				(justify left bottom)
				(hide yes)
			)
		)
		(property "Footprint" "antmicro-footprints:NetTie-2_SMD_Pad0.127mm"
			(at 123.19 180.34 0)
			(effects
				(font
					(size 1.27 1.27)
					(thickness 0.15)
				)
				(justify left bottom)
				(hide yes)
			)
		)
		(property "Datasheet" ""
			(at 125.73 180.34 0)
			(effects
				(font
					(size 1.27 1.27)
					(thickness 0.15)
				)
				(justify left bottom)
				(hide yes)
			)
		)
		(property "Description" ""
			(at 110.49 201.93 0)
			(effects
				(font
					(size 1.27 1.27)
				)
			)
		)
		(property "MPN" ""
			(at 120.65 180.34 0)
			(effects
				(font
					(size 1.27 1.27)
					(thickness 0.15)
				)
				(justify left bottom)
			)
		)
		(property "Manufacturer" ""
			(at 128.27 180.34 0)
			(effects
				(font
					(size 1.27 1.27)
					(thickness 0.15)
				)
				(justify left bottom)
				(hide yes)
			)
		)
		(property "Author" "Antmicro"
			(at 130.81 180.34 0)
			(effects
				(font
					(size 1.27 1.27)
					(thickness 0.15)
				)
				(justify left bottom)
				(hide yes)
			)
		)
		(property "License" "Apache-2.0"
			(at 133.35 180.34 0)
			(effects
				(font
					(size 1.27 1.27)
					(thickness 0.15)
				)
				(justify left bottom)
				(hide yes)
			)
		)
		(pin "1"
		)
		(pin "2"
		)
		(instances
			(project "sodimm-ddr5-tester"
				(path ""
					(reference "NT3")
					(unit 1)
				)
			)
		)
	)
	(symbol
		(lib_id "antmicroCapacitors0603:C_22u_0603")
		(at 285.75 226.06 90)
		(unit 1)
		(exclude_from_sim no)
		(in_bom yes)
		(on_board yes)
		(dnp no)
		(fields_autoplaced yes)
		(property "Reference" "C193"
			(at 283.4259 221.4171 90)
			(effects
				(font
					(size 1.27 1.27)
				)
				(justify left)
			)
		)
		(property "Value" "C_22u_0603"
			(at 295.91 205.74 0)
			(effects
				(font
					(size 1.27 1.27)
					(thickness 0.15)
				)
				(justify left bottom)
				(hide yes)
			)
		)
		(property "Footprint" "antmicro-footprints:C_0603_1608Metric"
			(at 298.45 205.74 0)
			(effects
				(font
					(size 1.27 1.27)
					(thickness 0.15)
				)
				(justify left bottom)
				(hide yes)
			)
		)
		(property "Datasheet" "https://www.murata.com/products/productdetail?partno=GRM188R60J226MEA0%23"
			(at 300.99 205.74 0)
			(effects
				(font
					(size 1.27 1.27)
					(thickness 0.15)
				)
				(justify left bottom)
				(hide yes)
			)
		)
		(property "Description" ""
			(at 285.75 226.06 0)
			(effects
				(font
					(size 1.27 1.27)
				)
			)
		)
		(property "Manufacturer" "Murata"
			(at 306.07 205.74 0)
			(effects
				(font
					(size 1.27 1.27)
					(thickness 0.15)
				)
				(justify left bottom)
				(hide yes)
			)
		)
		(property "MPN" "GRM188R60J226MEA0D"
			(at 303.53 205.74 0)
			(effects
				(font
					(size 1.27 1.27)
					(thickness 0.15)
				)
				(justify left bottom)
				(hide yes)
			)
		)
		(property "Val" "22u"
			(at 283.4259 223.9474 90)
			(effects
				(font
					(size 1.27 1.27)
					(thickness 0.15)
				)
				(justify left)
			)
		)
		(property "License" "Apache-2.0"
			(at 308.61 205.74 0)
			(effects
				(font
					(size 1.27 1.27)
					(thickness 0.15)
				)
				(justify left bottom)
				(hide yes)
			)
		)
		(property "Author" "Antmicro"
			(at 311.15 205.74 0)
			(effects
				(font
					(size 1.27 1.27)
					(thickness 0.15)
				)
				(justify left bottom)
				(hide yes)
			)
		)
		(property "Voltage" ""
			(at 313.69 205.74 0)
			(effects
				(font
					(size 1.27 1.27)
				)
				(justify left bottom)
				(hide yes)
			)
		)
		(property "Dielectric" ""
			(at 316.23 205.74 0)
			(effects
				(font
					(size 1.27 1.27)
				)
				(justify left bottom)
				(hide yes)
			)
		)
		(pin "1"
		)
		(pin "2"
		)
		(instances
			(project "sodimm-ddr5-tester"
				(path ""
					(reference "C193")
					(unit 1)
				)
			)
		)
	)
	(symbol
		(lib_id "antmicroCapacitorsmisc:C_22u_25V_0805")
		(at 27.305 164.465 90)
		(unit 1)
		(exclude_from_sim no)
		(in_bom yes)
		(on_board yes)
		(dnp no)
		(property "Reference" "C177"
			(at 27.94 160.02 90)
			(effects
				(font
					(size 1.27 1.27)
				)
				(justify right)
			)
		)
		(property "Value" "C_22u_25V_0805"
			(at 31.115 164.465 0)
			(effects
				(font
					(size 1.27 1.27)
				)
				(hide yes)
			)
		)
		(property "Footprint" "antmicro-footprints:C_0805_2012Metric"
			(at 22.225 159.385 0)
			(effects
				(font
					(size 1.27 1.27)
				)
				(justify left)
				(hide yes)
			)
		)
		(property "Datasheet" "https://product.samsungsem.com/mlcc/CL21A226MAYNNN.do"
			(at 27.305 164.465 0)
			(effects
				(font
					(size 1.27 1.27)
				)
				(hide yes)
			)
		)
		(property "Description" ""
			(at 27.305 164.465 0)
			(effects
				(font
					(size 1.27 1.27)
				)
			)
		)
		(property "Manufacturer" "Samsung Electro-Mechanics"
			(at 17.145 159.385 0)
			(effects
				(font
					(size 1.27 1.27)
				)
				(justify left)
				(hide yes)
			)
		)
		(property "MPN" "CL21A226MAYNNNE"
			(at 19.685 159.385 0)
			(effects
				(font
					(size 1.27 1.27)
				)
				(justify left)
				(hide yes)
			)
		)
		(property "Val" "22u_25V"
			(at 27.94 163.83 90)
			(effects
				(font
					(size 1.27 1.27)
				)
				(justify right)
			)
		)
		(property "License" "Apache-2.0"
			(at 50.165 144.145 0)
			(effects
				(font
					(size 1.27 1.27)
					(thickness 0.15)
				)
				(justify left bottom)
				(hide yes)
			)
		)
		(property "Author" "Antmicro"
			(at 52.705 144.145 0)
			(effects
				(font
					(size 1.27 1.27)
					(thickness 0.15)
				)
				(justify left bottom)
				(hide yes)
			)
		)
		(property "Voltage" ""
			(at 55.245 144.145 0)
			(effects
				(font
					(size 1.27 1.27)
				)
				(justify left bottom)
				(hide yes)
			)
		)
		(property "Dielectric" ""
			(at 57.785 144.145 0)
			(effects
				(font
					(size 1.27 1.27)
				)
				(justify left bottom)
				(hide yes)
			)
		)
		(pin "1"
		)
		(pin "2"
		)
		(instances
			(project "sodimm-ddr5-tester"
				(path ""
					(reference "C177")
					(unit 1)
				)
			)
		)
	)
	(symbol
		(lib_id "antmicropower:GND")
		(at 163.195 263.525 0)
		(mirror y)
		(unit 1)
		(exclude_from_sim no)
		(in_bom yes)
		(on_board yes)
		(dnp no)
		(property "Reference" "#PWR0391"
			(at 163.195 269.875 0)
			(effects
				(font
					(size 1.27 1.27)
				)
				(hide yes)
			)
		)
		(property "Value" "GND"
			(at 161.036 267.462 0)
			(effects
				(font
					(size 1.27 1.27)
					(thickness 0.15)
				)
				(justify right)
			)
		)
		(property "Footprint" ""
			(at 154.305 271.145 0)
			(effects
				(font
					(size 1.27 1.27)
					(thickness 0.15)
				)
				(justify left bottom)
				(hide yes)
			)
		)
		(property "Datasheet" ""
			(at 154.305 276.225 0)
			(effects
				(font
					(size 1.27 1.27)
					(thickness 0.15)
				)
				(justify left bottom)
				(hide yes)
			)
		)
		(property "Description" ""
			(at 154.305 278.765 0)
			(effects
				(font
					(size 1.27 1.27)
				)
				(justify left bottom)
				(hide yes)
			)
		)
		(property "Author" "Antmicro"
			(at 154.305 271.145 0)
			(effects
				(font
					(size 1.27 1.27)
					(thickness 0.15)
				)
				(justify left bottom)
				(hide yes)
			)
		)
		(property "License" "Apache-2.0"
			(at 154.305 273.685 0)
			(effects
				(font
					(size 1.27 1.27)
					(thickness 0.15)
				)
				(justify left bottom)
				(hide yes)
			)
		)
		(pin "1"
		)
		(instances
			(project "sodimm-ddr5-tester"
				(path ""
					(reference "#PWR0391")
					(unit 1)
				)
			)
		)
	)
	(symbol
		(lib_id "antmicroShuntsJumpers:Net-Tie_P0.127mm")
		(at 304.8 184.15 90)
		(unit 1)
		(exclude_from_sim no)
		(in_bom no)
		(on_board yes)
		(dnp no)
		(fields_autoplaced yes)
		(property "Reference" "NT6"
			(at 303.53 184.15 0)
			(effects
				(font
					(size 1.27 1.27)
				)
				(hide yes)
			)
		)
		(property "Value" "Net-Tie_P0.127mm"
			(at 312.42 162.56 0)
			(effects
				(font
					(size 1.27 1.27)
					(thickness 0.15)
				)
				(justify left bottom)
				(hide yes)
			)
		)
		(property "Footprint" "antmicro-footprints:NetTie-2_SMD_Pad0.127mm"
			(at 317.5 162.56 0)
			(effects
				(font
					(size 1.27 1.27)
					(thickness 0.15)
				)
				(justify left bottom)
				(hide yes)
			)
		)
		(property "Datasheet" ""
			(at 320.04 162.56 0)
			(effects
				(font
					(size 1.27 1.27)
					(thickness 0.15)
				)
				(justify left bottom)
				(hide yes)
			)
		)
		(property "Description" ""
			(at 304.8 184.15 0)
			(effects
				(font
					(size 1.27 1.27)
				)
			)
		)
		(property "MPN" ""
			(at 314.96 162.56 0)
			(effects
				(font
					(size 1.27 1.27)
					(thickness 0.15)
				)
				(justify left bottom)
			)
		)
		(property "Manufacturer" ""
			(at 322.58 162.56 0)
			(effects
				(font
					(size 1.27 1.27)
					(thickness 0.15)
				)
				(justify left bottom)
				(hide yes)
			)
		)
		(property "Author" "Antmicro"
			(at 325.12 162.56 0)
			(effects
				(font
					(size 1.27 1.27)
					(thickness 0.15)
				)
				(justify left bottom)
				(hide yes)
			)
		)
		(property "License" "Apache-2.0"
			(at 327.66 162.56 0)
			(effects
				(font
					(size 1.27 1.27)
					(thickness 0.15)
				)
				(justify left bottom)
				(hide yes)
			)
		)
		(pin "1"
		)
		(pin "2"
		)
		(instances
			(project "sodimm-ddr5-tester"
				(path ""
					(reference "NT6")
					(unit 1)
				)
			)
		)
	)
	(symbol
		(lib_id "antmicroCapacitors0603:C_22u_0603")
		(at 285.75 205.105 90)
		(unit 1)
		(exclude_from_sim no)
		(in_bom yes)
		(on_board yes)
		(dnp no)
		(property "Reference" "C192"
			(at 286.385 200.66 90)
			(effects
				(font
					(size 1.27 1.27)
				)
				(justify right)
			)
		)
		(property "Value" "C_22u_0603"
			(at 295.91 184.785 0)
			(effects
				(font
					(size 1.27 1.27)
					(thickness 0.15)
				)
				(justify left bottom)
				(hide yes)
			)
		)
		(property "Footprint" "antmicro-footprints:C_0603_1608Metric"
			(at 298.45 184.785 0)
			(effects
				(font
					(size 1.27 1.27)
					(thickness 0.15)
				)
				(justify left bottom)
				(hide yes)
			)
		)
		(property "Datasheet" "https://www.murata.com/products/productdetail?partno=GRM188R60J226MEA0%23"
			(at 300.99 184.785 0)
			(effects
				(font
					(size 1.27 1.27)
					(thickness 0.15)
				)
				(justify left bottom)
				(hide yes)
			)
		)
		(property "Description" ""
			(at 285.75 205.105 0)
			(effects
				(font
					(size 1.27 1.27)
				)
			)
		)
		(property "Manufacturer" "Murata"
			(at 306.07 184.785 0)
			(effects
				(font
					(size 1.27 1.27)
					(thickness 0.15)
				)
				(justify left bottom)
				(hide yes)
			)
		)
		(property "MPN" "GRM188R60J226MEA0D"
			(at 303.53 184.785 0)
			(effects
				(font
					(size 1.27 1.27)
					(thickness 0.15)
				)
				(justify left bottom)
				(hide yes)
			)
		)
		(property "Val" "22u"
			(at 286.385 204.47 90)
			(effects
				(font
					(size 1.27 1.27)
					(thickness 0.15)
				)
				(justify right)
			)
		)
		(property "License" "Apache-2.0"
			(at 308.61 184.785 0)
			(effects
				(font
					(size 1.27 1.27)
					(thickness 0.15)
				)
				(justify left bottom)
				(hide yes)
			)
		)
		(property "Author" "Antmicro"
			(at 311.15 184.785 0)
			(effects
				(font
					(size 1.27 1.27)
					(thickness 0.15)
				)
				(justify left bottom)
				(hide yes)
			)
		)
		(property "Voltage" ""
			(at 313.69 184.785 0)
			(effects
				(font
					(size 1.27 1.27)
				)
				(justify left bottom)
				(hide yes)
			)
		)
		(property "Dielectric" ""
			(at 316.23 184.785 0)
			(effects
				(font
					(size 1.27 1.27)
				)
				(justify left bottom)
				(hide yes)
			)
		)
		(pin "1"
		)
		(pin "2"
		)
		(instances
			(project "sodimm-ddr5-tester"
				(path ""
					(reference "C192")
					(unit 1)
				)
			)
		)
	)
	(symbol
		(lib_id "antmicroCapacitors0402:C_100n_0402")
		(at 351.155 40.005 90)
		(unit 1)
		(exclude_from_sim no)
		(in_bom yes)
		(on_board yes)
		(dnp no)
		(fields_autoplaced yes)
		(property "Reference" "C212"
			(at 353.695 36.1885 90)
			(effects
				(font
					(size 1.27 1.27)
				)
				(justify right)
			)
		)
		(property "Value" "C_100n_0402"
			(at 361.315 19.685 0)
			(effects
				(font
					(size 1.27 1.27)
					(thickness 0.15)
				)
				(justify left bottom)
				(hide yes)
			)
		)
		(property "Footprint" "antmicro-footprints:C_0402_1005Metric"
			(at 363.855 19.685 0)
			(effects
				(font
					(size 1.27 1.27)
					(thickness 0.15)
				)
				(justify left bottom)
				(hide yes)
			)
		)
		(property "Datasheet" "https://www.murata.com/products/productdetail?partno=GRM155R61H104KE14%23"
			(at 366.395 19.685 0)
			(effects
				(font
					(size 1.27 1.27)
					(thickness 0.15)
				)
				(justify left bottom)
				(hide yes)
			)
		)
		(property "Description" ""
			(at 351.155 40.005 0)
			(effects
				(font
					(size 1.27 1.27)
				)
			)
		)
		(property "Manufacturer" "Murata"
			(at 371.475 19.685 0)
			(effects
				(font
					(size 1.27 1.27)
					(thickness 0.15)
				)
				(justify left bottom)
				(hide yes)
			)
		)
		(property "MPN" "GRM155R61H104KE14D"
			(at 368.935 19.685 0)
			(effects
				(font
					(size 1.27 1.27)
					(thickness 0.15)
				)
				(justify left bottom)
				(hide yes)
			)
		)
		(property "Val" "100n"
			(at 353.695 38.7285 90)
			(effects
				(font
					(size 1.27 1.27)
					(thickness 0.15)
				)
				(justify right)
			)
		)
		(property "License" "Apache-2.0"
			(at 374.015 19.685 0)
			(effects
				(font
					(size 1.27 1.27)
					(thickness 0.15)
				)
				(justify left bottom)
				(hide yes)
			)
		)
		(property "Author" "Antmicro"
			(at 376.555 19.685 0)
			(effects
				(font
					(size 1.27 1.27)
					(thickness 0.15)
				)
				(justify left bottom)
				(hide yes)
			)
		)
		(property "Voltage" "50V"
			(at 379.095 19.685 0)
			(effects
				(font
					(size 1.27 1.27)
				)
				(justify left bottom)
				(hide yes)
			)
		)
		(property "Dielectric" "X5R"
			(at 381.635 19.685 0)
			(effects
				(font
					(size 1.27 1.27)
				)
				(justify left bottom)
				(hide yes)
			)
		)
		(pin "1"
		)
		(pin "2"
		)
		(instances
			(project "sodimm-ddr5-tester"
				(path ""
					(reference "C212")
					(unit 1)
				)
			)
		)
	)
	(symbol
		(lib_id "antmicroTransistorsFETsMOSFETsSingle:BSS138PW,115")
		(at 220.345 258.445 0)
		(unit 1)
		(exclude_from_sim no)
		(in_bom yes)
		(on_board yes)
		(dnp no)
		(property "Reference" "Q15"
			(at 219.329 252.095 0)
			(effects
				(font
					(size 1.27 1.27)
					(thickness 0.15)
				)
				(justify left)
			)
		)
		(property "Value" "BSS138PW,115"
			(at 243.205 267.335 0)
			(effects
				(font
					(size 1.27 1.27)
					(thickness 0.15)
				)
				(justify left bottom)
				(hide yes)
			)
		)
		(property "Footprint" "antmicro-footprints:SC70-3"
			(at 243.205 269.875 0)
			(effects
				(font
					(size 1.27 1.27)
					(thickness 0.15)
				)
				(justify left bottom)
				(hide yes)
			)
		)
		(property "Datasheet" "https://assets.nexperia.com/documents/data-sheet/BSS138PW.pdf"
			(at 243.205 272.415 0)
			(effects
				(font
					(size 1.27 1.27)
					(thickness 0.15)
				)
				(justify left bottom)
				(hide yes)
			)
		)
		(property "Description" "Power MOSFET, N Channel, 60 V, 320 mA, 0.9 ohm, SOT-323, Surface Mount"
			(at 243.205 285.115 0)
			(effects
				(font
					(size 1.27 1.27)
				)
				(justify left bottom)
				(hide yes)
			)
		)
		(property "MPN" "BSS138PW,115"
			(at 208.661 254.381 0)
			(effects
				(font
					(size 1.27 1.27)
					(thickness 0.15)
				)
				(justify left)
			)
		)
		(property "Manufacturer" "Nexperia"
			(at 243.205 277.495 0)
			(effects
				(font
					(size 1.27 1.27)
					(thickness 0.15)
				)
				(justify left bottom)
				(hide yes)
			)
		)
		(property "Author" "Antmicro"
			(at 243.205 280.035 0)
			(effects
				(font
					(size 1.27 1.27)
					(thickness 0.15)
				)
				(justify left bottom)
				(hide yes)
			)
		)
		(property "License" "Apache-2.0"
			(at 243.205 282.575 0)
			(effects
				(font
					(size 1.27 1.27)
					(thickness 0.15)
				)
				(justify left bottom)
				(hide yes)
			)
		)
		(pin "3"
		)
		(pin "2"
		)
		(pin "1"
		)
		(instances
			(project "sodimm-ddr5-tester"
				(path ""
					(reference "Q15")
					(unit 1)
				)
			)
		)
	)
	(symbol
		(lib_id "antmicroResistors0603:R_0R_22.4A_0603")
		(at 74.295 247.015 0)
		(unit 1)
		(exclude_from_sim no)
		(in_bom yes)
		(on_board yes)
		(dnp no)
		(fields_autoplaced yes)
		(property "Reference" "R183"
			(at 76.835 239.9106 0)
			(effects
				(font
					(size 1.27 1.27)
				)
			)
		)
		(property "Value" "R_0R_22.4A_0603"
			(at 76.835 239.9173 0)
			(effects
				(font
					(size 1.27 1.27)
					(thickness 0.15)
				)
				(hide yes)
			)
		)
		(property "Footprint" "antmicro-footprints:R_0603_1608Metric"
			(at 97.155 259.715 0)
			(effects
				(font
					(size 1.27 1.27)
					(thickness 0.15)
				)
				(justify left bottom)
				(hide yes)
			)
		)
		(property "Datasheet" "https://fscdn.rohm.com/en/products/databook/datasheet/passive/resistor/chip_resistor/pmr-jpw-e.pdf"
			(at 97.155 262.255 0)
			(effects
				(font
					(size 1.27 1.27)
					(thickness 0.15)
				)
				(justify left bottom)
				(hide yes)
			)
		)
		(property "Description" ""
			(at 74.295 247.015 0)
			(effects
				(font
					(size 1.27 1.27)
				)
			)
		)
		(property "Manufacturer" "ROHM Semiconductor"
			(at 97.155 264.795 0)
			(effects
				(font
					(size 1.27 1.27)
					(thickness 0.15)
				)
				(justify left bottom)
				(hide yes)
			)
		)
		(property "MPN" "PMR03EZPJ000"
			(at 97.155 267.335 0)
			(effects
				(font
					(size 1.27 1.27)
					(thickness 0.15)
				)
				(justify left bottom)
				(hide yes)
			)
		)
		(property "Val" "0R"
			(at 76.835 242.4409 0)
			(effects
				(font
					(size 1.27 1.27)
					(thickness 0.15)
				)
			)
		)
		(property "Author" "Antmicro"
			(at 97.155 269.875 0)
			(effects
				(font
					(size 1.27 1.27)
					(thickness 0.15)
				)
				(justify left bottom)
				(hide yes)
			)
		)
		(property "License" "Apache-2.0"
			(at 97.155 272.415 0)
			(effects
				(font
					(size 1.27 1.27)
					(thickness 0.15)
				)
				(justify left bottom)
				(hide yes)
			)
		)
		(property "Max. Curr." "22.4A"
			(at 76.835 244.9646 0)
			(effects
				(font
					(size 1.27 1.27)
					(thickness 0.15)
				)
			)
		)
		(pin "1"
		)
		(pin "2"
		)
		(instances
			(project "sodimm-ddr5-tester"
				(path ""
					(reference "R183")
					(unit 1)
				)
			)
		)
	)
	(symbol
		(lib_id "antmicroCapacitors0402:C_100n_0402")
		(at 58.42 73.025 90)
		(unit 1)
		(exclude_from_sim no)
		(in_bom yes)
		(on_board yes)
		(dnp no)
		(fields_autoplaced yes)
		(property "Reference" "C176"
			(at 60.96 69.2085 90)
			(effects
				(font
					(size 1.27 1.27)
				)
				(justify right)
			)
		)
		(property "Value" "C_100n_0402"
			(at 68.58 52.705 0)
			(effects
				(font
					(size 1.27 1.27)
					(thickness 0.15)
				)
				(justify left bottom)
				(hide yes)
			)
		)
		(property "Footprint" "antmicro-footprints:C_0402_1005Metric"
			(at 71.12 52.705 0)
			(effects
				(font
					(size 1.27 1.27)
					(thickness 0.15)
				)
				(justify left bottom)
				(hide yes)
			)
		)
		(property "Datasheet" "https://www.murata.com/products/productdetail?partno=GRM155R61H104KE14%23"
			(at 73.66 52.705 0)
			(effects
				(font
					(size 1.27 1.27)
					(thickness 0.15)
				)
				(justify left bottom)
				(hide yes)
			)
		)
		(property "Description" ""
			(at 58.42 73.025 0)
			(effects
				(font
					(size 1.27 1.27)
				)
			)
		)
		(property "Manufacturer" "Murata"
			(at 78.74 52.705 0)
			(effects
				(font
					(size 1.27 1.27)
					(thickness 0.15)
				)
				(justify left bottom)
				(hide yes)
			)
		)
		(property "MPN" "GRM155R61H104KE14D"
			(at 76.2 52.705 0)
			(effects
				(font
					(size 1.27 1.27)
					(thickness 0.15)
				)
				(justify left bottom)
				(hide yes)
			)
		)
		(property "Val" "100n"
			(at 60.96 71.7485 90)
			(effects
				(font
					(size 1.27 1.27)
					(thickness 0.15)
				)
				(justify right)
			)
		)
		(property "License" "Apache-2.0"
			(at 81.28 52.705 0)
			(effects
				(font
					(size 1.27 1.27)
					(thickness 0.15)
				)
				(justify left bottom)
				(hide yes)
			)
		)
		(property "Author" "Antmicro"
			(at 83.82 52.705 0)
			(effects
				(font
					(size 1.27 1.27)
					(thickness 0.15)
				)
				(justify left bottom)
				(hide yes)
			)
		)
		(property "Voltage" "50V"
			(at 86.36 52.705 0)
			(effects
				(font
					(size 1.27 1.27)
				)
				(justify left bottom)
				(hide yes)
			)
		)
		(property "Dielectric" "X5R"
			(at 88.9 52.705 0)
			(effects
				(font
					(size 1.27 1.27)
				)
				(justify left bottom)
				(hide yes)
			)
		)
		(pin "1"
		)
		(pin "2"
		)
		(instances
			(project "sodimm-ddr5-tester"
				(path ""
					(reference "C176")
					(unit 1)
				)
			)
		)
	)
	(symbol
		(lib_id "antmicropower:GND")
		(at 285.75 169.545 0)
		(unit 1)
		(exclude_from_sim no)
		(in_bom yes)
		(on_board yes)
		(dnp no)
		(fields_autoplaced yes)
		(property "Reference" "#PWR0308"
			(at 285.75 175.895 0)
			(effects
				(font
					(size 1.27 1.27)
				)
				(hide yes)
			)
		)
		(property "Value" "GND"
			(at 288.29 170.815 0)
			(effects
				(font
					(size 1.27 1.27)
					(thickness 0.15)
				)
				(justify left)
			)
		)
		(property "Footprint" ""
			(at 294.64 177.165 0)
			(effects
				(font
					(size 1.27 1.27)
					(thickness 0.15)
				)
				(justify left bottom)
				(hide yes)
			)
		)
		(property "Datasheet" ""
			(at 294.64 182.245 0)
			(effects
				(font
					(size 1.27 1.27)
					(thickness 0.15)
				)
				(justify left bottom)
				(hide yes)
			)
		)
		(property "Description" ""
			(at 294.64 184.785 0)
			(effects
				(font
					(size 1.27 1.27)
				)
				(justify left bottom)
				(hide yes)
			)
		)
		(property "Author" "Antmicro"
			(at 294.64 177.165 0)
			(effects
				(font
					(size 1.27 1.27)
					(thickness 0.15)
				)
				(justify left bottom)
				(hide yes)
			)
		)
		(property "License" "Apache-2.0"
			(at 294.64 179.705 0)
			(effects
				(font
					(size 1.27 1.27)
					(thickness 0.15)
				)
				(justify left bottom)
				(hide yes)
			)
		)
		(pin "1"
		)
		(instances
			(project "sodimm-ddr5-tester"
				(path ""
					(reference "#PWR0308")
					(unit 1)
				)
			)
		)
	)
	(symbol
		(lib_id "antmicropower:VDC")
		(at 105.41 276.86 0)
		(unit 1)
		(exclude_from_sim no)
		(in_bom yes)
		(on_board yes)
		(dnp no)
		(property "Reference" "#PWR021"
			(at 105.41 279.4 0)
			(effects
				(font
					(size 1.27 1.27)
				)
				(hide yes)
			)
		)
		(property "Value" "VDC"
			(at 105.41 273.05 0)
			(effects
				(font
					(size 1.27 1.27)
				)
			)
		)
		(property "Footprint" ""
			(at 105.41 276.86 0)
			(effects
				(font
					(size 1.27 1.27)
				)
				(hide yes)
			)
		)
		(property "Datasheet" ""
			(at 105.41 276.86 0)
			(effects
				(font
					(size 1.27 1.27)
				)
				(hide yes)
			)
		)
		(property "Description" ""
			(at 105.41 276.86 0)
			(effects
				(font
					(size 1.27 1.27)
				)
			)
		)
		(pin "1"
		)
		(instances
			(project "sodimm-ddr5-tester"
				(path ""
					(reference "#PWR021")
					(unit 1)
				)
			)
		)
	)
	(symbol
		(lib_id "antmicroResistors0402:R_10k_0402")
		(at 360.045 100.965 0)
		(unit 1)
		(exclude_from_sim no)
		(in_bom yes)
		(on_board yes)
		(dnp no)
		(property "Reference" "R182"
			(at 362.585 102.87 0)
			(effects
				(font
					(size 1.27 1.27)
				)
			)
		)
		(property "Value" "R_10k_0402"
			(at 380.365 113.665 0)
			(effects
				(font
					(size 1.27 1.27)
					(thickness 0.15)
				)
				(justify left bottom)
				(hide yes)
			)
		)
		(property "Footprint" "antmicro-footprints:R_0402_1005Metric"
			(at 380.365 116.205 0)
			(effects
				(font
					(size 1.27 1.27)
					(thickness 0.15)
				)
				(justify left bottom)
				(hide yes)
			)
		)
		(property "Datasheet" "https://www.bourns.com/docs/product-datasheets/cr.pdf"
			(at 380.365 118.745 0)
			(effects
				(font
					(size 1.27 1.27)
					(thickness 0.15)
				)
				(justify left bottom)
				(hide yes)
			)
		)
		(property "Description" ""
			(at 360.045 100.965 0)
			(effects
				(font
					(size 1.27 1.27)
				)
			)
		)
		(property "Manufacturer" "Bourns"
			(at 380.365 123.825 0)
			(effects
				(font
					(size 1.27 1.27)
					(thickness 0.15)
				)
				(justify left bottom)
				(hide yes)
			)
		)
		(property "MPN" "CR0402-FX-1002GLF"
			(at 380.365 121.285 0)
			(effects
				(font
					(size 1.27 1.27)
					(thickness 0.15)
				)
				(justify left bottom)
				(hide yes)
			)
		)
		(property "Val" "10k"
			(at 362.585 104.775 0)
			(effects
				(font
					(size 1.27 1.27)
					(thickness 0.15)
				)
			)
		)
		(property "License" "Apache-2.0"
			(at 380.365 126.365 0)
			(effects
				(font
					(size 1.27 1.27)
					(thickness 0.15)
				)
				(justify left bottom)
				(hide yes)
			)
		)
		(property "Author" "Antmicro"
			(at 380.365 128.905 0)
			(effects
				(font
					(size 1.27 1.27)
					(thickness 0.15)
				)
				(justify left bottom)
				(hide yes)
			)
		)
		(property "Tolerance" "1%"
			(at 380.365 111.125 0)
			(effects
				(font
					(size 1.27 1.27)
				)
				(justify left bottom)
				(hide yes)
			)
		)
		(pin "1"
		)
		(pin "2"
		)
		(instances
			(project "sodimm-ddr5-tester"
				(path ""
					(reference "R182")
					(unit 1)
				)
			)
		)
	)
	(symbol
		(lib_id "antmicropower:+3V3_AON")
		(at 146.685 36.195 0)
		(unit 1)
		(exclude_from_sim no)
		(in_bom yes)
		(on_board yes)
		(dnp no)
		(property "Reference" "#PWR0314"
			(at 146.685 40.005 0)
			(effects
				(font
					(size 1.27 1.27)
				)
				(hide yes)
			)
		)
		(property "Value" "+3V3_AON"
			(at 146.685 32.385 0)
			(effects
				(font
					(size 1.27 1.27)
				)
			)
		)
		(property "Footprint" ""
			(at 146.685 36.195 0)
			(effects
				(font
					(size 1.27 1.27)
				)
				(hide yes)
			)
		)
		(property "Datasheet" ""
			(at 146.685 36.195 0)
			(effects
				(font
					(size 1.27 1.27)
				)
				(hide yes)
			)
		)
		(property "Description" ""
			(at 146.685 36.195 0)
			(effects
				(font
					(size 1.27 1.27)
				)
			)
		)
		(pin "1"
		)
		(instances
			(project "sodimm-ddr5-tester"
				(path ""
					(reference "#PWR0314")
					(unit 1)
				)
			)
		)
	)
	(symbol
		(lib_id "antmicropower:GND")
		(at 215.9 187.325 0)
		(unit 1)
		(exclude_from_sim no)
		(in_bom yes)
		(on_board yes)
		(dnp no)
		(fields_autoplaced yes)
		(property "Reference" "#PWR0291"
			(at 215.9 193.675 0)
			(effects
				(font
					(size 1.27 1.27)
				)
				(hide yes)
			)
		)
		(property "Value" "GND"
			(at 218.44 188.595 0)
			(effects
				(font
					(size 1.27 1.27)
					(thickness 0.15)
				)
				(justify left)
			)
		)
		(property "Footprint" ""
			(at 224.79 194.945 0)
			(effects
				(font
					(size 1.27 1.27)
					(thickness 0.15)
				)
				(justify left bottom)
				(hide yes)
			)
		)
		(property "Datasheet" ""
			(at 224.79 200.025 0)
			(effects
				(font
					(size 1.27 1.27)
					(thickness 0.15)
				)
				(justify left bottom)
				(hide yes)
			)
		)
		(property "Description" ""
			(at 224.79 202.565 0)
			(effects
				(font
					(size 1.27 1.27)
				)
				(justify left bottom)
				(hide yes)
			)
		)
		(property "Author" "Antmicro"
			(at 224.79 194.945 0)
			(effects
				(font
					(size 1.27 1.27)
					(thickness 0.15)
				)
				(justify left bottom)
				(hide yes)
			)
		)
		(property "License" "Apache-2.0"
			(at 224.79 197.485 0)
			(effects
				(font
					(size 1.27 1.27)
					(thickness 0.15)
				)
				(justify left bottom)
				(hide yes)
			)
		)
		(pin "1"
		)
		(instances
			(project "sodimm-ddr5-tester"
				(path ""
					(reference "#PWR0291")
					(unit 1)
				)
			)
		)
	)
	(symbol
		(lib_id "antmicroShuntsJumpers:Net-Tie_P0.127mm")
		(at 118.745 201.93 90)
		(unit 1)
		(exclude_from_sim no)
		(in_bom no)
		(on_board yes)
		(dnp no)
		(fields_autoplaced yes)
		(property "Reference" "NT11"
			(at 117.475 201.93 0)
			(effects
				(font
					(size 1.27 1.27)
				)
				(hide yes)
			)
		)
		(property "Value" "Net-Tie_P0.127mm"
			(at 126.365 180.34 0)
			(effects
				(font
					(size 1.27 1.27)
					(thickness 0.15)
				)
				(justify left bottom)
				(hide yes)
			)
		)
		(property "Footprint" "antmicro-footprints:NetTie-2_SMD_Pad0.127mm"
			(at 131.445 180.34 0)
			(effects
				(font
					(size 1.27 1.27)
					(thickness 0.15)
				)
				(justify left bottom)
				(hide yes)
			)
		)
		(property "Datasheet" ""
			(at 133.985 180.34 0)
			(effects
				(font
					(size 1.27 1.27)
					(thickness 0.15)
				)
				(justify left bottom)
				(hide yes)
			)
		)
		(property "Description" ""
			(at 118.745 201.93 0)
			(effects
				(font
					(size 1.27 1.27)
				)
			)
		)
		(property "MPN" ""
			(at 128.905 180.34 0)
			(effects
				(font
					(size 1.27 1.27)
					(thickness 0.15)
				)
				(justify left bottom)
			)
		)
		(property "Manufacturer" ""
			(at 136.525 180.34 0)
			(effects
				(font
					(size 1.27 1.27)
					(thickness 0.15)
				)
				(justify left bottom)
				(hide yes)
			)
		)
		(property "Author" "Antmicro"
			(at 139.065 180.34 0)
			(effects
				(font
					(size 1.27 1.27)
					(thickness 0.15)
				)
				(justify left bottom)
				(hide yes)
			)
		)
		(property "License" "Apache-2.0"
			(at 141.605 180.34 0)
			(effects
				(font
					(size 1.27 1.27)
					(thickness 0.15)
				)
				(justify left bottom)
				(hide yes)
			)
		)
		(pin "1"
		)
		(pin "2"
		)
		(instances
			(project "sodimm-ddr5-tester"
				(path ""
					(reference "NT11")
					(unit 1)
				)
			)
		)
	)
	(symbol
		(lib_id "antmicroShuntsJumpers:Net-Tie_P0.127mm")
		(at 118.745 184.15 90)
		(unit 1)
		(exclude_from_sim no)
		(in_bom no)
		(on_board yes)
		(dnp no)
		(fields_autoplaced yes)
		(property "Reference" "NT10"
			(at 117.475 184.15 0)
			(effects
				(font
					(size 1.27 1.27)
				)
				(hide yes)
			)
		)
		(property "Value" "Net-Tie_P0.127mm"
			(at 126.365 162.56 0)
			(effects
				(font
					(size 1.27 1.27)
					(thickness 0.15)
				)
				(justify left bottom)
				(hide yes)
			)
		)
		(property "Footprint" "antmicro-footprints:NetTie-2_SMD_Pad0.127mm"
			(at 131.445 162.56 0)
			(effects
				(font
					(size 1.27 1.27)
					(thickness 0.15)
				)
				(justify left bottom)
				(hide yes)
			)
		)
		(property "Datasheet" ""
			(at 133.985 162.56 0)
			(effects
				(font
					(size 1.27 1.27)
					(thickness 0.15)
				)
				(justify left bottom)
				(hide yes)
			)
		)
		(property "Description" ""
			(at 118.745 184.15 0)
			(effects
				(font
					(size 1.27 1.27)
				)
			)
		)
		(property "MPN" ""
			(at 128.905 162.56 0)
			(effects
				(font
					(size 1.27 1.27)
					(thickness 0.15)
				)
				(justify left bottom)
			)
		)
		(property "Manufacturer" ""
			(at 136.525 162.56 0)
			(effects
				(font
					(size 1.27 1.27)
					(thickness 0.15)
				)
				(justify left bottom)
				(hide yes)
			)
		)
		(property "Author" "Antmicro"
			(at 139.065 162.56 0)
			(effects
				(font
					(size 1.27 1.27)
					(thickness 0.15)
				)
				(justify left bottom)
				(hide yes)
			)
		)
		(property "License" "Apache-2.0"
			(at 141.605 162.56 0)
			(effects
				(font
					(size 1.27 1.27)
					(thickness 0.15)
				)
				(justify left bottom)
				(hide yes)
			)
		)
		(pin "1"
		)
		(pin "2"
		)
		(instances
			(project "sodimm-ddr5-tester"
				(path ""
					(reference "NT10")
					(unit 1)
				)
			)
		)
	)
	(symbol
		(lib_id "antmicroResistors0402:R_47k_0402")
		(at 204.47 102.87 90)
		(unit 1)
		(exclude_from_sim no)
		(in_bom yes)
		(on_board yes)
		(dnp no)
		(fields_autoplaced yes)
		(property "Reference" "R139"
			(at 202.819 99.4994 90)
			(effects
				(font
					(size 1.27 1.27)
				)
				(justify left)
			)
		)
		(property "Value" "R_47k_0402"
			(at 217.17 82.55 0)
			(effects
				(font
					(size 1.27 1.27)
					(thickness 0.15)
				)
				(justify left bottom)
				(hide yes)
			)
		)
		(property "Footprint" "antmicro-footprints:R_0402_1005Metric"
			(at 219.71 82.55 0)
			(effects
				(font
					(size 1.27 1.27)
					(thickness 0.15)
				)
				(justify left bottom)
				(hide yes)
			)
		)
		(property "Datasheet" "https://www.bourns.com/docs/product-datasheets/cr.pdf"
			(at 222.25 82.55 0)
			(effects
				(font
					(size 1.27 1.27)
					(thickness 0.15)
				)
				(justify left bottom)
				(hide yes)
			)
		)
		(property "Description" ""
			(at 204.47 102.87 0)
			(effects
				(font
					(size 1.27 1.27)
				)
			)
		)
		(property "Manufacturer" "Bourns"
			(at 227.33 82.55 0)
			(effects
				(font
					(size 1.27 1.27)
					(thickness 0.15)
				)
				(justify left bottom)
				(hide yes)
			)
		)
		(property "MPN" "CR0402-FX-4702GLF"
			(at 224.79 82.55 0)
			(effects
				(font
					(size 1.27 1.27)
					(thickness 0.15)
				)
				(justify left bottom)
				(hide yes)
			)
		)
		(property "Val" "47k"
			(at 202.819 102.0297 90)
			(effects
				(font
					(size 1.27 1.27)
					(thickness 0.15)
				)
				(justify left)
			)
		)
		(property "License" "Apache-2.0"
			(at 229.87 82.55 0)
			(effects
				(font
					(size 1.27 1.27)
					(thickness 0.15)
				)
				(justify left bottom)
				(hide yes)
			)
		)
		(property "Author" "Antmicro"
			(at 232.41 82.55 0)
			(effects
				(font
					(size 1.27 1.27)
					(thickness 0.15)
				)
				(justify left bottom)
				(hide yes)
			)
		)
		(property "Tolerance" "1%"
			(at 214.63 82.55 0)
			(effects
				(font
					(size 1.27 1.27)
				)
				(justify left bottom)
				(hide yes)
			)
		)
		(pin "1"
		)
		(pin "2"
		)
		(instances
			(project "sodimm-ddr5-tester"
				(path ""
					(reference "R139")
					(unit 1)
				)
			)
		)
	)
	(symbol
		(lib_id "antmicropower:GND")
		(at 318.77 59.69 0)
		(unit 1)
		(exclude_from_sim no)
		(in_bom yes)
		(on_board yes)
		(dnp no)
		(fields_autoplaced yes)
		(property "Reference" "#PWR0377"
			(at 318.77 66.04 0)
			(effects
				(font
					(size 1.27 1.27)
				)
				(hide yes)
			)
		)
		(property "Value" "GND"
			(at 321.31 60.96 0)
			(effects
				(font
					(size 1.27 1.27)
					(thickness 0.15)
				)
				(justify left)
			)
		)
		(property "Footprint" ""
			(at 327.66 67.31 0)
			(effects
				(font
					(size 1.27 1.27)
					(thickness 0.15)
				)
				(justify left bottom)
				(hide yes)
			)
		)
		(property "Datasheet" ""
			(at 327.66 72.39 0)
			(effects
				(font
					(size 1.27 1.27)
					(thickness 0.15)
				)
				(justify left bottom)
				(hide yes)
			)
		)
		(property "Description" ""
			(at 327.66 74.93 0)
			(effects
				(font
					(size 1.27 1.27)
				)
				(justify left bottom)
				(hide yes)
			)
		)
		(property "Author" "Antmicro"
			(at 327.66 67.31 0)
			(effects
				(font
					(size 1.27 1.27)
					(thickness 0.15)
				)
				(justify left bottom)
				(hide yes)
			)
		)
		(property "License" "Apache-2.0"
			(at 327.66 69.85 0)
			(effects
				(font
					(size 1.27 1.27)
					(thickness 0.15)
				)
				(justify left bottom)
				(hide yes)
			)
		)
		(pin "1"
		)
		(instances
			(project "sodimm-ddr5-tester"
				(path ""
					(reference "#PWR0377")
					(unit 1)
				)
			)
		)
	)
	(symbol
		(lib_id "antmicroTestPoints:TP_1206_SMD_RCW-0C")
		(at 130.81 197.485 0)
		(unit 1)
		(exclude_from_sim no)
		(in_bom yes)
		(on_board yes)
		(dnp no)
		(property "Reference" "TP14"
			(at 135.382 196.6544 0)
			(effects
				(font
					(size 1.27 1.27)
					(thickness 0.15)
				)
				(justify left)
			)
		)
		(property "Value" "TP_1206_SMD_RCW-0C"
			(at 128.905 199.39 0)
			(effects
				(font
					(size 1.27 1.27)
					(thickness 0.15)
				)
				(justify left)
			)
		)
		(property "Footprint" "antmicro-footprints:TP_1206_SMD_RCW-0C"
			(at 148.59 207.645 0)
			(effects
				(font
					(size 1.27 1.27)
					(thickness 0.15)
				)
				(justify left bottom)
				(hide yes)
			)
		)
		(property "Datasheet" "https://www.te.com/commerce/DocumentDelivery/DDEController?Action=srchrtrv&DocNm=1773266&DocType=DS&DocLang=English"
			(at 148.59 210.185 0)
			(effects
				(font
					(size 1.27 1.27)
					(thickness 0.15)
				)
				(justify left bottom)
				(hide yes)
			)
		)
		(property "Description" ""
			(at 130.81 197.485 0)
			(effects
				(font
					(size 1.27 1.27)
				)
			)
		)
		(property "MPN" "RCW-0C"
			(at 148.59 212.725 0)
			(effects
				(font
					(size 1.27 1.27)
					(thickness 0.15)
				)
				(justify left bottom)
				(hide yes)
			)
		)
		(property "Manufacturer" "TE Connectivity"
			(at 148.59 215.265 0)
			(effects
				(font
					(size 1.27 1.27)
					(thickness 0.15)
				)
				(justify left bottom)
				(hide yes)
			)
		)
		(property "Author" "Antmicro"
			(at 148.59 217.805 0)
			(effects
				(font
					(size 1.27 1.27)
					(thickness 0.15)
				)
				(justify left bottom)
				(hide yes)
			)
		)
		(property "License" "Apache-2.0"
			(at 148.59 220.345 0)
			(effects
				(font
					(size 1.27 1.27)
					(thickness 0.15)
				)
				(justify left bottom)
				(hide yes)
			)
		)
		(pin "1"
		)
		(instances
			(project "sodimm-ddr5-tester"
				(path ""
					(reference "TP14")
					(unit 1)
				)
			)
		)
	)
	(symbol
		(lib_id "antmicroCapacitors0402:C_100n_0402")
		(at 163.195 262.255 270)
		(mirror x)
		(unit 1)
		(exclude_from_sim no)
		(in_bom yes)
		(on_board yes)
		(dnp no)
		(property "Reference" "C216"
			(at 161.925 257.81 90)
			(effects
				(font
					(size 1.27 1.27)
				)
				(justify right)
			)
		)
		(property "Value" "C_100n_0402"
			(at 153.035 241.935 0)
			(effects
				(font
					(size 1.27 1.27)
					(thickness 0.15)
				)
				(justify left bottom)
				(hide yes)
			)
		)
		(property "Footprint" "antmicro-footprints:C_0402_1005Metric"
			(at 150.495 241.935 0)
			(effects
				(font
					(size 1.27 1.27)
					(thickness 0.15)
				)
				(justify left bottom)
				(hide yes)
			)
		)
		(property "Datasheet" "https://www.murata.com/products/productdetail?partno=GRM155R61H104KE14%23"
			(at 147.955 241.935 0)
			(effects
				(font
					(size 1.27 1.27)
					(thickness 0.15)
				)
				(justify left bottom)
				(hide yes)
			)
		)
		(property "Description" ""
			(at 163.195 262.255 0)
			(effects
				(font
					(size 1.27 1.27)
				)
			)
		)
		(property "Manufacturer" "Murata"
			(at 142.875 241.935 0)
			(effects
				(font
					(size 1.27 1.27)
					(thickness 0.15)
				)
				(justify left bottom)
				(hide yes)
			)
		)
		(property "MPN" "GRM155R61H104KE14D"
			(at 145.415 241.935 0)
			(effects
				(font
					(size 1.27 1.27)
					(thickness 0.15)
				)
				(justify left bottom)
				(hide yes)
			)
		)
		(property "Val" "100n"
			(at 161.925 261.62 90)
			(effects
				(font
					(size 1.27 1.27)
					(thickness 0.15)
				)
				(justify right)
			)
		)
		(property "License" "Apache-2.0"
			(at 140.335 241.935 0)
			(effects
				(font
					(size 1.27 1.27)
					(thickness 0.15)
				)
				(justify left bottom)
				(hide yes)
			)
		)
		(property "Author" "Antmicro"
			(at 137.795 241.935 0)
			(effects
				(font
					(size 1.27 1.27)
					(thickness 0.15)
				)
				(justify left bottom)
				(hide yes)
			)
		)
		(property "Voltage" "50V"
			(at 135.255 241.935 0)
			(effects
				(font
					(size 1.27 1.27)
				)
				(justify left bottom)
				(hide yes)
			)
		)
		(property "Dielectric" "X5R"
			(at 132.715 241.935 0)
			(effects
				(font
					(size 1.27 1.27)
				)
				(justify left bottom)
				(hide yes)
			)
		)
		(pin "1"
		)
		(pin "2"
		)
		(instances
			(project "sodimm-ddr5-tester"
				(path ""
					(reference "C216")
					(unit 1)
				)
			)
		)
	)
	(symbol
		(lib_id "antmicropower:GND")
		(at 196.215 72.39 0)
		(unit 1)
		(exclude_from_sim no)
		(in_bom yes)
		(on_board yes)
		(dnp no)
		(fields_autoplaced yes)
		(property "Reference" "#PWR0318"
			(at 196.215 78.74 0)
			(effects
				(font
					(size 1.27 1.27)
				)
				(hide yes)
			)
		)
		(property "Value" "GND"
			(at 198.12 73.66 0)
			(effects
				(font
					(size 1.27 1.27)
					(thickness 0.15)
				)
				(justify left)
			)
		)
		(property "Footprint" ""
			(at 205.105 80.01 0)
			(effects
				(font
					(size 1.27 1.27)
					(thickness 0.15)
				)
				(justify left bottom)
				(hide yes)
			)
		)
		(property "Datasheet" ""
			(at 205.105 85.09 0)
			(effects
				(font
					(size 1.27 1.27)
					(thickness 0.15)
				)
				(justify left bottom)
				(hide yes)
			)
		)
		(property "Description" ""
			(at 205.105 87.63 0)
			(effects
				(font
					(size 1.27 1.27)
				)
				(justify left bottom)
				(hide yes)
			)
		)
		(property "Author" "Antmicro"
			(at 205.105 80.01 0)
			(effects
				(font
					(size 1.27 1.27)
					(thickness 0.15)
				)
				(justify left bottom)
				(hide yes)
			)
		)
		(property "License" "Apache-2.0"
			(at 205.105 82.55 0)
			(effects
				(font
					(size 1.27 1.27)
					(thickness 0.15)
				)
				(justify left bottom)
				(hide yes)
			)
		)
		(pin "1"
		)
		(instances
			(project "sodimm-ddr5-tester"
				(path ""
					(reference "#PWR0318")
					(unit 1)
				)
			)
		)
	)
	(symbol
		(lib_id "antmicropower:GND")
		(at 171.45 72.39 0)
		(unit 1)
		(exclude_from_sim no)
		(in_bom yes)
		(on_board yes)
		(dnp no)
		(fields_autoplaced yes)
		(property "Reference" "#PWR0341"
			(at 171.45 78.74 0)
			(effects
				(font
					(size 1.27 1.27)
				)
				(hide yes)
			)
		)
		(property "Value" "GND"
			(at 173.99 73.66 0)
			(effects
				(font
					(size 1.27 1.27)
					(thickness 0.15)
				)
				(justify left)
			)
		)
		(property "Footprint" ""
			(at 180.34 80.01 0)
			(effects
				(font
					(size 1.27 1.27)
					(thickness 0.15)
				)
				(justify left bottom)
				(hide yes)
			)
		)
		(property "Datasheet" ""
			(at 180.34 85.09 0)
			(effects
				(font
					(size 1.27 1.27)
					(thickness 0.15)
				)
				(justify left bottom)
				(hide yes)
			)
		)
		(property "Description" ""
			(at 180.34 87.63 0)
			(effects
				(font
					(size 1.27 1.27)
				)
				(justify left bottom)
				(hide yes)
			)
		)
		(property "Author" "Antmicro"
			(at 180.34 80.01 0)
			(effects
				(font
					(size 1.27 1.27)
					(thickness 0.15)
				)
				(justify left bottom)
				(hide yes)
			)
		)
		(property "License" "Apache-2.0"
			(at 180.34 82.55 0)
			(effects
				(font
					(size 1.27 1.27)
					(thickness 0.15)
				)
				(justify left bottom)
				(hide yes)
			)
		)
		(pin "1"
		)
		(instances
			(project "sodimm-ddr5-tester"
				(path ""
					(reference "#PWR0341")
					(unit 1)
				)
			)
		)
	)
	(symbol
		(lib_id "antmicropower:GND")
		(at 114.935 118.11 0)
		(unit 1)
		(exclude_from_sim no)
		(in_bom yes)
		(on_board yes)
		(dnp no)
		(fields_autoplaced yes)
		(property "Reference" "#PWR0393"
			(at 114.935 124.46 0)
			(effects
				(font
					(size 1.27 1.27)
				)
				(hide yes)
			)
		)
		(property "Value" "GND"
			(at 116.84 119.38 0)
			(effects
				(font
					(size 1.27 1.27)
					(thickness 0.15)
				)
				(justify left)
			)
		)
		(property "Footprint" ""
			(at 123.825 125.73 0)
			(effects
				(font
					(size 1.27 1.27)
					(thickness 0.15)
				)
				(justify left bottom)
				(hide yes)
			)
		)
		(property "Datasheet" ""
			(at 123.825 130.81 0)
			(effects
				(font
					(size 1.27 1.27)
					(thickness 0.15)
				)
				(justify left bottom)
				(hide yes)
			)
		)
		(property "Description" ""
			(at 123.825 133.35 0)
			(effects
				(font
					(size 1.27 1.27)
				)
				(justify left bottom)
				(hide yes)
			)
		)
		(property "Author" "Antmicro"
			(at 123.825 125.73 0)
			(effects
				(font
					(size 1.27 1.27)
					(thickness 0.15)
				)
				(justify left bottom)
				(hide yes)
			)
		)
		(property "License" "Apache-2.0"
			(at 123.825 128.27 0)
			(effects
				(font
					(size 1.27 1.27)
					(thickness 0.15)
				)
				(justify left bottom)
				(hide yes)
			)
		)
		(pin "1"
		)
		(instances
			(project "sodimm-ddr5-tester"
				(path ""
					(reference "#PWR0393")
					(unit 1)
				)
			)
		)
	)
	(symbol
		(lib_id "antmicroResistors0402:R_205k_0402")
		(at 123.825 134.62 90)
		(unit 1)
		(exclude_from_sim no)
		(in_bom yes)
		(on_board yes)
		(dnp no)
		(fields_autoplaced yes)
		(property "Reference" "R186"
			(at 125.73 130.8099 90)
			(effects
				(font
					(size 1.27 1.27)
				)
				(justify right)
			)
		)
		(property "Value" "R_205k_0402"
			(at 136.525 114.3 0)
			(effects
				(font
					(size 1.27 1.27)
					(thickness 0.15)
				)
				(justify left bottom)
				(hide yes)
			)
		)
		(property "Footprint" "antmicro-footprints:R_0402_1005Metric"
			(at 139.065 114.3 0)
			(effects
				(font
					(size 1.27 1.27)
					(thickness 0.15)
				)
				(justify left bottom)
				(hide yes)
			)
		)
		(property "Datasheet" "https://www.bourns.com/docs/product-datasheets/cr.pdf"
			(at 141.605 114.3 0)
			(effects
				(font
					(size 1.27 1.27)
					(thickness 0.15)
				)
				(justify left bottom)
				(hide yes)
			)
		)
		(property "Description" ""
			(at 123.825 134.62 0)
			(effects
				(font
					(size 1.27 1.27)
				)
			)
		)
		(property "Manufacturer" "Bourns"
			(at 146.685 114.3 0)
			(effects
				(font
					(size 1.27 1.27)
					(thickness 0.15)
				)
				(justify left bottom)
				(hide yes)
			)
		)
		(property "MPN" "CR0402-FX-2053GLF"
			(at 144.145 114.3 0)
			(effects
				(font
					(size 1.27 1.27)
					(thickness 0.15)
				)
				(justify left bottom)
				(hide yes)
			)
		)
		(property "Val" "205k"
			(at 125.73 133.3499 90)
			(effects
				(font
					(size 1.27 1.27)
					(thickness 0.15)
				)
				(justify right)
			)
		)
		(property "License" "Apache-2.0"
			(at 149.225 114.3 0)
			(effects
				(font
					(size 1.27 1.27)
					(thickness 0.15)
				)
				(justify left bottom)
				(hide yes)
			)
		)
		(property "Author" "Antmicro"
			(at 151.765 114.3 0)
			(effects
				(font
					(size 1.27 1.27)
					(thickness 0.15)
				)
				(justify left bottom)
				(hide yes)
			)
		)
		(property "Tolerance" "1%"
			(at 133.985 114.3 0)
			(effects
				(font
					(size 1.27 1.27)
				)
				(justify left bottom)
				(hide yes)
			)
		)
		(pin "1"
		)
		(pin "2"
		)
		(instances
			(project "sodimm-ddr5-tester"
				(path ""
					(reference "R186")
					(unit 1)
				)
			)
		)
	)
	(symbol
		(lib_id "antmicropower:+3V3")
		(at 109.22 247.65 0)
		(unit 1)
		(exclude_from_sim no)
		(in_bom yes)
		(on_board yes)
		(dnp no)
		(fields_autoplaced yes)
		(property "Reference" "#PWR0372"
			(at 109.22 251.46 0)
			(effects
				(font
					(size 1.27 1.27)
				)
				(hide yes)
			)
		)
		(property "Value" "+3V3"
			(at 106.045 245.11 0)
			(effects
				(font
					(size 1.27 1.27)
					(thickness 0.15)
				)
				(justify left bottom)
			)
		)
		(property "Footprint" ""
			(at 124.46 255.27 0)
			(effects
				(font
					(size 1.27 1.27)
					(thickness 0.15)
				)
				(justify left bottom)
				(hide yes)
			)
		)
		(property "Datasheet" ""
			(at 124.46 257.81 0)
			(effects
				(font
					(size 1.27 1.27)
					(thickness 0.15)
				)
				(justify left bottom)
				(hide yes)
			)
		)
		(property "Description" ""
			(at 109.22 247.65 0)
			(effects
				(font
					(size 1.27 1.27)
				)
			)
		)
		(property "Author" "Antmicro"
			(at 124.46 250.19 0)
			(effects
				(font
					(size 1.27 1.27)
					(thickness 0.15)
				)
				(justify left bottom)
				(hide yes)
			)
		)
		(property "License" "Apache-2.0"
			(at 124.46 252.73 0)
			(effects
				(font
					(size 1.27 1.27)
					(thickness 0.15)
				)
				(justify left bottom)
				(hide yes)
			)
		)
		(pin "1"
		)
		(instances
			(project "sodimm-ddr5-tester"
				(path ""
					(reference "#PWR0372")
					(unit 1)
				)
			)
		)
	)
	(symbol
		(lib_id "antmicropower:VDC")
		(at 111.125 36.195 0)
		(unit 1)
		(exclude_from_sim no)
		(in_bom yes)
		(on_board yes)
		(dnp no)
		(property "Reference" "#PWR0301"
			(at 111.125 38.735 0)
			(effects
				(font
					(size 1.27 1.27)
				)
				(hide yes)
			)
		)
		(property "Value" "VDC"
			(at 111.125 32.385 0)
			(effects
				(font
					(size 1.27 1.27)
				)
			)
		)
		(property "Footprint" ""
			(at 111.125 36.195 0)
			(effects
				(font
					(size 1.27 1.27)
				)
				(hide yes)
			)
		)
		(property "Datasheet" ""
			(at 111.125 36.195 0)
			(effects
				(font
					(size 1.27 1.27)
				)
				(hide yes)
			)
		)
		(property "Description" ""
			(at 111.125 36.195 0)
			(effects
				(font
					(size 1.27 1.27)
				)
			)
		)
		(pin "1"
		)
		(instances
			(project "sodimm-ddr5-tester"
				(path ""
					(reference "#PWR0301")
					(unit 1)
				)
			)
		)
	)
	(symbol
		(lib_id "antmicroShuntsJumpers:Net-Tie_P0.127mm")
		(at 313.055 201.93 90)
		(unit 1)
		(exclude_from_sim no)
		(in_bom no)
		(on_board yes)
		(dnp no)
		(fields_autoplaced yes)
		(property "Reference" "NT15"
			(at 311.785 201.93 0)
			(effects
				(font
					(size 1.27 1.27)
				)
				(hide yes)
			)
		)
		(property "Value" "Net-Tie_P0.127mm"
			(at 320.675 180.34 0)
			(effects
				(font
					(size 1.27 1.27)
					(thickness 0.15)
				)
				(justify left bottom)
				(hide yes)
			)
		)
		(property "Footprint" "antmicro-footprints:NetTie-2_SMD_Pad0.127mm"
			(at 325.755 180.34 0)
			(effects
				(font
					(size 1.27 1.27)
					(thickness 0.15)
				)
				(justify left bottom)
				(hide yes)
			)
		)
		(property "Datasheet" ""
			(at 328.295 180.34 0)
			(effects
				(font
					(size 1.27 1.27)
					(thickness 0.15)
				)
				(justify left bottom)
				(hide yes)
			)
		)
		(property "Description" ""
			(at 313.055 201.93 0)
			(effects
				(font
					(size 1.27 1.27)
				)
			)
		)
		(property "MPN" ""
			(at 323.215 180.34 0)
			(effects
				(font
					(size 1.27 1.27)
					(thickness 0.15)
				)
				(justify left bottom)
			)
		)
		(property "Manufacturer" ""
			(at 330.835 180.34 0)
			(effects
				(font
					(size 1.27 1.27)
					(thickness 0.15)
				)
				(justify left bottom)
				(hide yes)
			)
		)
		(property "Author" "Antmicro"
			(at 333.375 180.34 0)
			(effects
				(font
					(size 1.27 1.27)
					(thickness 0.15)
				)
				(justify left bottom)
				(hide yes)
			)
		)
		(property "License" "Apache-2.0"
			(at 335.915 180.34 0)
			(effects
				(font
					(size 1.27 1.27)
					(thickness 0.15)
				)
				(justify left bottom)
				(hide yes)
			)
		)
		(pin "1"
		)
		(pin "2"
		)
		(instances
			(project "sodimm-ddr5-tester"
				(path ""
					(reference "NT15")
					(unit 1)
				)
			)
		)
	)
	(symbol
		(lib_id "antmicropower:PWR_FLAG")
		(at 85.09 157.48 0)
		(unit 1)
		(exclude_from_sim no)
		(in_bom yes)
		(on_board yes)
		(dnp no)
		(fields_autoplaced yes)
		(property "Reference" "#FLG04"
			(at 85.09 155.575 0)
			(effects
				(font
					(size 1.27 1.27)
				)
				(hide yes)
			)
		)
		(property "Value" "PWR_FLAG"
			(at 85.09 153.67 0)
			(effects
				(font
					(size 1.27 1.27)
				)
			)
		)
		(property "Footprint" ""
			(at 85.09 157.48 0)
			(effects
				(font
					(size 1.27 1.27)
				)
				(hide yes)
			)
		)
		(property "Datasheet" ""
			(at 85.09 157.48 0)
			(effects
				(font
					(size 1.27 1.27)
				)
				(hide yes)
			)
		)
		(property "Description" ""
			(at 85.09 157.48 0)
			(effects
				(font
					(size 1.27 1.27)
				)
			)
		)
		(pin "1"
		)
		(instances
			(project "sodimm-ddr5-tester"
				(path ""
					(reference "#FLG04")
					(unit 1)
				)
			)
		)
	)
	(symbol
		(lib_id "antmicroTestPoints:TP_1mm_SMD")
		(at 160.02 278.13 270)
		(unit 1)
		(exclude_from_sim no)
		(in_bom yes)
		(on_board yes)
		(dnp no)
		(property "Reference" "TP33"
			(at 160.02 283.1028 90)
			(effects
				(font
					(size 1.27 1.27)
				)
			)
		)
		(property "Value" "TP_1mm_SMD"
			(at 152.4 293.37 0)
			(effects
				(font
					(size 1.27 1.27)
					(thickness 0.15)
				)
				(justify left bottom)
				(hide yes)
			)
		)
		(property "Footprint" "antmicro-footprints:TP_SMD_1mm"
			(at 149.86 293.37 0)
			(effects
				(font
					(size 1.27 1.27)
					(thickness 0.15)
				)
				(justify left bottom)
				(hide yes)
			)
		)
		(property "Datasheet" ""
			(at 147.32 293.37 0)
			(effects
				(font
					(size 1.27 1.27)
					(thickness 0.15)
				)
				(justify left bottom)
				(hide yes)
			)
		)
		(property "Description" ""
			(at 160.02 278.13 0)
			(effects
				(font
					(size 1.27 1.27)
				)
			)
		)
		(property "MPN" ""
			(at 160.02 278.13 0)
			(effects
				(font
					(size 1.27 1.27)
				)
				(hide yes)
			)
		)
		(property "Manufacturer" ""
			(at 160.02 278.13 0)
			(effects
				(font
					(size 1.27 1.27)
				)
				(hide yes)
			)
		)
		(property "Author" "Antmicro"
			(at 144.78 293.37 0)
			(effects
				(font
					(size 1.27 1.27)
					(thickness 0.15)
				)
				(justify left bottom)
				(hide yes)
			)
		)
		(property "License" "Apache-2.0"
			(at 142.24 293.37 0)
			(effects
				(font
					(size 1.27 1.27)
					(thickness 0.15)
				)
				(justify left bottom)
				(hide yes)
			)
		)
		(pin "1"
		)
		(instances
			(project "sodimm-ddr5-tester"
				(path ""
					(reference "TP33")
					(unit 1)
				)
			)
		)
	)
	(symbol
		(lib_id "antmicroResistors0603:R_0R_22.4A_0603")
		(at 125.73 102.235 0)
		(unit 1)
		(exclude_from_sim no)
		(in_bom yes)
		(on_board yes)
		(dnp no)
		(fields_autoplaced yes)
		(property "Reference" "R188"
			(at 128.27 95.1306 0)
			(effects
				(font
					(size 1.27 1.27)
				)
			)
		)
		(property "Value" "R_0R_22.4A_0603"
			(at 128.27 95.1373 0)
			(effects
				(font
					(size 1.27 1.27)
					(thickness 0.15)
				)
				(hide yes)
			)
		)
		(property "Footprint" "antmicro-footprints:R_0603_1608Metric"
			(at 148.59 114.935 0)
			(effects
				(font
					(size 1.27 1.27)
					(thickness 0.15)
				)
				(justify left bottom)
				(hide yes)
			)
		)
		(property "Datasheet" "https://fscdn.rohm.com/en/products/databook/datasheet/passive/resistor/chip_resistor/pmr-jpw-e.pdf"
			(at 148.59 117.475 0)
			(effects
				(font
					(size 1.27 1.27)
					(thickness 0.15)
				)
				(justify left bottom)
				(hide yes)
			)
		)
		(property "Description" ""
			(at 125.73 102.235 0)
			(effects
				(font
					(size 1.27 1.27)
				)
			)
		)
		(property "Manufacturer" "ROHM Semiconductor"
			(at 148.59 120.015 0)
			(effects
				(font
					(size 1.27 1.27)
					(thickness 0.15)
				)
				(justify left bottom)
				(hide yes)
			)
		)
		(property "MPN" "PMR03EZPJ000"
			(at 148.59 122.555 0)
			(effects
				(font
					(size 1.27 1.27)
					(thickness 0.15)
				)
				(justify left bottom)
				(hide yes)
			)
		)
		(property "Val" "0R"
			(at 128.27 97.6609 0)
			(effects
				(font
					(size 1.27 1.27)
					(thickness 0.15)
				)
			)
		)
		(property "Author" "Antmicro"
			(at 148.59 125.095 0)
			(effects
				(font
					(size 1.27 1.27)
					(thickness 0.15)
				)
				(justify left bottom)
				(hide yes)
			)
		)
		(property "License" "Apache-2.0"
			(at 148.59 127.635 0)
			(effects
				(font
					(size 1.27 1.27)
					(thickness 0.15)
				)
				(justify left bottom)
				(hide yes)
			)
		)
		(property "Max. Curr." "22.4A"
			(at 128.27 100.1846 0)
			(effects
				(font
					(size 1.27 1.27)
					(thickness 0.15)
				)
			)
		)
		(pin "1"
		)
		(pin "2"
		)
		(instances
			(project "sodimm-ddr5-tester"
				(path ""
					(reference "R188")
					(unit 1)
				)
			)
		)
	)
	(symbol
		(lib_id "antmicroCapacitors0603:C_22u_0603")
		(at 78.105 165.735 90)
		(unit 1)
		(exclude_from_sim no)
		(in_bom yes)
		(on_board yes)
		(dnp no)
		(property "Reference" "C182"
			(at 78.74 161.29 90)
			(effects
				(font
					(size 1.27 1.27)
				)
				(justify right)
			)
		)
		(property "Value" "C_22u_0603"
			(at 88.265 145.415 0)
			(effects
				(font
					(size 1.27 1.27)
					(thickness 0.15)
				)
				(justify left bottom)
				(hide yes)
			)
		)
		(property "Footprint" "antmicro-footprints:C_0603_1608Metric"
			(at 90.805 145.415 0)
			(effects
				(font
					(size 1.27 1.27)
					(thickness 0.15)
				)
				(justify left bottom)
				(hide yes)
			)
		)
		(property "Datasheet" "https://www.murata.com/products/productdetail?partno=GRM188R60J226MEA0%23"
			(at 93.345 145.415 0)
			(effects
				(font
					(size 1.27 1.27)
					(thickness 0.15)
				)
				(justify left bottom)
				(hide yes)
			)
		)
		(property "Description" ""
			(at 78.105 165.735 0)
			(effects
				(font
					(size 1.27 1.27)
				)
			)
		)
		(property "Manufacturer" "Murata"
			(at 98.425 145.415 0)
			(effects
				(font
					(size 1.27 1.27)
					(thickness 0.15)
				)
				(justify left bottom)
				(hide yes)
			)
		)
		(property "MPN" "GRM188R60J226MEA0D"
			(at 95.885 145.415 0)
			(effects
				(font
					(size 1.27 1.27)
					(thickness 0.15)
				)
				(justify left bottom)
				(hide yes)
			)
		)
		(property "Val" "22u"
			(at 78.74 165.1 90)
			(effects
				(font
					(size 1.27 1.27)
					(thickness 0.15)
				)
				(justify right)
			)
		)
		(property "License" "Apache-2.0"
			(at 100.965 145.415 0)
			(effects
				(font
					(size 1.27 1.27)
					(thickness 0.15)
				)
				(justify left bottom)
				(hide yes)
			)
		)
		(property "Author" "Antmicro"
			(at 103.505 145.415 0)
			(effects
				(font
					(size 1.27 1.27)
					(thickness 0.15)
				)
				(justify left bottom)
				(hide yes)
			)
		)
		(property "Voltage" ""
			(at 106.045 145.415 0)
			(effects
				(font
					(size 1.27 1.27)
				)
				(justify left bottom)
				(hide yes)
			)
		)
		(property "Dielectric" ""
			(at 108.585 145.415 0)
			(effects
				(font
					(size 1.27 1.27)
				)
				(justify left bottom)
				(hide yes)
			)
		)
		(pin "1"
		)
		(pin "2"
		)
		(instances
			(project "sodimm-ddr5-tester"
				(path ""
					(reference "C182")
					(unit 1)
				)
			)
		)
	)
	(symbol
		(lib_id "antmicroCapacitors0402:C_1u_0402")
		(at 22.86 254.635 90)
		(unit 1)
		(exclude_from_sim no)
		(in_bom yes)
		(on_board yes)
		(dnp no)
		(property "Reference" "C206"
			(at 23.495 250.19 90)
			(effects
				(font
					(size 1.27 1.27)
				)
				(justify right)
			)
		)
		(property "Value" "C_1u_0402"
			(at 26.67 254.635 0)
			(effects
				(font
					(size 1.27 1.27)
				)
				(hide yes)
			)
		)
		(property "Footprint" "antmicro-footprints:C_0402_1005Metric"
			(at 35.56 234.315 0)
			(effects
				(font
					(size 1.27 1.27)
					(thickness 0.15)
				)
				(justify left bottom)
				(hide yes)
			)
		)
		(property "Datasheet" "https://product.tdk.com/en/search/capacitor/ceramic/mlcc/info?part_no=C1005X6S1A105K050BC"
			(at 38.1 234.315 0)
			(effects
				(font
					(size 1.27 1.27)
					(thickness 0.15)
				)
				(justify left bottom)
				(hide yes)
			)
		)
		(property "Description" ""
			(at 22.86 254.635 0)
			(effects
				(font
					(size 1.27 1.27)
				)
			)
		)
		(property "Manufacturer" "TDK"
			(at 43.18 234.315 0)
			(effects
				(font
					(size 1.27 1.27)
					(thickness 0.15)
				)
				(justify left bottom)
				(hide yes)
			)
		)
		(property "MPN" "C1005X6S1A105K050BC"
			(at 40.64 234.315 0)
			(effects
				(font
					(size 1.27 1.27)
					(thickness 0.15)
				)
				(justify left bottom)
				(hide yes)
			)
		)
		(property "Val" "1u"
			(at 23.495 254 90)
			(effects
				(font
					(size 1.27 1.27)
					(thickness 0.15)
				)
				(justify right)
			)
		)
		(property "License" "Apache-2.0"
			(at 45.72 234.315 0)
			(effects
				(font
					(size 1.27 1.27)
					(thickness 0.15)
				)
				(justify left bottom)
				(hide yes)
			)
		)
		(property "Author" "Antmicro"
			(at 48.26 234.315 0)
			(effects
				(font
					(size 1.27 1.27)
					(thickness 0.15)
				)
				(justify left bottom)
				(hide yes)
			)
		)
		(property "Voltage" ""
			(at 50.8 234.315 0)
			(effects
				(font
					(size 1.27 1.27)
				)
				(justify left bottom)
				(hide yes)
			)
		)
		(property "Dielectric" ""
			(at 53.34 234.315 0)
			(effects
				(font
					(size 1.27 1.27)
				)
				(justify left bottom)
				(hide yes)
			)
		)
		(pin "1"
		)
		(pin "2"
		)
		(instances
			(project "sodimm-ddr5-tester"
				(path ""
					(reference "C206")
					(unit 1)
				)
			)
		)
	)
	(symbol
		(lib_id "antmicroBarrelPowerConnectors:BarrelJack_Pin2mm_PJ-002AH")
		(at 29.21 22.225 0)
		(unit 1)
		(exclude_from_sim no)
		(in_bom yes)
		(on_board yes)
		(dnp no)
		(property "Reference" "J7"
			(at 26.67 16.51 0)
			(effects
				(font
					(size 1.27 1.27)
				)
				(justify right)
			)
		)
		(property "Value" "BarrelJack_Pin2mm_MJ-179PH"
			(at 46.99 32.385 0)
			(effects
				(font
					(size 1.27 1.27)
					(thickness 0.15)
				)
				(justify left bottom)
				(hide yes)
			)
		)
		(property "Footprint" "antmicro-footprints:BarrelJack_Pin2mm_PJ-002AH"
			(at 44.45 34.925 0)
			(effects
				(font
					(size 1.27 1.27)
					(thickness 0.15)
				)
				(justify left bottom)
				(hide yes)
			)
		)
		(property "Datasheet" "https://www.cuidevices.com/product/resource/pj-002ah.pdf"
			(at 44.45 37.465 0)
			(effects
				(font
					(size 1.27 1.27)
					(thickness 0.15)
				)
				(justify left bottom)
				(hide yes)
			)
		)
		(property "Description" "Barrel power connector"
			(at 44.45 47.625 0)
			(effects
				(font
					(size 1.27 1.27)
				)
				(justify left bottom)
				(hide yes)
			)
		)
		(property "Manufacturer" "CUI Inc"
			(at 44.45 40.005 0)
			(effects
				(font
					(size 1.27 1.27)
					(thickness 0.15)
				)
				(justify left bottom)
				(hide yes)
			)
		)
		(property "MPN" "PJ-002AH"
			(at 16.764 19.812 0)
			(effects
				(font
					(size 1.27 1.27)
					(thickness 0.15)
				)
				(justify left bottom)
			)
		)
		(property "Author" "Antmicro"
			(at 44.45 42.545 0)
			(effects
				(font
					(size 1.27 1.27)
					(thickness 0.15)
				)
				(justify left bottom)
				(hide yes)
			)
		)
		(property "License" "Apache-2.0"
			(at 44.45 45.085 0)
			(effects
				(font
					(size 1.27 1.27)
					(thickness 0.15)
				)
				(justify left bottom)
				(hide yes)
			)
		)
		(pin "1"
		)
		(pin "2"
		)
		(pin "3"
		)
		(instances
			(project "sodimm-ddr5-tester"
				(path ""
					(reference "J7")
					(unit 1)
				)
			)
		)
	)
	(symbol
		(lib_id "antmicroTestPoints:TP_1mm_SMD")
		(at 95.25 247.015 0)
		(unit 1)
		(exclude_from_sim no)
		(in_bom yes)
		(on_board yes)
		(dnp no)
		(property "Reference" "TP17"
			(at 95.25 249.555 0)
			(effects
				(font
					(size 1.27 1.27)
				)
				(justify left)
			)
		)
		(property "Value" "TP_1mm_SMD"
			(at 110.49 254.635 0)
			(effects
				(font
					(size 1.27 1.27)
					(thickness 0.15)
				)
				(justify left bottom)
				(hide yes)
			)
		)
		(property "Footprint" "antmicro-footprints:TP_SMD_1mm"
			(at 110.49 257.175 0)
			(effects
				(font
					(size 1.27 1.27)
					(thickness 0.15)
				)
				(justify left bottom)
				(hide yes)
			)
		)
		(property "Datasheet" ""
			(at 110.49 259.715 0)
			(effects
				(font
					(size 1.27 1.27)
					(thickness 0.15)
				)
				(justify left bottom)
				(hide yes)
			)
		)
		(property "Description" ""
			(at 95.25 247.015 0)
			(effects
				(font
					(size 1.27 1.27)
				)
			)
		)
		(property "MPN" ""
			(at 95.25 247.015 0)
			(effects
				(font
					(size 1.27 1.27)
				)
				(hide yes)
			)
		)
		(property "Manufacturer" ""
			(at 95.25 247.015 0)
			(effects
				(font
					(size 1.27 1.27)
				)
				(hide yes)
			)
		)
		(property "Author" "Antmicro"
			(at 110.49 262.255 0)
			(effects
				(font
					(size 1.27 1.27)
					(thickness 0.15)
				)
				(justify left bottom)
				(hide yes)
			)
		)
		(property "License" "Apache-2.0"
			(at 110.49 264.795 0)
			(effects
				(font
					(size 1.27 1.27)
					(thickness 0.15)
				)
				(justify left bottom)
				(hide yes)
			)
		)
		(pin "1"
		)
		(instances
			(project "sodimm-ddr5-tester"
				(path ""
					(reference "TP17")
					(unit 1)
				)
			)
		)
	)
	(symbol
		(lib_id "antmicroCapacitors0402:C_1u_0402")
		(at 215.9 184.785 90)
		(unit 1)
		(exclude_from_sim no)
		(in_bom yes)
		(on_board yes)
		(dnp no)
		(fields_autoplaced yes)
		(property "Reference" "C174"
			(at 218.44 180.9685 90)
			(effects
				(font
					(size 1.27 1.27)
				)
				(justify right)
			)
		)
		(property "Value" "C_1u_0402"
			(at 219.71 184.785 0)
			(effects
				(font
					(size 1.27 1.27)
				)
				(hide yes)
			)
		)
		(property "Footprint" "antmicro-footprints:C_0402_1005Metric"
			(at 210.82 179.705 0)
			(effects
				(font
					(size 1.27 1.27)
				)
				(justify left)
				(hide yes)
			)
		)
		(property "Datasheet" "https://product.tdk.com/en/search/capacitor/ceramic/mlcc/info?part_no=C1005X6S1A105K050BC"
			(at 215.9 184.785 0)
			(effects
				(font
					(size 1.27 1.27)
				)
				(hide yes)
			)
		)
		(property "Description" ""
			(at 215.9 184.785 0)
			(effects
				(font
					(size 1.27 1.27)
				)
			)
		)
		(property "Manufacturer" "TDK"
			(at 205.74 179.705 0)
			(effects
				(font
					(size 1.27 1.27)
				)
				(justify left)
				(hide yes)
			)
		)
		(property "MPN" "C1005X6S1A105K050BC"
			(at 208.28 179.705 0)
			(effects
				(font
					(size 1.27 1.27)
				)
				(justify left)
				(hide yes)
			)
		)
		(property "Val" "1u"
			(at 218.44 183.5085 90)
			(effects
				(font
					(size 1.27 1.27)
				)
				(justify right)
			)
		)
		(property "License" "Apache-2.0"
			(at 238.76 164.465 0)
			(effects
				(font
					(size 1.27 1.27)
					(thickness 0.15)
				)
				(justify left bottom)
				(hide yes)
			)
		)
		(property "Author" "Antmicro"
			(at 241.3 164.465 0)
			(effects
				(font
					(size 1.27 1.27)
					(thickness 0.15)
				)
				(justify left bottom)
				(hide yes)
			)
		)
		(property "Voltage" ""
			(at 243.84 164.465 0)
			(effects
				(font
					(size 1.27 1.27)
				)
				(justify left bottom)
				(hide yes)
			)
		)
		(property "Dielectric" ""
			(at 246.38 164.465 0)
			(effects
				(font
					(size 1.27 1.27)
				)
				(justify left bottom)
				(hide yes)
			)
		)
		(pin "1"
		)
		(pin "2"
		)
		(instances
			(project "sodimm-ddr5-tester"
				(path ""
					(reference "C174")
					(unit 1)
				)
			)
		)
	)
	(symbol
		(lib_id "antmicropower:GND")
		(at 269.24 61.595 0)
		(unit 1)
		(exclude_from_sim no)
		(in_bom yes)
		(on_board yes)
		(dnp no)
		(fields_autoplaced yes)
		(property "Reference" "#PWR0359"
			(at 269.24 67.945 0)
			(effects
				(font
					(size 1.27 1.27)
				)
				(hide yes)
			)
		)
		(property "Value" "GND"
			(at 271.78 62.865 0)
			(effects
				(font
					(size 1.27 1.27)
					(thickness 0.15)
				)
				(justify left)
			)
		)
		(property "Footprint" ""
			(at 278.13 69.215 0)
			(effects
				(font
					(size 1.27 1.27)
					(thickness 0.15)
				)
				(justify left bottom)
				(hide yes)
			)
		)
		(property "Datasheet" ""
			(at 278.13 74.295 0)
			(effects
				(font
					(size 1.27 1.27)
					(thickness 0.15)
				)
				(justify left bottom)
				(hide yes)
			)
		)
		(property "Description" ""
			(at 278.13 76.835 0)
			(effects
				(font
					(size 1.27 1.27)
				)
				(justify left bottom)
				(hide yes)
			)
		)
		(property "Author" "Antmicro"
			(at 278.13 69.215 0)
			(effects
				(font
					(size 1.27 1.27)
					(thickness 0.15)
				)
				(justify left bottom)
				(hide yes)
			)
		)
		(property "License" "Apache-2.0"
			(at 278.13 71.755 0)
			(effects
				(font
					(size 1.27 1.27)
					(thickness 0.15)
				)
				(justify left bottom)
				(hide yes)
			)
		)
		(pin "1"
		)
		(instances
			(project "sodimm-ddr5-tester"
				(path ""
					(reference "#PWR0359")
					(unit 1)
				)
			)
		)
	)
	(symbol
		(lib_id "antmicropower:GND")
		(at 190.5 215.265 0)
		(unit 1)
		(exclude_from_sim no)
		(in_bom yes)
		(on_board yes)
		(dnp no)
		(fields_autoplaced yes)
		(property "Reference" "#PWR0344"
			(at 190.5 221.615 0)
			(effects
				(font
					(size 1.27 1.27)
				)
				(hide yes)
			)
		)
		(property "Value" "GND"
			(at 193.04 216.535 0)
			(effects
				(font
					(size 1.27 1.27)
					(thickness 0.15)
				)
				(justify left)
			)
		)
		(property "Footprint" ""
			(at 199.39 222.885 0)
			(effects
				(font
					(size 1.27 1.27)
					(thickness 0.15)
				)
				(justify left bottom)
				(hide yes)
			)
		)
		(property "Datasheet" ""
			(at 199.39 227.965 0)
			(effects
				(font
					(size 1.27 1.27)
					(thickness 0.15)
				)
				(justify left bottom)
				(hide yes)
			)
		)
		(property "Description" ""
			(at 199.39 230.505 0)
			(effects
				(font
					(size 1.27 1.27)
				)
				(justify left bottom)
				(hide yes)
			)
		)
		(property "Author" "Antmicro"
			(at 199.39 222.885 0)
			(effects
				(font
					(size 1.27 1.27)
					(thickness 0.15)
				)
				(justify left bottom)
				(hide yes)
			)
		)
		(property "License" "Apache-2.0"
			(at 199.39 225.425 0)
			(effects
				(font
					(size 1.27 1.27)
					(thickness 0.15)
				)
				(justify left bottom)
				(hide yes)
			)
		)
		(pin "1"
		)
		(instances
			(project "sodimm-ddr5-tester"
				(path ""
					(reference "#PWR0344")
					(unit 1)
				)
			)
		)
	)
	(symbol
		(lib_id "antmicroTestPoints:TP_1mm_SMD")
		(at 113.03 278.13 270)
		(unit 1)
		(exclude_from_sim no)
		(in_bom yes)
		(on_board yes)
		(dnp no)
		(property "Reference" "TP26"
			(at 113.03 283.1028 90)
			(effects
				(font
					(size 1.27 1.27)
				)
			)
		)
		(property "Value" "TP_1mm_SMD"
			(at 105.41 293.37 0)
			(effects
				(font
					(size 1.27 1.27)
					(thickness 0.15)
				)
				(justify left bottom)
				(hide yes)
			)
		)
		(property "Footprint" "antmicro-footprints:TP_SMD_1mm"
			(at 102.87 293.37 0)
			(effects
				(font
					(size 1.27 1.27)
					(thickness 0.15)
				)
				(justify left bottom)
				(hide yes)
			)
		)
		(property "Datasheet" ""
			(at 100.33 293.37 0)
			(effects
				(font
					(size 1.27 1.27)
					(thickness 0.15)
				)
				(justify left bottom)
				(hide yes)
			)
		)
		(property "Description" ""
			(at 113.03 278.13 0)
			(effects
				(font
					(size 1.27 1.27)
				)
			)
		)
		(property "MPN" ""
			(at 113.03 278.13 0)
			(effects
				(font
					(size 1.27 1.27)
				)
				(hide yes)
			)
		)
		(property "Manufacturer" ""
			(at 113.03 278.13 0)
			(effects
				(font
					(size 1.27 1.27)
				)
				(hide yes)
			)
		)
		(property "Author" "Antmicro"
			(at 97.79 293.37 0)
			(effects
				(font
					(size 1.27 1.27)
					(thickness 0.15)
				)
				(justify left bottom)
				(hide yes)
			)
		)
		(property "License" "Apache-2.0"
			(at 95.25 293.37 0)
			(effects
				(font
					(size 1.27 1.27)
					(thickness 0.15)
				)
				(justify left bottom)
				(hide yes)
			)
		)
		(pin "1"
		)
		(instances
			(project "sodimm-ddr5-tester"
				(path ""
					(reference "TP26")
					(unit 1)
				)
			)
		)
	)
	(symbol
		(lib_id "antmicropower:GND")
		(at 86.995 226.06 0)
		(unit 1)
		(exclude_from_sim no)
		(in_bom yes)
		(on_board yes)
		(dnp no)
		(fields_autoplaced yes)
		(property "Reference" "#PWR0307"
			(at 86.995 232.41 0)
			(effects
				(font
					(size 1.27 1.27)
				)
				(hide yes)
			)
		)
		(property "Value" "GND"
			(at 88.9 227.33 0)
			(effects
				(font
					(size 1.27 1.27)
					(thickness 0.15)
				)
				(justify left)
			)
		)
		(property "Footprint" ""
			(at 95.885 233.68 0)
			(effects
				(font
					(size 1.27 1.27)
					(thickness 0.15)
				)
				(justify left bottom)
				(hide yes)
			)
		)
		(property "Datasheet" ""
			(at 95.885 238.76 0)
			(effects
				(font
					(size 1.27 1.27)
					(thickness 0.15)
				)
				(justify left bottom)
				(hide yes)
			)
		)
		(property "Description" ""
			(at 95.885 241.3 0)
			(effects
				(font
					(size 1.27 1.27)
				)
				(justify left bottom)
				(hide yes)
			)
		)
		(property "Author" "Antmicro"
			(at 95.885 233.68 0)
			(effects
				(font
					(size 1.27 1.27)
					(thickness 0.15)
				)
				(justify left bottom)
				(hide yes)
			)
		)
		(property "License" "Apache-2.0"
			(at 95.885 236.22 0)
			(effects
				(font
					(size 1.27 1.27)
					(thickness 0.15)
				)
				(justify left bottom)
				(hide yes)
			)
		)
		(pin "1"
		)
		(instances
			(project "sodimm-ddr5-tester"
				(path ""
					(reference "#PWR0307")
					(unit 1)
				)
			)
		)
	)
	(symbol
		(lib_id "antmicropower:GND")
		(at 111.125 52.705 0)
		(unit 1)
		(exclude_from_sim no)
		(in_bom yes)
		(on_board yes)
		(dnp no)
		(fields_autoplaced yes)
		(property "Reference" "#PWR0302"
			(at 111.125 59.055 0)
			(effects
				(font
					(size 1.27 1.27)
				)
				(hide yes)
			)
		)
		(property "Value" "GND"
			(at 113.665 53.975 0)
			(effects
				(font
					(size 1.27 1.27)
					(thickness 0.15)
				)
				(justify left)
			)
		)
		(property "Footprint" ""
			(at 120.015 60.325 0)
			(effects
				(font
					(size 1.27 1.27)
					(thickness 0.15)
				)
				(justify left bottom)
				(hide yes)
			)
		)
		(property "Datasheet" ""
			(at 120.015 65.405 0)
			(effects
				(font
					(size 1.27 1.27)
					(thickness 0.15)
				)
				(justify left bottom)
				(hide yes)
			)
		)
		(property "Description" ""
			(at 120.015 67.945 0)
			(effects
				(font
					(size 1.27 1.27)
				)
				(justify left bottom)
				(hide yes)
			)
		)
		(property "Author" "Antmicro"
			(at 120.015 60.325 0)
			(effects
				(font
					(size 1.27 1.27)
					(thickness 0.15)
				)
				(justify left bottom)
				(hide yes)
			)
		)
		(property "License" "Apache-2.0"
			(at 120.015 62.865 0)
			(effects
				(font
					(size 1.27 1.27)
					(thickness 0.15)
				)
				(justify left bottom)
				(hide yes)
			)
		)
		(pin "1"
		)
		(instances
			(project "sodimm-ddr5-tester"
				(path ""
					(reference "#PWR0302")
					(unit 1)
				)
			)
		)
	)
	(symbol
		(lib_id "antmicroTestPoints:TP_1mm_SMD")
		(at 290.83 276.86 0)
		(unit 1)
		(exclude_from_sim no)
		(in_bom yes)
		(on_board yes)
		(dnp no)
		(property "Reference" "TP71"
			(at 297.688 276.86 0)
			(effects
				(font
					(size 1.27 1.27)
				)
			)
		)
		(property "Value" "TP_1mm_SMD"
			(at 306.07 284.48 0)
			(effects
				(font
					(size 1.27 1.27)
					(thickness 0.15)
				)
				(justify left bottom)
				(hide yes)
			)
		)
		(property "Footprint" "antmicro-footprints:TP_SMD_1mm"
			(at 306.07 287.02 0)
			(effects
				(font
					(size 1.27 1.27)
					(thickness 0.15)
				)
				(justify left bottom)
				(hide yes)
			)
		)
		(property "Datasheet" ""
			(at 306.07 289.56 0)
			(effects
				(font
					(size 1.27 1.27)
					(thickness 0.15)
				)
				(justify left bottom)
				(hide yes)
			)
		)
		(property "Description" ""
			(at 290.83 276.86 0)
			(effects
				(font
					(size 1.27 1.27)
				)
			)
		)
		(property "MPN" ""
			(at 290.83 276.86 0)
			(effects
				(font
					(size 1.27 1.27)
				)
				(hide yes)
			)
		)
		(property "Manufacturer" ""
			(at 290.83 276.86 0)
			(effects
				(font
					(size 1.27 1.27)
				)
				(hide yes)
			)
		)
		(property "Author" "Antmicro"
			(at 306.07 292.1 0)
			(effects
				(font
					(size 1.27 1.27)
					(thickness 0.15)
				)
				(justify left bottom)
				(hide yes)
			)
		)
		(property "License" "Apache-2.0"
			(at 306.07 294.64 0)
			(effects
				(font
					(size 1.27 1.27)
					(thickness 0.15)
				)
				(justify left bottom)
				(hide yes)
			)
		)
		(pin "1"
		)
		(instances
			(project "sodimm-ddr5-tester"
				(path ""
					(reference "TP71")
					(unit 1)
				)
			)
		)
	)
	(symbol
		(lib_id "antmicropower:GND")
		(at 184.15 72.39 0)
		(unit 1)
		(exclude_from_sim no)
		(in_bom yes)
		(on_board yes)
		(dnp no)
		(fields_autoplaced yes)
		(property "Reference" "#PWR0343"
			(at 184.15 78.74 0)
			(effects
				(font
					(size 1.27 1.27)
				)
				(hide yes)
			)
		)
		(property "Value" "GND"
			(at 186.69 73.66 0)
			(effects
				(font
					(size 1.27 1.27)
					(thickness 0.15)
				)
				(justify left)
			)
		)
		(property "Footprint" ""
			(at 193.04 80.01 0)
			(effects
				(font
					(size 1.27 1.27)
					(thickness 0.15)
				)
				(justify left bottom)
				(hide yes)
			)
		)
		(property "Datasheet" ""
			(at 193.04 85.09 0)
			(effects
				(font
					(size 1.27 1.27)
					(thickness 0.15)
				)
				(justify left bottom)
				(hide yes)
			)
		)
		(property "Description" ""
			(at 193.04 87.63 0)
			(effects
				(font
					(size 1.27 1.27)
				)
				(justify left bottom)
				(hide yes)
			)
		)
		(property "Author" "Antmicro"
			(at 193.04 80.01 0)
			(effects
				(font
					(size 1.27 1.27)
					(thickness 0.15)
				)
				(justify left bottom)
				(hide yes)
			)
		)
		(property "License" "Apache-2.0"
			(at 193.04 82.55 0)
			(effects
				(font
					(size 1.27 1.27)
					(thickness 0.15)
				)
				(justify left bottom)
				(hide yes)
			)
		)
		(pin "1"
		)
		(instances
			(project "sodimm-ddr5-tester"
				(path ""
					(reference "#PWR0343")
					(unit 1)
				)
			)
		)
	)
	(symbol
		(lib_id "antmicroResistorsmisc:R_0R01_1206")
		(at 306.07 179.705 0)
		(unit 1)
		(exclude_from_sim no)
		(in_bom yes)
		(on_board yes)
		(dnp no)
		(property "Reference" "R146"
			(at 308.61 174.625 0)
			(effects
				(font
					(size 1.27 1.27)
				)
			)
		)
		(property "Value" "R_0R01_1206"
			(at 326.39 192.405 0)
			(effects
				(font
					(size 1.27 1.27)
					(thickness 0.15)
				)
				(justify left bottom)
				(hide yes)
			)
		)
		(property "Footprint" "antmicro-footprints:R_1206_3216Metric"
			(at 326.39 194.945 0)
			(effects
				(font
					(size 1.27 1.27)
					(thickness 0.15)
				)
				(justify left bottom)
				(hide yes)
			)
		)
		(property "Datasheet" "https://www.yageo.com/upload/media/product/productsearch/datasheet/rchip/PYu-RL_Group_521_RoHS_L_2.pdf"
			(at 326.39 197.485 0)
			(effects
				(font
					(size 1.27 1.27)
					(thickness 0.15)
				)
				(justify left bottom)
				(hide yes)
			)
		)
		(property "Description" ""
			(at 306.07 179.705 0)
			(effects
				(font
					(size 1.27 1.27)
				)
			)
		)
		(property "Manufacturer" "YAGEO"
			(at 326.39 202.565 0)
			(effects
				(font
					(size 1.27 1.27)
					(thickness 0.15)
				)
				(justify left bottom)
				(hide yes)
			)
		)
		(property "MPN" "RL1206FR-7W0R01L"
			(at 326.39 200.025 0)
			(effects
				(font
					(size 1.27 1.27)
					(thickness 0.15)
				)
				(justify left bottom)
				(hide yes)
			)
		)
		(property "Val" "0R01"
			(at 308.61 177.165 0)
			(effects
				(font
					(size 1.27 1.27)
					(thickness 0.15)
				)
			)
		)
		(property "License" "Apache-2.0"
			(at 326.39 205.105 0)
			(effects
				(font
					(size 1.27 1.27)
					(thickness 0.15)
				)
				(justify left bottom)
				(hide yes)
			)
		)
		(property "Author" "Antmicro"
			(at 326.39 207.645 0)
			(effects
				(font
					(size 1.27 1.27)
					(thickness 0.15)
				)
				(justify left bottom)
				(hide yes)
			)
		)
		(property "Tolerance" "1%"
			(at 326.39 189.865 0)
			(effects
				(font
					(size 1.27 1.27)
				)
				(justify left bottom)
				(hide yes)
			)
		)
		(pin "1"
		)
		(pin "2"
		)
		(instances
			(project "sodimm-ddr5-tester"
				(path ""
					(reference "R146")
					(unit 1)
				)
			)
		)
	)
	(symbol
		(lib_id "antmicroResistors0402:R_0R_0402")
		(at 386.715 208.28 90)
		(unit 1)
		(exclude_from_sim no)
		(in_bom yes)
		(on_board yes)
		(dnp no)
		(fields_autoplaced yes)
		(property "Reference" "R168"
			(at 388.62 204.4699 90)
			(effects
				(font
					(size 1.27 1.27)
				)
				(justify right)
			)
		)
		(property "Value" "R_0R_0402"
			(at 399.415 187.96 0)
			(effects
				(font
					(size 1.27 1.27)
					(thickness 0.15)
				)
				(justify left bottom)
				(hide yes)
			)
		)
		(property "Footprint" "antmicro-footprints:R_0402_1005Metric"
			(at 401.955 187.96 0)
			(effects
				(font
					(size 1.27 1.27)
					(thickness 0.15)
				)
				(justify left bottom)
				(hide yes)
			)
		)
		(property "Datasheet" "https://industrial.panasonic.com/cdbs/www-data/pdf/RDA0000/AOA0000C301.pdf"
			(at 404.495 187.96 0)
			(effects
				(font
					(size 1.27 1.27)
					(thickness 0.15)
				)
				(justify left bottom)
				(hide yes)
			)
		)
		(property "Description" ""
			(at 386.715 208.28 0)
			(effects
				(font
					(size 1.27 1.27)
				)
			)
		)
		(property "Manufacturer" "Panasonic"
			(at 409.575 187.96 0)
			(effects
				(font
					(size 1.27 1.27)
					(thickness 0.15)
				)
				(justify left bottom)
				(hide yes)
			)
		)
		(property "MPN" "ERJ2GE0R00X"
			(at 407.035 187.96 0)
			(effects
				(font
					(size 1.27 1.27)
					(thickness 0.15)
				)
				(justify left bottom)
				(hide yes)
			)
		)
		(property "Val" "0R"
			(at 388.62 207.0099 90)
			(effects
				(font
					(size 1.27 1.27)
					(thickness 0.15)
				)
				(justify right)
			)
		)
		(property "License" "Apache-2.0"
			(at 412.115 187.96 0)
			(effects
				(font
					(size 1.27 1.27)
					(thickness 0.15)
				)
				(justify left bottom)
				(hide yes)
			)
		)
		(property "Author" "Antmicro"
			(at 414.655 187.96 0)
			(effects
				(font
					(size 1.27 1.27)
					(thickness 0.15)
				)
				(justify left bottom)
				(hide yes)
			)
		)
		(property "Tolerance" "~"
			(at 396.875 187.96 0)
			(effects
				(font
					(size 1.27 1.27)
				)
				(justify left bottom)
				(hide yes)
			)
		)
		(property "Current" "1A"
			(at 388.62 208.2799 90)
			(effects
				(font
					(size 1.27 1.27)
					(thickness 0.15)
				)
				(justify right)
				(hide yes)
			)
		)
		(pin "1"
		)
		(pin "2"
		)
		(instances
			(project "sodimm-ddr5-tester"
				(path ""
					(reference "R168")
					(unit 1)
				)
			)
		)
	)
	(symbol
		(lib_id "antmicroTestPoints:TP_1mm_SMD")
		(at 105.41 278.13 270)
		(unit 1)
		(exclude_from_sim no)
		(in_bom yes)
		(on_board yes)
		(dnp no)
		(property "Reference" "TP25"
			(at 105.41 283.1028 90)
			(effects
				(font
					(size 1.27 1.27)
				)
			)
		)
		(property "Value" "TP_1mm_SMD"
			(at 97.79 293.37 0)
			(effects
				(font
					(size 1.27 1.27)
					(thickness 0.15)
				)
				(justify left bottom)
				(hide yes)
			)
		)
		(property "Footprint" "antmicro-footprints:TP_SMD_1mm"
			(at 95.25 293.37 0)
			(effects
				(font
					(size 1.27 1.27)
					(thickness 0.15)
				)
				(justify left bottom)
				(hide yes)
			)
		)
		(property "Datasheet" ""
			(at 92.71 293.37 0)
			(effects
				(font
					(size 1.27 1.27)
					(thickness 0.15)
				)
				(justify left bottom)
				(hide yes)
			)
		)
		(property "Description" ""
			(at 105.41 278.13 0)
			(effects
				(font
					(size 1.27 1.27)
				)
			)
		)
		(property "MPN" ""
			(at 105.41 278.13 0)
			(effects
				(font
					(size 1.27 1.27)
				)
				(hide yes)
			)
		)
		(property "Manufacturer" ""
			(at 105.41 278.13 0)
			(effects
				(font
					(size 1.27 1.27)
				)
				(hide yes)
			)
		)
		(property "Author" "Antmicro"
			(at 90.17 293.37 0)
			(effects
				(font
					(size 1.27 1.27)
					(thickness 0.15)
				)
				(justify left bottom)
				(hide yes)
			)
		)
		(property "License" "Apache-2.0"
			(at 87.63 293.37 0)
			(effects
				(font
					(size 1.27 1.27)
					(thickness 0.15)
				)
				(justify left bottom)
				(hide yes)
			)
		)
		(pin "1"
		)
		(instances
			(project "sodimm-ddr5-tester"
				(path ""
					(reference "TP25")
					(unit 1)
				)
			)
		)
	)
	(symbol
		(lib_id "antmicroTransistorsFETsMOSFETsSingle:BSS138PW,115")
		(at 311.15 54.61 0)
		(unit 1)
		(exclude_from_sim no)
		(in_bom yes)
		(on_board yes)
		(dnp no)
		(fields_autoplaced yes)
		(property "Reference" "Q17"
			(at 322.58 50.8 0)
			(effects
				(font
					(size 1.27 1.27)
					(thickness 0.15)
				)
				(justify left)
			)
		)
		(property "Value" "BSS138PW,115"
			(at 334.01 63.5 0)
			(effects
				(font
					(size 1.27 1.27)
					(thickness 0.15)
				)
				(justify left bottom)
				(hide yes)
			)
		)
		(property "Footprint" "antmicro-footprints:SC70-3"
			(at 334.01 66.04 0)
			(effects
				(font
					(size 1.27 1.27)
					(thickness 0.15)
				)
				(justify left bottom)
				(hide yes)
			)
		)
		(property "Datasheet" "https://assets.nexperia.com/documents/data-sheet/BSS138PW.pdf"
			(at 334.01 68.58 0)
			(effects
				(font
					(size 1.27 1.27)
					(thickness 0.15)
				)
				(justify left bottom)
				(hide yes)
			)
		)
		(property "Description" "Power MOSFET, N Channel, 60 V, 320 mA, 0.9 ohm, SOT-323, Surface Mount"
			(at 334.01 81.28 0)
			(effects
				(font
					(size 1.27 1.27)
				)
				(justify left bottom)
				(hide yes)
			)
		)
		(property "MPN" "BSS138PW,115"
			(at 322.58 53.34 0)
			(effects
				(font
					(size 1.27 1.27)
					(thickness 0.15)
				)
				(justify left)
			)
		)
		(property "Manufacturer" "Nexperia"
			(at 334.01 73.66 0)
			(effects
				(font
					(size 1.27 1.27)
					(thickness 0.15)
				)
				(justify left bottom)
				(hide yes)
			)
		)
		(property "Author" "Antmicro"
			(at 334.01 76.2 0)
			(effects
				(font
					(size 1.27 1.27)
					(thickness 0.15)
				)
				(justify left bottom)
				(hide yes)
			)
		)
		(property "License" "Apache-2.0"
			(at 334.01 78.74 0)
			(effects
				(font
					(size 1.27 1.27)
					(thickness 0.15)
				)
				(justify left bottom)
				(hide yes)
			)
		)
		(pin "3"
		)
		(pin "2"
		)
		(pin "1"
		)
		(instances
			(project "sodimm-ddr5-tester"
				(path ""
					(reference "Q17")
					(unit 1)
				)
			)
		)
	)
	(symbol
		(lib_id "antmicropower:+1V1")
		(at 163.195 253.365 0)
		(unit 1)
		(exclude_from_sim no)
		(in_bom yes)
		(on_board yes)
		(dnp no)
		(fields_autoplaced yes)
		(property "Reference" "#PWR0390"
			(at 163.195 257.175 0)
			(effects
				(font
					(size 1.27 1.27)
				)
				(hide yes)
			)
		)
		(property "Value" "+1V1"
			(at 163.195 249.809 0)
			(effects
				(font
					(size 1.27 1.27)
				)
			)
		)
		(property "Footprint" ""
			(at 163.195 253.365 0)
			(effects
				(font
					(size 1.27 1.27)
				)
				(hide yes)
			)
		)
		(property "Datasheet" ""
			(at 163.195 253.365 0)
			(effects
				(font
					(size 1.27 1.27)
				)
				(hide yes)
			)
		)
		(property "Description" ""
			(at 163.195 253.365 0)
			(effects
				(font
					(size 1.27 1.27)
				)
			)
		)
		(pin "1"
		)
		(instances
			(project "sodimm-ddr5-tester"
				(path ""
					(reference "#PWR0390")
					(unit 1)
				)
			)
		)
	)
	(symbol
		(lib_id "antmicropower:PWR_FLAG")
		(at 316.865 179.07 0)
		(unit 1)
		(exclude_from_sim no)
		(in_bom yes)
		(on_board yes)
		(dnp no)
		(fields_autoplaced yes)
		(property "Reference" "#FLG0115"
			(at 316.865 177.165 0)
			(effects
				(font
					(size 1.27 1.27)
				)
				(hide yes)
			)
		)
		(property "Value" "PWR_FLAG"
			(at 316.865 175.4942 0)
			(effects
				(font
					(size 1.27 1.27)
				)
			)
		)
		(property "Footprint" ""
			(at 316.865 179.07 0)
			(effects
				(font
					(size 1.27 1.27)
				)
				(hide yes)
			)
		)
		(property "Datasheet" ""
			(at 316.865 179.07 0)
			(effects
				(font
					(size 1.27 1.27)
				)
				(hide yes)
			)
		)
		(property "Description" ""
			(at 316.865 179.07 0)
			(effects
				(font
					(size 1.27 1.27)
				)
			)
		)
		(pin "1"
		)
		(instances
			(project "sodimm-ddr5-tester"
				(path ""
					(reference "#FLG0115")
					(unit 1)
				)
			)
		)
	)
	(symbol
		(lib_id "antmicropower:GND")
		(at 285.75 229.87 0)
		(unit 1)
		(exclude_from_sim no)
		(in_bom yes)
		(on_board yes)
		(dnp no)
		(fields_autoplaced yes)
		(property "Reference" "#PWR0311"
			(at 285.75 236.22 0)
			(effects
				(font
					(size 1.27 1.27)
				)
				(hide yes)
			)
		)
		(property "Value" "GND"
			(at 288.29 231.14 0)
			(effects
				(font
					(size 1.27 1.27)
					(thickness 0.15)
				)
				(justify left)
			)
		)
		(property "Footprint" ""
			(at 294.64 237.49 0)
			(effects
				(font
					(size 1.27 1.27)
					(thickness 0.15)
				)
				(justify left bottom)
				(hide yes)
			)
		)
		(property "Datasheet" ""
			(at 294.64 242.57 0)
			(effects
				(font
					(size 1.27 1.27)
					(thickness 0.15)
				)
				(justify left bottom)
				(hide yes)
			)
		)
		(property "Description" ""
			(at 294.64 245.11 0)
			(effects
				(font
					(size 1.27 1.27)
				)
				(justify left bottom)
				(hide yes)
			)
		)
		(property "Author" "Antmicro"
			(at 294.64 237.49 0)
			(effects
				(font
					(size 1.27 1.27)
					(thickness 0.15)
				)
				(justify left bottom)
				(hide yes)
			)
		)
		(property "License" "Apache-2.0"
			(at 294.64 240.03 0)
			(effects
				(font
					(size 1.27 1.27)
					(thickness 0.15)
				)
				(justify left bottom)
				(hide yes)
			)
		)
		(pin "1"
		)
		(instances
			(project "sodimm-ddr5-tester"
				(path ""
					(reference "#PWR0311")
					(unit 1)
				)
			)
		)
	)
	(symbol
		(lib_id "antmicroPMICPowerSequencers:MAX812REUS+T")
		(at 294.005 52.07 0)
		(unit 1)
		(exclude_from_sim no)
		(in_bom yes)
		(on_board yes)
		(dnp no)
		(fields_autoplaced yes)
		(property "Reference" "U26"
			(at 301.625 44.45 0)
			(effects
				(font
					(size 1.27 1.27)
				)
			)
		)
		(property "Value" "MAX812REUS+T"
			(at 301.625 46.99 0)
			(effects
				(font
					(size 1.27 1.27)
					(thickness 0.15)
				)
			)
		)
		(property "Footprint" "antmicro-footprints:SOT-143-4"
			(at 324.485 59.69 0)
			(effects
				(font
					(size 1.27 1.27)
					(thickness 0.15)
				)
				(justify left bottom)
				(hide yes)
			)
		)
		(property "Datasheet" "https://datasheets.maximintegrated.com/en/ds/MAX811-MAX812T.pdf"
			(at 324.485 62.23 0)
			(effects
				(font
					(size 1.27 1.27)
					(thickness 0.15)
				)
				(justify left bottom)
				(hide yes)
			)
		)
		(property "Description" ""
			(at 294.005 52.07 0)
			(effects
				(font
					(size 1.27 1.27)
				)
			)
		)
		(property "Manufacturer" "Maxim Integrated Products"
			(at 324.485 64.77 0)
			(effects
				(font
					(size 1.27 1.27)
					(thickness 0.15)
				)
				(justify left bottom)
				(hide yes)
			)
		)
		(property "MPN" "MAX812REUS+T"
			(at 324.485 67.31 0)
			(effects
				(font
					(size 1.27 1.27)
					(thickness 0.15)
				)
				(justify left bottom)
				(hide yes)
			)
		)
		(property "License" "Apache-2.0"
			(at 324.485 69.85 0)
			(effects
				(font
					(size 1.27 1.27)
					(thickness 0.15)
				)
				(justify left bottom)
				(hide yes)
			)
		)
		(property "Author" "Antmicro"
			(at 324.485 72.39 0)
			(effects
				(font
					(size 1.27 1.27)
					(thickness 0.15)
				)
				(justify left bottom)
				(hide yes)
			)
		)
		(pin "1"
		)
		(pin "2"
		)
		(pin "3"
		)
		(pin "4"
		)
		(instances
			(project "sodimm-ddr5-tester"
				(path ""
					(reference "U26")
					(unit 1)
				)
			)
		)
	)
	(symbol
		(lib_id "antmicroResistors0402:R_47k_0402")
		(at 207.01 102.87 90)
		(unit 1)
		(exclude_from_sim no)
		(in_bom yes)
		(on_board yes)
		(dnp no)
		(fields_autoplaced yes)
		(property "Reference" "R140"
			(at 208.661 99.4994 90)
			(effects
				(font
					(size 1.27 1.27)
				)
				(justify right)
			)
		)
		(property "Value" "R_47k_0402"
			(at 219.71 82.55 0)
			(effects
				(font
					(size 1.27 1.27)
					(thickness 0.15)
				)
				(justify left bottom)
				(hide yes)
			)
		)
		(property "Footprint" "antmicro-footprints:R_0402_1005Metric"
			(at 222.25 82.55 0)
			(effects
				(font
					(size 1.27 1.27)
					(thickness 0.15)
				)
				(justify left bottom)
				(hide yes)
			)
		)
		(property "Datasheet" "https://www.bourns.com/docs/product-datasheets/cr.pdf"
			(at 224.79 82.55 0)
			(effects
				(font
					(size 1.27 1.27)
					(thickness 0.15)
				)
				(justify left bottom)
				(hide yes)
			)
		)
		(property "Description" ""
			(at 207.01 102.87 0)
			(effects
				(font
					(size 1.27 1.27)
				)
			)
		)
		(property "Manufacturer" "Bourns"
			(at 229.87 82.55 0)
			(effects
				(font
					(size 1.27 1.27)
					(thickness 0.15)
				)
				(justify left bottom)
				(hide yes)
			)
		)
		(property "MPN" "CR0402-FX-4702GLF"
			(at 227.33 82.55 0)
			(effects
				(font
					(size 1.27 1.27)
					(thickness 0.15)
				)
				(justify left bottom)
				(hide yes)
			)
		)
		(property "Val" "47k"
			(at 208.661 102.0297 90)
			(effects
				(font
					(size 1.27 1.27)
					(thickness 0.15)
				)
				(justify right)
			)
		)
		(property "License" "Apache-2.0"
			(at 232.41 82.55 0)
			(effects
				(font
					(size 1.27 1.27)
					(thickness 0.15)
				)
				(justify left bottom)
				(hide yes)
			)
		)
		(property "Author" "Antmicro"
			(at 234.95 82.55 0)
			(effects
				(font
					(size 1.27 1.27)
					(thickness 0.15)
				)
				(justify left bottom)
				(hide yes)
			)
		)
		(property "Tolerance" "1%"
			(at 217.17 82.55 0)
			(effects
				(font
					(size 1.27 1.27)
				)
				(justify left bottom)
				(hide yes)
			)
		)
		(pin "1"
		)
		(pin "2"
		)
		(instances
			(project "sodimm-ddr5-tester"
				(path ""
					(reference "R140")
					(unit 1)
				)
			)
		)
	)
	(symbol
		(lib_id "antmicroSlideSwitches:SW_CVS-08TB")
		(at 222.25 105.41 0)
		(unit 1)
		(exclude_from_sim no)
		(in_bom yes)
		(on_board yes)
		(dnp no)
		(fields_autoplaced yes)
		(property "Reference" "SW4"
			(at 228.6017 97.155 0)
			(effects
				(font
					(size 1.27 1.27)
					(thickness 0.15)
				)
			)
		)
		(property "Value" "SW_CVS-08TB"
			(at 228.6017 99.695 0)
			(effects
				(font
					(size 1.27 1.27)
					(thickness 0.15)
				)
			)
		)
		(property "Footprint" "antmicro-footprints:SW_DIP_SPSTx08_Slide_Copal_CVS-08xB_W5.9mm_P1mm"
			(at 248.92 113.03 0)
			(effects
				(font
					(size 1.27 1.27)
					(thickness 0.15)
				)
				(justify left bottom)
				(hide yes)
			)
		)
		(property "Datasheet" "https://www.mouser.com/datasheet/2/972/cvs-1827291.pdf"
			(at 248.92 115.57 0)
			(effects
				(font
					(size 1.27 1.27)
					(thickness 0.15)
				)
				(justify left bottom)
				(hide yes)
			)
		)
		(property "Description" ""
			(at 222.25 105.41 0)
			(effects
				(font
					(size 1.27 1.27)
				)
			)
		)
		(property "MPN" "CVS-08TB"
			(at 248.92 118.11 0)
			(effects
				(font
					(size 1.27 1.27)
					(thickness 0.15)
				)
				(justify left bottom)
				(hide yes)
			)
		)
		(property "Manufacturer" "Nidec Components"
			(at 248.92 120.65 0)
			(effects
				(font
					(size 1.27 1.27)
					(thickness 0.15)
				)
				(justify left bottom)
				(hide yes)
			)
		)
		(property "Author" "Antmicro"
			(at 248.92 123.19 0)
			(effects
				(font
					(size 1.27 1.27)
					(thickness 0.15)
				)
				(justify left bottom)
				(hide yes)
			)
		)
		(property "License" "Apache-2.0"
			(at 248.92 125.73 0)
			(effects
				(font
					(size 1.27 1.27)
					(thickness 0.15)
				)
				(justify left bottom)
				(hide yes)
			)
		)
		(pin "1"
		)
		(pin "10"
		)
		(pin "11"
		)
		(pin "12"
		)
		(pin "13"
		)
		(pin "14"
		)
		(pin "15"
		)
		(pin "16"
		)
		(pin "17"
		)
		(pin "2"
		)
		(pin "3"
		)
		(pin "4"
		)
		(pin "5"
		)
		(pin "6"
		)
		(pin "7"
		)
		(pin "8"
		)
		(pin "9"
		)
		(instances
			(project "sodimm-ddr5-tester"
				(path ""
					(reference "SW4")
					(unit 1)
				)
			)
		)
	)
	(symbol
		(lib_id "antmicroResistors0402:R_0R_0402")
		(at 160.02 184.15 90)
		(unit 1)
		(exclude_from_sim no)
		(in_bom no)
		(on_board yes)
		(dnp yes)
		(property "Reference" "R152"
			(at 162.56 180.3399 90)
			(effects
				(font
					(size 1.27 1.27)
				)
				(justify right)
			)
		)
		(property "Value" "R_0R_0402"
			(at 172.72 163.83 0)
			(effects
				(font
					(size 1.27 1.27)
					(thickness 0.15)
				)
				(justify left bottom)
				(hide yes)
			)
		)
		(property "Footprint" "antmicro-footprints:R_0402_1005Metric"
			(at 175.26 163.83 0)
			(effects
				(font
					(size 1.27 1.27)
					(thickness 0.15)
				)
				(justify left bottom)
				(hide yes)
			)
		)
		(property "Datasheet" "https://industrial.panasonic.com/cdbs/www-data/pdf/RDA0000/AOA0000C301.pdf"
			(at 177.8 163.83 0)
			(effects
				(font
					(size 1.27 1.27)
					(thickness 0.15)
				)
				(justify left bottom)
				(hide yes)
			)
		)
		(property "Description" ""
			(at 160.02 184.15 0)
			(effects
				(font
					(size 1.27 1.27)
				)
			)
		)
		(property "Manufacturer" "Panasonic"
			(at 182.88 163.83 0)
			(effects
				(font
					(size 1.27 1.27)
					(thickness 0.15)
				)
				(justify left bottom)
				(hide yes)
			)
		)
		(property "MPN" "ERJ2GE0R00X"
			(at 180.34 163.83 0)
			(effects
				(font
					(size 1.27 1.27)
					(thickness 0.15)
				)
				(justify left bottom)
				(hide yes)
			)
		)
		(property "Val" "0R"
			(at 162.56 182.8799 90)
			(effects
				(font
					(size 1.27 1.27)
					(thickness 0.15)
				)
				(justify right)
			)
		)
		(property "License" "Apache-2.0"
			(at 185.42 163.83 0)
			(effects
				(font
					(size 1.27 1.27)
					(thickness 0.15)
				)
				(justify left bottom)
				(hide yes)
			)
		)
		(property "Author" "Antmicro"
			(at 187.96 163.83 0)
			(effects
				(font
					(size 1.27 1.27)
					(thickness 0.15)
				)
				(justify left bottom)
				(hide yes)
			)
		)
		(property "Tolerance" "~"
			(at 170.18 163.83 0)
			(effects
				(font
					(size 1.27 1.27)
				)
				(justify left bottom)
				(hide yes)
			)
		)
		(property "Current" "1A"
			(at 162.56 185.4199 90)
			(effects
				(font
					(size 1.27 1.27)
					(thickness 0.15)
				)
				(justify right)
				(hide yes)
			)
		)
		(pin "1"
		)
		(pin "2"
		)
		(instances
			(project "sodimm-ddr5-tester"
				(path ""
					(reference "R152")
					(unit 1)
				)
			)
		)
	)
	(symbol
		(lib_id "antmicroTestPoints:TP_1mm_SMD")
		(at 267.97 274.32 0)
		(unit 1)
		(exclude_from_sim no)
		(in_bom yes)
		(on_board yes)
		(dnp no)
		(property "Reference" "TP63"
			(at 274.828 274.32 0)
			(effects
				(font
					(size 1.27 1.27)
				)
			)
		)
		(property "Value" "TP_1mm_SMD"
			(at 283.21 281.94 0)
			(effects
				(font
					(size 1.27 1.27)
					(thickness 0.15)
				)
				(justify left bottom)
				(hide yes)
			)
		)
		(property "Footprint" "antmicro-footprints:TP_SMD_1mm"
			(at 283.21 284.48 0)
			(effects
				(font
					(size 1.27 1.27)
					(thickness 0.15)
				)
				(justify left bottom)
				(hide yes)
			)
		)
		(property "Datasheet" ""
			(at 283.21 287.02 0)
			(effects
				(font
					(size 1.27 1.27)
					(thickness 0.15)
				)
				(justify left bottom)
				(hide yes)
			)
		)
		(property "Description" ""
			(at 267.97 274.32 0)
			(effects
				(font
					(size 1.27 1.27)
				)
			)
		)
		(property "MPN" ""
			(at 267.97 274.32 0)
			(effects
				(font
					(size 1.27 1.27)
				)
				(hide yes)
			)
		)
		(property "Manufacturer" ""
			(at 267.97 274.32 0)
			(effects
				(font
					(size 1.27 1.27)
				)
				(hide yes)
			)
		)
		(property "Author" "Antmicro"
			(at 283.21 289.56 0)
			(effects
				(font
					(size 1.27 1.27)
					(thickness 0.15)
				)
				(justify left bottom)
				(hide yes)
			)
		)
		(property "License" "Apache-2.0"
			(at 283.21 292.1 0)
			(effects
				(font
					(size 1.27 1.27)
					(thickness 0.15)
				)
				(justify left bottom)
				(hide yes)
			)
		)
		(pin "1"
		)
		(instances
			(project "sodimm-ddr5-tester"
				(path ""
					(reference "TP63")
					(unit 1)
				)
			)
		)
	)
	(symbol
		(lib_id "antmicropower:GND")
		(at 235.585 53.34 0)
		(unit 1)
		(exclude_from_sim no)
		(in_bom yes)
		(on_board yes)
		(dnp no)
		(fields_autoplaced yes)
		(property "Reference" "#PWR0333"
			(at 235.585 59.69 0)
			(effects
				(font
					(size 1.27 1.27)
				)
				(hide yes)
			)
		)
		(property "Value" "GND"
			(at 237.49 54.61 0)
			(effects
				(font
					(size 1.27 1.27)
					(thickness 0.15)
				)
				(justify left)
			)
		)
		(property "Footprint" ""
			(at 244.475 60.96 0)
			(effects
				(font
					(size 1.27 1.27)
					(thickness 0.15)
				)
				(justify left bottom)
				(hide yes)
			)
		)
		(property "Datasheet" ""
			(at 244.475 66.04 0)
			(effects
				(font
					(size 1.27 1.27)
					(thickness 0.15)
				)
				(justify left bottom)
				(hide yes)
			)
		)
		(property "Description" ""
			(at 244.475 68.58 0)
			(effects
				(font
					(size 1.27 1.27)
				)
				(justify left bottom)
				(hide yes)
			)
		)
		(property "Author" "Antmicro"
			(at 244.475 60.96 0)
			(effects
				(font
					(size 1.27 1.27)
					(thickness 0.15)
				)
				(justify left bottom)
				(hide yes)
			)
		)
		(property "License" "Apache-2.0"
			(at 244.475 63.5 0)
			(effects
				(font
					(size 1.27 1.27)
					(thickness 0.15)
				)
				(justify left bottom)
				(hide yes)
			)
		)
		(pin "1"
		)
		(instances
			(project "sodimm-ddr5-tester"
				(path ""
					(reference "#PWR0333")
					(unit 1)
				)
			)
		)
	)
	(symbol
		(lib_id "antmicropower:GND")
		(at 236.22 211.455 0)
		(unit 1)
		(exclude_from_sim no)
		(in_bom yes)
		(on_board yes)
		(dnp no)
		(property "Reference" "#PWR0296"
			(at 236.22 217.805 0)
			(effects
				(font
					(size 1.27 1.27)
				)
				(hide yes)
			)
		)
		(property "Value" "GND"
			(at 234.188 215.392 0)
			(effects
				(font
					(size 1.27 1.27)
					(thickness 0.15)
				)
				(justify left)
			)
		)
		(property "Footprint" ""
			(at 245.11 219.075 0)
			(effects
				(font
					(size 1.27 1.27)
					(thickness 0.15)
				)
				(justify left bottom)
				(hide yes)
			)
		)
		(property "Datasheet" ""
			(at 245.11 224.155 0)
			(effects
				(font
					(size 1.27 1.27)
					(thickness 0.15)
				)
				(justify left bottom)
				(hide yes)
			)
		)
		(property "Description" ""
			(at 245.11 226.695 0)
			(effects
				(font
					(size 1.27 1.27)
				)
				(justify left bottom)
				(hide yes)
			)
		)
		(property "Author" "Antmicro"
			(at 245.11 219.075 0)
			(effects
				(font
					(size 1.27 1.27)
					(thickness 0.15)
				)
				(justify left bottom)
				(hide yes)
			)
		)
		(property "License" "Apache-2.0"
			(at 245.11 221.615 0)
			(effects
				(font
					(size 1.27 1.27)
					(thickness 0.15)
				)
				(justify left bottom)
				(hide yes)
			)
		)
		(pin "1"
		)
		(instances
			(project "sodimm-ddr5-tester"
				(path ""
					(reference "#PWR0296")
					(unit 1)
				)
			)
		)
	)
	(symbol
		(lib_id "antmicropower:GND")
		(at 386.715 184.785 0)
		(unit 1)
		(exclude_from_sim no)
		(in_bom yes)
		(on_board yes)
		(dnp no)
		(fields_autoplaced yes)
		(property "Reference" "#PWR0345"
			(at 386.715 191.135 0)
			(effects
				(font
					(size 1.27 1.27)
				)
				(hide yes)
			)
		)
		(property "Value" "GND"
			(at 388.62 186.055 0)
			(effects
				(font
					(size 1.27 1.27)
					(thickness 0.15)
				)
				(justify left)
			)
		)
		(property "Footprint" ""
			(at 395.605 192.405 0)
			(effects
				(font
					(size 1.27 1.27)
					(thickness 0.15)
				)
				(justify left bottom)
				(hide yes)
			)
		)
		(property "Datasheet" ""
			(at 395.605 197.485 0)
			(effects
				(font
					(size 1.27 1.27)
					(thickness 0.15)
				)
				(justify left bottom)
				(hide yes)
			)
		)
		(property "Description" ""
			(at 395.605 200.025 0)
			(effects
				(font
					(size 1.27 1.27)
				)
				(justify left bottom)
				(hide yes)
			)
		)
		(property "Author" "Antmicro"
			(at 395.605 192.405 0)
			(effects
				(font
					(size 1.27 1.27)
					(thickness 0.15)
				)
				(justify left bottom)
				(hide yes)
			)
		)
		(property "License" "Apache-2.0"
			(at 395.605 194.945 0)
			(effects
				(font
					(size 1.27 1.27)
					(thickness 0.15)
				)
				(justify left bottom)
				(hide yes)
			)
		)
		(pin "1"
		)
		(instances
			(project "sodimm-ddr5-tester"
				(path ""
					(reference "#PWR0345")
					(unit 1)
				)
			)
		)
	)
	(symbol
		(lib_id "antmicroTransistorsFETsMOSFETsSingle:SI7613DN-T1-GE3")
		(at 88.265 29.845 90)
		(unit 1)
		(exclude_from_sim no)
		(in_bom yes)
		(on_board yes)
		(dnp no)
		(fields_autoplaced yes)
		(property "Reference" "Q12"
			(at 85.725 16.5014 90)
			(effects
				(font
					(size 1.27 1.27)
				)
			)
		)
		(property "Value" "SI7613DN-T1-GE3"
			(at 85.725 19.0317 90)
			(effects
				(font
					(size 1.27 1.27)
					(thickness 0.15)
				)
			)
		)
		(property "Footprint" "antmicro-footprints:Vishay_PowerPAK_1212-8_Single"
			(at 86.995 14.605 0)
			(effects
				(font
					(size 1.27 1.27)
					(thickness 0.15)
				)
				(justify left bottom)
				(hide yes)
			)
		)
		(property "Datasheet" "https://www.vishay.com/docs/64809/si7613dn.pdf"
			(at 89.535 14.605 0)
			(effects
				(font
					(size 1.27 1.27)
					(thickness 0.15)
				)
				(justify left bottom)
				(hide yes)
			)
		)
		(property "Description" ""
			(at 88.265 29.845 0)
			(effects
				(font
					(size 1.27 1.27)
				)
			)
		)
		(property "MPN" "SI7613DN-T1-GE3"
			(at 93.345 14.605 0)
			(effects
				(font
					(size 1.27 1.27)
					(thickness 0.15)
				)
				(justify left bottom)
				(hide yes)
			)
		)
		(property "Manufacturer" "Vishay"
			(at 95.885 14.605 0)
			(effects
				(font
					(size 1.27 1.27)
					(thickness 0.15)
				)
				(justify left bottom)
				(hide yes)
			)
		)
		(property "Author" "Antmicro"
			(at 98.425 14.605 0)
			(effects
				(font
					(size 1.27 1.27)
					(thickness 0.15)
				)
				(justify left bottom)
				(hide yes)
			)
		)
		(property "License" "Apache-2.0"
			(at 100.965 14.605 0)
			(effects
				(font
					(size 1.27 1.27)
					(thickness 0.15)
				)
				(justify left bottom)
				(hide yes)
			)
		)
		(pin "1"
		)
		(pin "2"
		)
		(pin "3"
		)
		(pin "4"
		)
		(pin "5"
		)
		(instances
			(project "sodimm-ddr5-tester"
				(path ""
					(reference "Q12")
					(unit 1)
				)
			)
		)
	)
	(symbol
		(lib_id "antmicropower:+3V3")
		(at 300.355 116.84 0)
		(unit 1)
		(exclude_from_sim no)
		(in_bom yes)
		(on_board yes)
		(dnp no)
		(fields_autoplaced yes)
		(property "Reference" "#PWR0367"
			(at 300.355 120.65 0)
			(effects
				(font
					(size 1.27 1.27)
				)
				(hide yes)
			)
		)
		(property "Value" "+3V3"
			(at 297.18 114.3 0)
			(effects
				(font
					(size 1.27 1.27)
					(thickness 0.15)
				)
				(justify left bottom)
			)
		)
		(property "Footprint" ""
			(at 315.595 124.46 0)
			(effects
				(font
					(size 1.27 1.27)
					(thickness 0.15)
				)
				(justify left bottom)
				(hide yes)
			)
		)
		(property "Datasheet" ""
			(at 315.595 127 0)
			(effects
				(font
					(size 1.27 1.27)
					(thickness 0.15)
				)
				(justify left bottom)
				(hide yes)
			)
		)
		(property "Description" ""
			(at 300.355 116.84 0)
			(effects
				(font
					(size 1.27 1.27)
				)
			)
		)
		(property "Author" "Antmicro"
			(at 315.595 119.38 0)
			(effects
				(font
					(size 1.27 1.27)
					(thickness 0.15)
				)
				(justify left bottom)
				(hide yes)
			)
		)
		(property "License" "Apache-2.0"
			(at 315.595 121.92 0)
			(effects
				(font
					(size 1.27 1.27)
					(thickness 0.15)
				)
				(justify left bottom)
				(hide yes)
			)
		)
		(pin "1"
		)
		(instances
			(project "sodimm-ddr5-tester"
				(path ""
					(reference "#PWR0367")
					(unit 1)
				)
			)
		)
	)
	(symbol
		(lib_id "antmicropower:PWR_FLAG")
		(at 317.5 212.09 0)
		(unit 1)
		(exclude_from_sim no)
		(in_bom yes)
		(on_board yes)
		(dnp no)
		(fields_autoplaced yes)
		(property "Reference" "#FLG0114"
			(at 317.5 210.185 0)
			(effects
				(font
					(size 1.27 1.27)
				)
				(hide yes)
			)
		)
		(property "Value" "PWR_FLAG"
			(at 317.5 208.5142 0)
			(effects
				(font
					(size 1.27 1.27)
				)
			)
		)
		(property "Footprint" ""
			(at 317.5 212.09 0)
			(effects
				(font
					(size 1.27 1.27)
				)
				(hide yes)
			)
		)
		(property "Datasheet" ""
			(at 317.5 212.09 0)
			(effects
				(font
					(size 1.27 1.27)
				)
				(hide yes)
			)
		)
		(property "Description" ""
			(at 317.5 212.09 0)
			(effects
				(font
					(size 1.27 1.27)
				)
			)
		)
		(pin "1"
		)
		(instances
			(project "sodimm-ddr5-tester"
				(path ""
					(reference "#FLG0114")
					(unit 1)
				)
			)
		)
	)
	(symbol
		(lib_id "antmicropower:GND")
		(at 185.42 279.4 0)
		(unit 1)
		(exclude_from_sim no)
		(in_bom yes)
		(on_board yes)
		(dnp no)
		(property "Reference" "#PWR042"
			(at 185.42 285.75 0)
			(effects
				(font
					(size 1.27 1.27)
				)
				(hide yes)
			)
		)
		(property "Value" "GND"
			(at 183.642 283.464 0)
			(effects
				(font
					(size 1.27 1.27)
					(thickness 0.15)
				)
				(justify left)
			)
		)
		(property "Footprint" ""
			(at 194.31 287.02 0)
			(effects
				(font
					(size 1.27 1.27)
					(thickness 0.15)
				)
				(justify left bottom)
				(hide yes)
			)
		)
		(property "Datasheet" ""
			(at 194.31 292.1 0)
			(effects
				(font
					(size 1.27 1.27)
					(thickness 0.15)
				)
				(justify left bottom)
				(hide yes)
			)
		)
		(property "Description" ""
			(at 194.31 294.64 0)
			(effects
				(font
					(size 1.27 1.27)
				)
				(justify left bottom)
				(hide yes)
			)
		)
		(property "Author" "Antmicro"
			(at 194.31 287.02 0)
			(effects
				(font
					(size 1.27 1.27)
					(thickness 0.15)
				)
				(justify left bottom)
				(hide yes)
			)
		)
		(property "License" "Apache-2.0"
			(at 194.31 289.56 0)
			(effects
				(font
					(size 1.27 1.27)
					(thickness 0.15)
				)
				(justify left bottom)
				(hide yes)
			)
		)
		(pin "1"
		)
		(instances
			(project "sodimm-ddr5-tester"
				(path ""
					(reference "#PWR042")
					(unit 1)
				)
			)
		)
	)
	(symbol
		(lib_id "antmicroResistors0402:R_0R_0402")
		(at 356.87 208.28 90)
		(unit 1)
		(exclude_from_sim no)
		(in_bom yes)
		(on_board yes)
		(dnp no)
		(fields_autoplaced yes)
		(property "Reference" "R157"
			(at 359.41 204.4699 90)
			(effects
				(font
					(size 1.27 1.27)
				)
				(justify right)
			)
		)
		(property "Value" "R_0R_0402"
			(at 369.57 187.96 0)
			(effects
				(font
					(size 1.27 1.27)
					(thickness 0.15)
				)
				(justify left bottom)
				(hide yes)
			)
		)
		(property "Footprint" "antmicro-footprints:R_0402_1005Metric"
			(at 372.11 187.96 0)
			(effects
				(font
					(size 1.27 1.27)
					(thickness 0.15)
				)
				(justify left bottom)
				(hide yes)
			)
		)
		(property "Datasheet" "https://industrial.panasonic.com/cdbs/www-data/pdf/RDA0000/AOA0000C301.pdf"
			(at 374.65 187.96 0)
			(effects
				(font
					(size 1.27 1.27)
					(thickness 0.15)
				)
				(justify left bottom)
				(hide yes)
			)
		)
		(property "Description" ""
			(at 356.87 208.28 0)
			(effects
				(font
					(size 1.27 1.27)
				)
			)
		)
		(property "Manufacturer" "Panasonic"
			(at 379.73 187.96 0)
			(effects
				(font
					(size 1.27 1.27)
					(thickness 0.15)
				)
				(justify left bottom)
				(hide yes)
			)
		)
		(property "MPN" "ERJ2GE0R00X"
			(at 377.19 187.96 0)
			(effects
				(font
					(size 1.27 1.27)
					(thickness 0.15)
				)
				(justify left bottom)
				(hide yes)
			)
		)
		(property "Val" "0R"
			(at 359.41 207.0099 90)
			(effects
				(font
					(size 1.27 1.27)
					(thickness 0.15)
				)
				(justify right)
			)
		)
		(property "License" "Apache-2.0"
			(at 382.27 187.96 0)
			(effects
				(font
					(size 1.27 1.27)
					(thickness 0.15)
				)
				(justify left bottom)
				(hide yes)
			)
		)
		(property "Author" "Antmicro"
			(at 384.81 187.96 0)
			(effects
				(font
					(size 1.27 1.27)
					(thickness 0.15)
				)
				(justify left bottom)
				(hide yes)
			)
		)
		(property "Tolerance" "~"
			(at 367.03 187.96 0)
			(effects
				(font
					(size 1.27 1.27)
				)
				(justify left bottom)
				(hide yes)
			)
		)
		(property "Current" "1A"
			(at 359.41 208.2799 90)
			(effects
				(font
					(size 1.27 1.27)
					(thickness 0.15)
				)
				(justify right)
				(hide yes)
			)
		)
		(pin "1"
		)
		(pin "2"
		)
		(instances
			(project "sodimm-ddr5-tester"
				(path ""
					(reference "R157")
					(unit 1)
				)
			)
		)
	)
	(symbol
		(lib_id "antmicropower:PWR_FLAG")
		(at 316.865 196.85 0)
		(unit 1)
		(exclude_from_sim no)
		(in_bom yes)
		(on_board yes)
		(dnp no)
		(fields_autoplaced yes)
		(property "Reference" "#FLG0113"
			(at 316.865 194.945 0)
			(effects
				(font
					(size 1.27 1.27)
				)
				(hide yes)
			)
		)
		(property "Value" "PWR_FLAG"
			(at 316.865 193.2742 0)
			(effects
				(font
					(size 1.27 1.27)
				)
			)
		)
		(property "Footprint" ""
			(at 316.865 196.85 0)
			(effects
				(font
					(size 1.27 1.27)
				)
				(hide yes)
			)
		)
		(property "Datasheet" ""
			(at 316.865 196.85 0)
			(effects
				(font
					(size 1.27 1.27)
				)
				(hide yes)
			)
		)
		(property "Description" ""
			(at 316.865 196.85 0)
			(effects
				(font
					(size 1.27 1.27)
				)
			)
		)
		(pin "1"
		)
		(instances
			(project "sodimm-ddr5-tester"
				(path ""
					(reference "#FLG0113")
					(unit 1)
				)
			)
		)
	)
	(symbol
		(lib_id "antmicroPMICORControllersIdealDiodes:LTC4412IS6")
		(at 67.945 32.385 0)
		(unit 1)
		(exclude_from_sim no)
		(in_bom yes)
		(on_board yes)
		(dnp no)
		(property "Reference" "U17"
			(at 76.835 26.035 0)
			(effects
				(font
					(size 1.27 1.27)
				)
			)
		)
		(property "Value" "LTC4412IS6"
			(at 76.835 28.575 0)
			(effects
				(font
					(size 1.27 1.27)
					(thickness 0.15)
				)
			)
		)
		(property "Footprint" "antmicro-footprints:SOT-23-6"
			(at 99.695 40.005 0)
			(effects
				(font
					(size 1.27 1.27)
					(thickness 0.15)
				)
				(justify left bottom)
				(hide yes)
			)
		)
		(property "Datasheet" "https://www.mouser.com/datasheet/2/308/NCV8187_D-1813214.pdf"
			(at 99.695 42.545 0)
			(effects
				(font
					(size 1.27 1.27)
					(thickness 0.15)
				)
				(justify left bottom)
				(hide yes)
			)
		)
		(property "Description" ""
			(at 67.945 32.385 0)
			(effects
				(font
					(size 1.27 1.27)
				)
			)
		)
		(property "MPN" "LTC4412IS6#TRMPBF"
			(at 99.695 45.085 0)
			(effects
				(font
					(size 1.27 1.27)
					(thickness 0.15)
				)
				(justify left bottom)
				(hide yes)
			)
		)
		(property "Manufacturer" "Analog Devices"
			(at 99.695 47.625 0)
			(effects
				(font
					(size 1.27 1.27)
					(thickness 0.15)
				)
				(justify left bottom)
				(hide yes)
			)
		)
		(property "Author" "Antmicro"
			(at 99.695 50.165 0)
			(effects
				(font
					(size 1.27 1.27)
					(thickness 0.15)
				)
				(justify left bottom)
				(hide yes)
			)
		)
		(property "License" "Apache-2.0"
			(at 99.695 52.705 0)
			(effects
				(font
					(size 1.27 1.27)
					(thickness 0.15)
				)
				(justify left bottom)
				(hide yes)
			)
		)
		(pin "1"
		)
		(pin "2"
		)
		(pin "3"
		)
		(pin "4"
		)
		(pin "5"
		)
		(pin "6"
		)
		(instances
			(project "sodimm-ddr5-tester"
				(path ""
					(reference "U17")
					(unit 1)
				)
			)
		)
	)
	(symbol
		(lib_id "antmicroShuntsJumpers:Net-Tie_P0.127mm")
		(at 110.49 184.15 90)
		(unit 1)
		(exclude_from_sim no)
		(in_bom no)
		(on_board yes)
		(dnp no)
		(fields_autoplaced yes)
		(property "Reference" "NT2"
			(at 109.22 184.15 0)
			(effects
				(font
					(size 1.27 1.27)
				)
				(hide yes)
			)
		)
		(property "Value" "Net-Tie_P0.127mm"
			(at 118.11 162.56 0)
			(effects
				(font
					(size 1.27 1.27)
					(thickness 0.15)
				)
				(justify left bottom)
				(hide yes)
			)
		)
		(property "Footprint" "antmicro-footprints:NetTie-2_SMD_Pad0.127mm"
			(at 123.19 162.56 0)
			(effects
				(font
					(size 1.27 1.27)
					(thickness 0.15)
				)
				(justify left bottom)
				(hide yes)
			)
		)
		(property "Datasheet" ""
			(at 125.73 162.56 0)
			(effects
				(font
					(size 1.27 1.27)
					(thickness 0.15)
				)
				(justify left bottom)
				(hide yes)
			)
		)
		(property "Description" ""
			(at 110.49 184.15 0)
			(effects
				(font
					(size 1.27 1.27)
				)
			)
		)
		(property "MPN" ""
			(at 120.65 162.56 0)
			(effects
				(font
					(size 1.27 1.27)
					(thickness 0.15)
				)
				(justify left bottom)
			)
		)
		(property "Manufacturer" ""
			(at 128.27 162.56 0)
			(effects
				(font
					(size 1.27 1.27)
					(thickness 0.15)
				)
				(justify left bottom)
				(hide yes)
			)
		)
		(property "Author" "Antmicro"
			(at 130.81 162.56 0)
			(effects
				(font
					(size 1.27 1.27)
					(thickness 0.15)
				)
				(justify left bottom)
				(hide yes)
			)
		)
		(property "License" "Apache-2.0"
			(at 133.35 162.56 0)
			(effects
				(font
					(size 1.27 1.27)
					(thickness 0.15)
				)
				(justify left bottom)
				(hide yes)
			)
		)
		(pin "1"
		)
		(pin "2"
		)
		(instances
			(project "sodimm-ddr5-tester"
				(path ""
					(reference "NT2")
					(unit 1)
				)
			)
		)
	)
	(symbol
		(lib_id "antmicropower:GND")
		(at 109.22 257.81 0)
		(mirror y)
		(unit 1)
		(exclude_from_sim no)
		(in_bom yes)
		(on_board yes)
		(dnp no)
		(property "Reference" "#PWR0373"
			(at 109.22 264.16 0)
			(effects
				(font
					(size 1.27 1.27)
				)
				(hide yes)
			)
		)
		(property "Value" "GND"
			(at 107.188 262.128 0)
			(effects
				(font
					(size 1.27 1.27)
					(thickness 0.15)
				)
				(justify right)
			)
		)
		(property "Footprint" ""
			(at 100.33 265.43 0)
			(effects
				(font
					(size 1.27 1.27)
					(thickness 0.15)
				)
				(justify left bottom)
				(hide yes)
			)
		)
		(property "Datasheet" ""
			(at 100.33 270.51 0)
			(effects
				(font
					(size 1.27 1.27)
					(thickness 0.15)
				)
				(justify left bottom)
				(hide yes)
			)
		)
		(property "Description" ""
			(at 100.33 273.05 0)
			(effects
				(font
					(size 1.27 1.27)
				)
				(justify left bottom)
				(hide yes)
			)
		)
		(property "Author" "Antmicro"
			(at 100.33 265.43 0)
			(effects
				(font
					(size 1.27 1.27)
					(thickness 0.15)
				)
				(justify left bottom)
				(hide yes)
			)
		)
		(property "License" "Apache-2.0"
			(at 100.33 267.97 0)
			(effects
				(font
					(size 1.27 1.27)
					(thickness 0.15)
				)
				(justify left bottom)
				(hide yes)
			)
		)
		(pin "1"
		)
		(instances
			(project "sodimm-ddr5-tester"
				(path ""
					(reference "#PWR0373")
					(unit 1)
				)
			)
		)
	)
	(symbol
		(lib_id "antmicroCapacitors0402:C_100n_0402")
		(at 58.42 40.005 90)
		(unit 1)
		(exclude_from_sim no)
		(in_bom yes)
		(on_board yes)
		(dnp no)
		(property "Reference" "C175"
			(at 60.96 36.1885 90)
			(effects
				(font
					(size 1.27 1.27)
				)
				(justify right)
			)
		)
		(property "Value" "C_100n_0402"
			(at 68.58 19.685 0)
			(effects
				(font
					(size 1.27 1.27)
					(thickness 0.15)
				)
				(justify left bottom)
				(hide yes)
			)
		)
		(property "Footprint" "antmicro-footprints:C_0402_1005Metric"
			(at 71.12 19.685 0)
			(effects
				(font
					(size 1.27 1.27)
					(thickness 0.15)
				)
				(justify left bottom)
				(hide yes)
			)
		)
		(property "Datasheet" "https://www.murata.com/products/productdetail?partno=GRM155R61H104KE14%23"
			(at 73.66 19.685 0)
			(effects
				(font
					(size 1.27 1.27)
					(thickness 0.15)
				)
				(justify left bottom)
				(hide yes)
			)
		)
		(property "Description" ""
			(at 58.42 40.005 0)
			(effects
				(font
					(size 1.27 1.27)
				)
			)
		)
		(property "Manufacturer" "Murata"
			(at 78.74 19.685 0)
			(effects
				(font
					(size 1.27 1.27)
					(thickness 0.15)
				)
				(justify left bottom)
				(hide yes)
			)
		)
		(property "MPN" "GRM155R61H104KE14D"
			(at 76.2 19.685 0)
			(effects
				(font
					(size 1.27 1.27)
					(thickness 0.15)
				)
				(justify left bottom)
				(hide yes)
			)
		)
		(property "Val" "100n"
			(at 60.96 38.7285 90)
			(effects
				(font
					(size 1.27 1.27)
					(thickness 0.15)
				)
				(justify right)
			)
		)
		(property "License" "Apache-2.0"
			(at 81.28 19.685 0)
			(effects
				(font
					(size 1.27 1.27)
					(thickness 0.15)
				)
				(justify left bottom)
				(hide yes)
			)
		)
		(property "Author" "Antmicro"
			(at 83.82 19.685 0)
			(effects
				(font
					(size 1.27 1.27)
					(thickness 0.15)
				)
				(justify left bottom)
				(hide yes)
			)
		)
		(property "Voltage" "50V"
			(at 86.36 19.685 0)
			(effects
				(font
					(size 1.27 1.27)
				)
				(justify left bottom)
				(hide yes)
			)
		)
		(property "Dielectric" "X5R"
			(at 88.9 19.685 0)
			(effects
				(font
					(size 1.27 1.27)
				)
				(justify left bottom)
				(hide yes)
			)
		)
		(pin "1"
		)
		(pin "2"
		)
		(instances
			(project "sodimm-ddr5-tester"
				(path ""
					(reference "C175")
					(unit 1)
				)
			)
		)
	)
	(symbol
		(lib_id "antmicroResistors0402:R_0R_0402")
		(at 386.715 182.245 90)
		(unit 1)
		(exclude_from_sim no)
		(in_bom no)
		(on_board yes)
		(dnp yes)
		(property "Reference" "R167"
			(at 388.62 178.435 90)
			(effects
				(font
					(size 1.27 1.27)
				)
				(justify right)
			)
		)
		(property "Value" "R_0R_0402"
			(at 399.415 161.925 0)
			(effects
				(font
					(size 1.27 1.27)
					(thickness 0.15)
				)
				(justify left bottom)
				(hide yes)
			)
		)
		(property "Footprint" "antmicro-footprints:R_0402_1005Metric"
			(at 401.955 161.925 0)
			(effects
				(font
					(size 1.27 1.27)
					(thickness 0.15)
				)
				(justify left bottom)
				(hide yes)
			)
		)
		(property "Datasheet" "https://industrial.panasonic.com/cdbs/www-data/pdf/RDA0000/AOA0000C301.pdf"
			(at 404.495 161.925 0)
			(effects
				(font
					(size 1.27 1.27)
					(thickness 0.15)
				)
				(justify left bottom)
				(hide yes)
			)
		)
		(property "Description" ""
			(at 386.715 182.245 0)
			(effects
				(font
					(size 1.27 1.27)
				)
			)
		)
		(property "Manufacturer" "Panasonic"
			(at 409.575 161.925 0)
			(effects
				(font
					(size 1.27 1.27)
					(thickness 0.15)
				)
				(justify left bottom)
				(hide yes)
			)
		)
		(property "MPN" "ERJ2GE0R00X"
			(at 407.035 161.925 0)
			(effects
				(font
					(size 1.27 1.27)
					(thickness 0.15)
				)
				(justify left bottom)
				(hide yes)
			)
		)
		(property "Val" "0R"
			(at 388.62 180.975 90)
			(effects
				(font
					(size 1.27 1.27)
					(thickness 0.15)
				)
				(justify right)
			)
		)
		(property "License" "Apache-2.0"
			(at 412.115 161.925 0)
			(effects
				(font
					(size 1.27 1.27)
					(thickness 0.15)
				)
				(justify left bottom)
				(hide yes)
			)
		)
		(property "Author" "Antmicro"
			(at 414.655 161.925 0)
			(effects
				(font
					(size 1.27 1.27)
					(thickness 0.15)
				)
				(justify left bottom)
				(hide yes)
			)
		)
		(property "Tolerance" "~"
			(at 396.875 161.925 0)
			(effects
				(font
					(size 1.27 1.27)
				)
				(justify left bottom)
				(hide yes)
			)
		)
		(property "Current" "1A"
			(at 388.62 183.5149 90)
			(effects
				(font
					(size 1.27 1.27)
					(thickness 0.15)
				)
				(justify right)
				(hide yes)
			)
		)
		(pin "1"
		)
		(pin "2"
		)
		(instances
			(project "sodimm-ddr5-tester"
				(path ""
					(reference "R167")
					(unit 1)
				)
			)
		)
	)
	(symbol
		(lib_id "antmicroResistors0402:R_4k7_0402")
		(at 28.575 259.08 90)
		(unit 1)
		(exclude_from_sim no)
		(in_bom yes)
		(on_board yes)
		(dnp no)
		(fields_autoplaced yes)
		(property "Reference" "R180"
			(at 31.115 255.2699 90)
			(effects
				(font
					(size 1.27 1.27)
				)
				(justify right)
			)
		)
		(property "Value" "R_4k7_0402"
			(at 41.275 238.76 0)
			(effects
				(font
					(size 1.27 1.27)
					(thickness 0.15)
				)
				(justify left bottom)
				(hide yes)
			)
		)
		(property "Footprint" "antmicro-footprints:R_0402_1005Metric"
			(at 43.815 238.76 0)
			(effects
				(font
					(size 1.27 1.27)
					(thickness 0.15)
				)
				(justify left bottom)
				(hide yes)
			)
		)
		(property "Datasheet" "https://www.bourns.com/docs/product-datasheets/cr.pdf"
			(at 46.355 238.76 0)
			(effects
				(font
					(size 1.27 1.27)
					(thickness 0.15)
				)
				(justify left bottom)
				(hide yes)
			)
		)
		(property "Description" ""
			(at 28.575 259.08 0)
			(effects
				(font
					(size 1.27 1.27)
				)
			)
		)
		(property "Manufacturer" "Bourns"
			(at 51.435 238.76 0)
			(effects
				(font
					(size 1.27 1.27)
					(thickness 0.15)
				)
				(justify left bottom)
				(hide yes)
			)
		)
		(property "MPN" "CR0402-FX-4701GLF"
			(at 48.895 238.76 0)
			(effects
				(font
					(size 1.27 1.27)
					(thickness 0.15)
				)
				(justify left bottom)
				(hide yes)
			)
		)
		(property "Val" "4k7"
			(at 31.115 257.8099 90)
			(effects
				(font
					(size 1.27 1.27)
					(thickness 0.15)
				)
				(justify right)
			)
		)
		(property "License" "Apache-2.0"
			(at 53.975 238.76 0)
			(effects
				(font
					(size 1.27 1.27)
					(thickness 0.15)
				)
				(justify left bottom)
				(hide yes)
			)
		)
		(property "Author" "Antmicro"
			(at 56.515 238.76 0)
			(effects
				(font
					(size 1.27 1.27)
					(thickness 0.15)
				)
				(justify left bottom)
				(hide yes)
			)
		)
		(property "Tolerance" "1%"
			(at 38.735 238.76 0)
			(effects
				(font
					(size 1.27 1.27)
				)
				(justify left bottom)
				(hide yes)
			)
		)
		(pin "1"
		)
		(pin "2"
		)
		(instances
			(project "sodimm-ddr5-tester"
				(path ""
					(reference "R180")
					(unit 1)
				)
			)
		)
	)
	(symbol
		(lib_id "antmicropower:GND")
		(at 285.75 133.985 0)
		(unit 1)
		(exclude_from_sim no)
		(in_bom yes)
		(on_board yes)
		(dnp no)
		(fields_autoplaced yes)
		(property "Reference" "#PWR0361"
			(at 285.75 140.335 0)
			(effects
				(font
					(size 1.27 1.27)
				)
				(hide yes)
			)
		)
		(property "Value" "GND"
			(at 288.29 135.255 0)
			(effects
				(font
					(size 1.27 1.27)
					(thickness 0.15)
				)
				(justify left)
			)
		)
		(property "Footprint" ""
			(at 294.64 141.605 0)
			(effects
				(font
					(size 1.27 1.27)
					(thickness 0.15)
				)
				(justify left bottom)
				(hide yes)
			)
		)
		(property "Datasheet" ""
			(at 294.64 146.685 0)
			(effects
				(font
					(size 1.27 1.27)
					(thickness 0.15)
				)
				(justify left bottom)
				(hide yes)
			)
		)
		(property "Description" ""
			(at 294.64 149.225 0)
			(effects
				(font
					(size 1.27 1.27)
				)
				(justify left bottom)
				(hide yes)
			)
		)
		(property "Author" "Antmicro"
			(at 294.64 141.605 0)
			(effects
				(font
					(size 1.27 1.27)
					(thickness 0.15)
				)
				(justify left bottom)
				(hide yes)
			)
		)
		(property "License" "Apache-2.0"
			(at 294.64 144.145 0)
			(effects
				(font
					(size 1.27 1.27)
					(thickness 0.15)
				)
				(justify left bottom)
				(hide yes)
			)
		)
		(pin "1"
		)
		(instances
			(project "sodimm-ddr5-tester"
				(path ""
					(reference "#PWR0361")
					(unit 1)
				)
			)
		)
	)
	(symbol
		(lib_id "antmicroShuntsJumpers:Net-Tie_P0.127mm")
		(at 304.8 162.56 90)
		(unit 1)
		(exclude_from_sim no)
		(in_bom no)
		(on_board yes)
		(dnp no)
		(fields_autoplaced yes)
		(property "Reference" "NT5"
			(at 303.53 162.56 0)
			(effects
				(font
					(size 1.27 1.27)
				)
				(hide yes)
			)
		)
		(property "Value" "Net-Tie_P0.127mm"
			(at 312.42 140.97 0)
			(effects
				(font
					(size 1.27 1.27)
					(thickness 0.15)
				)
				(justify left bottom)
				(hide yes)
			)
		)
		(property "Footprint" "antmicro-footprints:NetTie-2_SMD_Pad0.127mm"
			(at 317.5 140.97 0)
			(effects
				(font
					(size 1.27 1.27)
					(thickness 0.15)
				)
				(justify left bottom)
				(hide yes)
			)
		)
		(property "Datasheet" ""
			(at 320.04 140.97 0)
			(effects
				(font
					(size 1.27 1.27)
					(thickness 0.15)
				)
				(justify left bottom)
				(hide yes)
			)
		)
		(property "Description" ""
			(at 304.8 162.56 0)
			(effects
				(font
					(size 1.27 1.27)
				)
			)
		)
		(property "MPN" ""
			(at 314.96 140.97 0)
			(effects
				(font
					(size 1.27 1.27)
					(thickness 0.15)
				)
				(justify left bottom)
			)
		)
		(property "Manufacturer" ""
			(at 322.58 140.97 0)
			(effects
				(font
					(size 1.27 1.27)
					(thickness 0.15)
				)
				(justify left bottom)
				(hide yes)
			)
		)
		(property "Author" "Antmicro"
			(at 325.12 140.97 0)
			(effects
				(font
					(size 1.27 1.27)
					(thickness 0.15)
				)
				(justify left bottom)
				(hide yes)
			)
		)
		(property "License" "Apache-2.0"
			(at 327.66 140.97 0)
			(effects
				(font
					(size 1.27 1.27)
					(thickness 0.15)
				)
				(justify left bottom)
				(hide yes)
			)
		)
		(pin "1"
		)
		(pin "2"
		)
		(instances
			(project "sodimm-ddr5-tester"
				(path ""
					(reference "NT5")
					(unit 1)
				)
			)
		)
	)
	(symbol
		(lib_id "antmicroTestPoints:TP_1mm_SMD")
		(at 267.97 281.94 0)
		(unit 1)
		(exclude_from_sim no)
		(in_bom yes)
		(on_board yes)
		(dnp no)
		(property "Reference" "TP57"
			(at 274.828 281.94 0)
			(effects
				(font
					(size 1.27 1.27)
				)
			)
		)
		(property "Value" "TP_1mm_SMD"
			(at 283.21 289.56 0)
			(effects
				(font
					(size 1.27 1.27)
					(thickness 0.15)
				)
				(justify left bottom)
				(hide yes)
			)
		)
		(property "Footprint" "antmicro-footprints:TP_SMD_1mm"
			(at 283.21 292.1 0)
			(effects
				(font
					(size 1.27 1.27)
					(thickness 0.15)
				)
				(justify left bottom)
				(hide yes)
			)
		)
		(property "Datasheet" ""
			(at 283.21 294.64 0)
			(effects
				(font
					(size 1.27 1.27)
					(thickness 0.15)
				)
				(justify left bottom)
				(hide yes)
			)
		)
		(property "Description" ""
			(at 267.97 281.94 0)
			(effects
				(font
					(size 1.27 1.27)
				)
			)
		)
		(property "MPN" ""
			(at 267.97 281.94 0)
			(effects
				(font
					(size 1.27 1.27)
				)
				(hide yes)
			)
		)
		(property "Manufacturer" ""
			(at 267.97 281.94 0)
			(effects
				(font
					(size 1.27 1.27)
				)
				(hide yes)
			)
		)
		(property "Author" "Antmicro"
			(at 283.21 297.18 0)
			(effects
				(font
					(size 1.27 1.27)
					(thickness 0.15)
				)
				(justify left bottom)
				(hide yes)
			)
		)
		(property "License" "Apache-2.0"
			(at 283.21 299.72 0)
			(effects
				(font
					(size 1.27 1.27)
					(thickness 0.15)
				)
				(justify left bottom)
				(hide yes)
			)
		)
		(pin "1"
		)
		(instances
			(project "sodimm-ddr5-tester"
				(path ""
					(reference "TP57")
					(unit 1)
				)
			)
		)
	)
	(symbol
		(lib_id "antmicroCapacitors0402:C_100n_0402")
		(at 41.91 102.87 90)
		(unit 1)
		(exclude_from_sim no)
		(in_bom yes)
		(on_board yes)
		(dnp no)
		(property "Reference" "C204"
			(at 42.545 98.425 90)
			(effects
				(font
					(size 1.27 1.27)
				)
				(justify right)
			)
		)
		(property "Value" "C_100n_0402"
			(at 52.07 82.55 0)
			(effects
				(font
					(size 1.27 1.27)
					(thickness 0.15)
				)
				(justify left bottom)
				(hide yes)
			)
		)
		(property "Footprint" "antmicro-footprints:C_0402_1005Metric"
			(at 54.61 82.55 0)
			(effects
				(font
					(size 1.27 1.27)
					(thickness 0.15)
				)
				(justify left bottom)
				(hide yes)
			)
		)
		(property "Datasheet" "https://www.murata.com/products/productdetail?partno=GRM155R61H104KE14%23"
			(at 57.15 82.55 0)
			(effects
				(font
					(size 1.27 1.27)
					(thickness 0.15)
				)
				(justify left bottom)
				(hide yes)
			)
		)
		(property "Description" ""
			(at 41.91 102.87 0)
			(effects
				(font
					(size 1.27 1.27)
				)
			)
		)
		(property "Manufacturer" "Murata"
			(at 62.23 82.55 0)
			(effects
				(font
					(size 1.27 1.27)
					(thickness 0.15)
				)
				(justify left bottom)
				(hide yes)
			)
		)
		(property "MPN" "GRM155R61H104KE14D"
			(at 59.69 82.55 0)
			(effects
				(font
					(size 1.27 1.27)
					(thickness 0.15)
				)
				(justify left bottom)
				(hide yes)
			)
		)
		(property "Val" "100n"
			(at 42.545 102.235 90)
			(effects
				(font
					(size 1.27 1.27)
					(thickness 0.15)
				)
				(justify right)
			)
		)
		(property "License" "Apache-2.0"
			(at 64.77 82.55 0)
			(effects
				(font
					(size 1.27 1.27)
					(thickness 0.15)
				)
				(justify left bottom)
				(hide yes)
			)
		)
		(property "Author" "Antmicro"
			(at 67.31 82.55 0)
			(effects
				(font
					(size 1.27 1.27)
					(thickness 0.15)
				)
				(justify left bottom)
				(hide yes)
			)
		)
		(property "Voltage" "50V"
			(at 69.85 82.55 0)
			(effects
				(font
					(size 1.27 1.27)
				)
				(justify left bottom)
				(hide yes)
			)
		)
		(property "Dielectric" "X5R"
			(at 72.39 82.55 0)
			(effects
				(font
					(size 1.27 1.27)
				)
				(justify left bottom)
				(hide yes)
			)
		)
		(pin "1"
		)
		(pin "2"
		)
		(instances
			(project "sodimm-ddr5-tester"
				(path ""
					(reference "C204")
					(unit 1)
				)
			)
		)
	)
	(symbol
		(lib_id "antmicropower:+3V3_AON")
		(at 113.03 276.86 0)
		(unit 1)
		(exclude_from_sim no)
		(in_bom yes)
		(on_board yes)
		(dnp no)
		(property "Reference" "#PWR022"
			(at 113.03 280.67 0)
			(effects
				(font
					(size 1.27 1.27)
				)
				(hide yes)
			)
		)
		(property "Value" "+3V3_AON"
			(at 113.03 273.05 0)
			(effects
				(font
					(size 1.27 1.27)
				)
			)
		)
		(property "Footprint" ""
			(at 113.03 276.86 0)
			(effects
				(font
					(size 1.27 1.27)
				)
				(hide yes)
			)
		)
		(property "Datasheet" ""
			(at 113.03 276.86 0)
			(effects
				(font
					(size 1.27 1.27)
				)
				(hide yes)
			)
		)
		(property "Description" ""
			(at 113.03 276.86 0)
			(effects
				(font
					(size 1.27 1.27)
				)
			)
		)
		(pin "1"
		)
		(instances
			(project "sodimm-ddr5-tester"
				(path ""
					(reference "#PWR022")
					(unit 1)
				)
			)
		)
	)
	(symbol
		(lib_id "antmicroTestPoints:TP_1mm_SMD")
		(at 170.18 278.13 270)
		(unit 1)
		(exclude_from_sim no)
		(in_bom yes)
		(on_board yes)
		(dnp no)
		(property "Reference" "TP35"
			(at 170.18 283.1028 90)
			(effects
				(font
					(size 1.27 1.27)
				)
			)
		)
		(property "Value" "TP_1mm_SMD"
			(at 162.56 293.37 0)
			(effects
				(font
					(size 1.27 1.27)
					(thickness 0.15)
				)
				(justify left bottom)
				(hide yes)
			)
		)
		(property "Footprint" "antmicro-footprints:TP_SMD_1mm"
			(at 160.02 293.37 0)
			(effects
				(font
					(size 1.27 1.27)
					(thickness 0.15)
				)
				(justify left bottom)
				(hide yes)
			)
		)
		(property "Datasheet" ""
			(at 157.48 293.37 0)
			(effects
				(font
					(size 1.27 1.27)
					(thickness 0.15)
				)
				(justify left bottom)
				(hide yes)
			)
		)
		(property "Description" ""
			(at 170.18 278.13 0)
			(effects
				(font
					(size 1.27 1.27)
				)
			)
		)
		(property "MPN" ""
			(at 170.18 278.13 0)
			(effects
				(font
					(size 1.27 1.27)
				)
				(hide yes)
			)
		)
		(property "Manufacturer" ""
			(at 170.18 278.13 0)
			(effects
				(font
					(size 1.27 1.27)
				)
				(hide yes)
			)
		)
		(property "Author" "Antmicro"
			(at 154.94 293.37 0)
			(effects
				(font
					(size 1.27 1.27)
					(thickness 0.15)
				)
				(justify left bottom)
				(hide yes)
			)
		)
		(property "License" "Apache-2.0"
			(at 152.4 293.37 0)
			(effects
				(font
					(size 1.27 1.27)
					(thickness 0.15)
				)
				(justify left bottom)
				(hide yes)
			)
		)
		(pin "1"
		)
		(instances
			(project "sodimm-ddr5-tester"
				(path ""
					(reference "TP35")
					(unit 1)
				)
			)
		)
	)
	(symbol
		(lib_id "antmicroCapacitors0603:C_22u_0603")
		(at 86.995 224.155 90)
		(unit 1)
		(exclude_from_sim no)
		(in_bom yes)
		(on_board yes)
		(dnp no)
		(fields_autoplaced yes)
		(property "Reference" "C189"
			(at 89.3191 220.778 90)
			(effects
				(font
					(size 1.27 1.27)
				)
				(justify right)
			)
		)
		(property "Value" "C_22u_0603"
			(at 97.155 203.835 0)
			(effects
				(font
					(size 1.27 1.27)
					(thickness 0.15)
				)
				(justify left bottom)
				(hide yes)
			)
		)
		(property "Footprint" "antmicro-footprints:C_0603_1608Metric"
			(at 99.695 203.835 0)
			(effects
				(font
					(size 1.27 1.27)
					(thickness 0.15)
				)
				(justify left bottom)
				(hide yes)
			)
		)
		(property "Datasheet" "https://www.murata.com/products/productdetail?partno=GRM188R60J226MEA0%23"
			(at 102.235 203.835 0)
			(effects
				(font
					(size 1.27 1.27)
					(thickness 0.15)
				)
				(justify left bottom)
				(hide yes)
			)
		)
		(property "Description" ""
			(at 86.995 224.155 0)
			(effects
				(font
					(size 1.27 1.27)
				)
			)
		)
		(property "Manufacturer" "Murata"
			(at 107.315 203.835 0)
			(effects
				(font
					(size 1.27 1.27)
					(thickness 0.15)
				)
				(justify left bottom)
				(hide yes)
			)
		)
		(property "MPN" "GRM188R60J226MEA0D"
			(at 104.775 203.835 0)
			(effects
				(font
					(size 1.27 1.27)
					(thickness 0.15)
				)
				(justify left bottom)
				(hide yes)
			)
		)
		(property "Val" "22u"
			(at 89.3191 223.3083 90)
			(effects
				(font
					(size 1.27 1.27)
					(thickness 0.15)
				)
				(justify right)
			)
		)
		(property "License" "Apache-2.0"
			(at 109.855 203.835 0)
			(effects
				(font
					(size 1.27 1.27)
					(thickness 0.15)
				)
				(justify left bottom)
				(hide yes)
			)
		)
		(property "Author" "Antmicro"
			(at 112.395 203.835 0)
			(effects
				(font
					(size 1.27 1.27)
					(thickness 0.15)
				)
				(justify left bottom)
				(hide yes)
			)
		)
		(property "Voltage" ""
			(at 114.935 203.835 0)
			(effects
				(font
					(size 1.27 1.27)
				)
				(justify left bottom)
				(hide yes)
			)
		)
		(property "Dielectric" ""
			(at 117.475 203.835 0)
			(effects
				(font
					(size 1.27 1.27)
				)
				(justify left bottom)
				(hide yes)
			)
		)
		(pin "1"
		)
		(pin "2"
		)
		(instances
			(project "sodimm-ddr5-tester"
				(path ""
					(reference "C189")
					(unit 1)
				)
			)
		)
	)
	(symbol
		(lib_id "antmicroTestPoints:TP_1mm_SMD")
		(at 248.92 274.32 0)
		(unit 1)
		(exclude_from_sim no)
		(in_bom yes)
		(on_board yes)
		(dnp no)
		(property "Reference" "TP60"
			(at 255.778 274.32 0)
			(effects
				(font
					(size 1.27 1.27)
				)
			)
		)
		(property "Value" "TP_1mm_SMD"
			(at 264.16 281.94 0)
			(effects
				(font
					(size 1.27 1.27)
					(thickness 0.15)
				)
				(justify left bottom)
				(hide yes)
			)
		)
		(property "Footprint" "antmicro-footprints:TP_SMD_1mm"
			(at 264.16 284.48 0)
			(effects
				(font
					(size 1.27 1.27)
					(thickness 0.15)
				)
				(justify left bottom)
				(hide yes)
			)
		)
		(property "Datasheet" ""
			(at 264.16 287.02 0)
			(effects
				(font
					(size 1.27 1.27)
					(thickness 0.15)
				)
				(justify left bottom)
				(hide yes)
			)
		)
		(property "Description" ""
			(at 248.92 274.32 0)
			(effects
				(font
					(size 1.27 1.27)
				)
			)
		)
		(property "MPN" ""
			(at 248.92 274.32 0)
			(effects
				(font
					(size 1.27 1.27)
				)
				(hide yes)
			)
		)
		(property "Manufacturer" ""
			(at 248.92 274.32 0)
			(effects
				(font
					(size 1.27 1.27)
				)
				(hide yes)
			)
		)
		(property "Author" "Antmicro"
			(at 264.16 289.56 0)
			(effects
				(font
					(size 1.27 1.27)
					(thickness 0.15)
				)
				(justify left bottom)
				(hide yes)
			)
		)
		(property "License" "Apache-2.0"
			(at 264.16 292.1 0)
			(effects
				(font
					(size 1.27 1.27)
					(thickness 0.15)
				)
				(justify left bottom)
				(hide yes)
			)
		)
		(pin "1"
		)
		(instances
			(project "sodimm-ddr5-tester"
				(path ""
					(reference "TP60")
					(unit 1)
				)
			)
		)
	)
	(symbol
		(lib_id "antmicroCapacitors0603:C_22u_0603")
		(at 276.86 187.325 90)
		(unit 1)
		(exclude_from_sim no)
		(in_bom yes)
		(on_board yes)
		(dnp no)
		(property "Reference" "C185"
			(at 277.495 182.88 90)
			(effects
				(font
					(size 1.27 1.27)
				)
				(justify right)
			)
		)
		(property "Value" "C_22u_0603"
			(at 287.02 167.005 0)
			(effects
				(font
					(size 1.27 1.27)
					(thickness 0.15)
				)
				(justify left bottom)
				(hide yes)
			)
		)
		(property "Footprint" "antmicro-footprints:C_0603_1608Metric"
			(at 289.56 167.005 0)
			(effects
				(font
					(size 1.27 1.27)
					(thickness 0.15)
				)
				(justify left bottom)
				(hide yes)
			)
		)
		(property "Datasheet" "https://www.murata.com/products/productdetail?partno=GRM188R60J226MEA0%23"
			(at 292.1 167.005 0)
			(effects
				(font
					(size 1.27 1.27)
					(thickness 0.15)
				)
				(justify left bottom)
				(hide yes)
			)
		)
		(property "Description" ""
			(at 276.86 187.325 0)
			(effects
				(font
					(size 1.27 1.27)
				)
			)
		)
		(property "Manufacturer" "Murata"
			(at 297.18 167.005 0)
			(effects
				(font
					(size 1.27 1.27)
					(thickness 0.15)
				)
				(justify left bottom)
				(hide yes)
			)
		)
		(property "MPN" "GRM188R60J226MEA0D"
			(at 294.64 167.005 0)
			(effects
				(font
					(size 1.27 1.27)
					(thickness 0.15)
				)
				(justify left bottom)
				(hide yes)
			)
		)
		(property "Val" "22u"
			(at 277.495 186.69 90)
			(effects
				(font
					(size 1.27 1.27)
					(thickness 0.15)
				)
				(justify right)
			)
		)
		(property "License" "Apache-2.0"
			(at 299.72 167.005 0)
			(effects
				(font
					(size 1.27 1.27)
					(thickness 0.15)
				)
				(justify left bottom)
				(hide yes)
			)
		)
		(property "Author" "Antmicro"
			(at 302.26 167.005 0)
			(effects
				(font
					(size 1.27 1.27)
					(thickness 0.15)
				)
				(justify left bottom)
				(hide yes)
			)
		)
		(property "Voltage" ""
			(at 304.8 167.005 0)
			(effects
				(font
					(size 1.27 1.27)
				)
				(justify left bottom)
				(hide yes)
			)
		)
		(property "Dielectric" ""
			(at 307.34 167.005 0)
			(effects
				(font
					(size 1.27 1.27)
				)
				(justify left bottom)
				(hide yes)
			)
		)
		(pin "1"
		)
		(pin "2"
		)
		(instances
			(project "sodimm-ddr5-tester"
				(path ""
					(reference "C185")
					(unit 1)
				)
			)
		)
	)
	(symbol
		(lib_id "antmicroResistors0402:R_47k_0402")
		(at 171.45 70.485 90)
		(unit 1)
		(exclude_from_sim no)
		(in_bom yes)
		(on_board yes)
		(dnp no)
		(property "Reference" "R161"
			(at 170.18 66.675 90)
			(effects
				(font
					(size 1.27 1.27)
				)
				(justify left)
			)
		)
		(property "Value" "R_47k_0402"
			(at 184.15 50.165 0)
			(effects
				(font
					(size 1.27 1.27)
					(thickness 0.15)
				)
				(justify left bottom)
				(hide yes)
			)
		)
		(property "Footprint" "antmicro-footprints:R_0402_1005Metric"
			(at 186.69 50.165 0)
			(effects
				(font
					(size 1.27 1.27)
					(thickness 0.15)
				)
				(justify left bottom)
				(hide yes)
			)
		)
		(property "Datasheet" "https://www.bourns.com/docs/product-datasheets/cr.pdf"
			(at 189.23 50.165 0)
			(effects
				(font
					(size 1.27 1.27)
					(thickness 0.15)
				)
				(justify left bottom)
				(hide yes)
			)
		)
		(property "Description" ""
			(at 171.45 70.485 0)
			(effects
				(font
					(size 1.27 1.27)
				)
			)
		)
		(property "Manufacturer" "Bourns"
			(at 194.31 50.165 0)
			(effects
				(font
					(size 1.27 1.27)
					(thickness 0.15)
				)
				(justify left bottom)
				(hide yes)
			)
		)
		(property "MPN" "CR0402-FX-4702GLF"
			(at 191.77 50.165 0)
			(effects
				(font
					(size 1.27 1.27)
					(thickness 0.15)
				)
				(justify left bottom)
				(hide yes)
			)
		)
		(property "Val" "47k"
			(at 170.18 69.215 90)
			(effects
				(font
					(size 1.27 1.27)
					(thickness 0.15)
				)
				(justify left)
			)
		)
		(property "License" "Apache-2.0"
			(at 196.85 50.165 0)
			(effects
				(font
					(size 1.27 1.27)
					(thickness 0.15)
				)
				(justify left bottom)
				(hide yes)
			)
		)
		(property "Author" "Antmicro"
			(at 199.39 50.165 0)
			(effects
				(font
					(size 1.27 1.27)
					(thickness 0.15)
				)
				(justify left bottom)
				(hide yes)
			)
		)
		(property "Tolerance" "1%"
			(at 181.61 50.165 0)
			(effects
				(font
					(size 1.27 1.27)
				)
				(justify left bottom)
				(hide yes)
			)
		)
		(pin "1"
		)
		(pin "2"
		)
		(instances
			(project "sodimm-ddr5-tester"
				(path ""
					(reference "R161")
					(unit 1)
				)
			)
		)
	)
	(symbol
		(lib_id "antmicroCapacitors0402:C_10u_6.3V_0402")
		(at 170.815 262.255 90)
		(unit 1)
		(exclude_from_sim no)
		(in_bom yes)
		(on_board yes)
		(dnp no)
		(fields_autoplaced yes)
		(property "Reference" "C218"
			(at 173.1391 258.878 90)
			(effects
				(font
					(size 1.27 1.27)
					(thickness 0.15)
				)
				(justify right)
			)
		)
		(property "Value" "C_10u_6.3V_0402"
			(at 180.975 241.935 0)
			(effects
				(font
					(size 1.27 1.27)
					(thickness 0.15)
				)
				(justify left bottom)
				(hide yes)
			)
		)
		(property "Footprint" "antmicro-footprints:C_0402_1005Metric"
			(at 183.515 241.935 0)
			(effects
				(font
					(size 1.27 1.27)
					(thickness 0.15)
				)
				(justify left bottom)
				(hide yes)
			)
		)
		(property "Datasheet" "https://www.murata.com/products/productdetail?partno=GRM155R60J106ME15%23"
			(at 186.055 241.935 0)
			(effects
				(font
					(size 1.27 1.27)
					(thickness 0.15)
				)
				(justify left bottom)
				(hide yes)
			)
		)
		(property "Description" ""
			(at 170.815 262.255 0)
			(effects
				(font
					(size 1.27 1.27)
				)
			)
		)
		(property "MPN" "GRM155R60J106ME15D"
			(at 188.595 241.935 0)
			(effects
				(font
					(size 1.27 1.27)
					(thickness 0.15)
				)
				(justify left bottom)
				(hide yes)
			)
		)
		(property "Manufacturer" "Murata"
			(at 191.135 241.935 0)
			(effects
				(font
					(size 1.27 1.27)
					(thickness 0.15)
				)
				(justify left bottom)
				(hide yes)
			)
		)
		(property "License" "Apache-2.0"
			(at 193.675 241.935 0)
			(effects
				(font
					(size 1.27 1.27)
					(thickness 0.15)
				)
				(justify left bottom)
				(hide yes)
			)
		)
		(property "Author" "Antmicro"
			(at 196.215 241.935 0)
			(effects
				(font
					(size 1.27 1.27)
					(thickness 0.15)
				)
				(justify left bottom)
				(hide yes)
			)
		)
		(property "Val" "10u"
			(at 173.1391 261.4017 90)
			(effects
				(font
					(size 1.27 1.27)
					(thickness 0.15)
				)
				(justify right)
			)
		)
		(property "Voltage" "6.3V"
			(at 198.755 241.935 0)
			(effects
				(font
					(size 1.27 1.27)
				)
				(justify left bottom)
				(hide yes)
			)
		)
		(property "Dielectric" "X5R"
			(at 201.295 241.935 0)
			(effects
				(font
					(size 1.27 1.27)
				)
				(justify left bottom)
				(hide yes)
			)
		)
		(pin "1"
		)
		(pin "2"
		)
		(instances
			(project "sodimm-ddr5-tester"
				(path ""
					(reference "C218")
					(unit 1)
				)
			)
		)
	)
	(symbol
		(lib_id "antmicroResistors0402:R_0R_0402")
		(at 283.21 256.54 0)
		(unit 1)
		(exclude_from_sim no)
		(in_bom yes)
		(on_board yes)
		(dnp no)
		(property "Reference" "R136"
			(at 290.83 255.27 0)
			(effects
				(font
					(size 1.27 1.27)
					(thickness 0.15)
				)
			)
		)
		(property "Value" "R_0R_0402"
			(at 303.53 269.24 0)
			(effects
				(font
					(size 1.27 1.27)
					(thickness 0.15)
				)
				(justify left bottom)
				(hide yes)
			)
		)
		(property "Footprint" "antmicro-footprints:R_0402_1005Metric"
			(at 303.53 271.78 0)
			(effects
				(font
					(size 1.27 1.27)
					(thickness 0.15)
				)
				(justify left bottom)
				(hide yes)
			)
		)
		(property "Datasheet" "https://industrial.panasonic.com/cdbs/www-data/pdf/RDA0000/AOA0000C301.pdf"
			(at 303.53 274.32 0)
			(effects
				(font
					(size 1.27 1.27)
					(thickness 0.15)
				)
				(justify left bottom)
				(hide yes)
			)
		)
		(property "Description" ""
			(at 283.21 256.54 0)
			(effects
				(font
					(size 1.27 1.27)
				)
			)
		)
		(property "MPN" "ERJ2GE0R00X"
			(at 303.53 276.86 0)
			(effects
				(font
					(size 1.27 1.27)
					(thickness 0.15)
				)
				(justify left bottom)
				(hide yes)
			)
		)
		(property "Manufacturer" "Panasonic"
			(at 303.53 279.4 0)
			(effects
				(font
					(size 1.27 1.27)
					(thickness 0.15)
				)
				(justify left bottom)
				(hide yes)
			)
		)
		(property "License" "Apache-2.0"
			(at 303.53 281.94 0)
			(effects
				(font
					(size 1.27 1.27)
					(thickness 0.15)
				)
				(justify left bottom)
				(hide yes)
			)
		)
		(property "Author" "Antmicro"
			(at 303.53 284.48 0)
			(effects
				(font
					(size 1.27 1.27)
					(thickness 0.15)
				)
				(justify left bottom)
				(hide yes)
			)
		)
		(property "Val" "0R"
			(at 281.94 255.27 0)
			(effects
				(font
					(size 1.27 1.27)
					(thickness 0.15)
				)
			)
		)
		(property "Tolerance" "~"
			(at 303.53 266.7 0)
			(effects
				(font
					(size 1.27 1.27)
				)
				(justify left bottom)
				(hide yes)
			)
		)
		(property "Current" "1A"
			(at 303.53 287.02 0)
			(effects
				(font
					(size 1.27 1.27)
					(thickness 0.15)
				)
				(justify left bottom)
				(hide yes)
			)
		)
		(pin "1"
		)
		(pin "2"
		)
		(instances
			(project "sodimm-ddr5-tester"
				(path ""
					(reference "R136")
					(unit 1)
				)
			)
		)
	)
	(symbol
		(lib_id "antmicropower:PWR_FLAG")
		(at 138.43 105.41 0)
		(unit 1)
		(exclude_from_sim no)
		(in_bom yes)
		(on_board yes)
		(dnp no)
		(fields_autoplaced yes)
		(property "Reference" "#FLG0118"
			(at 138.43 103.505 0)
			(effects
				(font
					(size 1.27 1.27)
				)
				(hide yes)
			)
		)
		(property "Value" "PWR_FLAG"
			(at 138.43 101.8342 0)
			(effects
				(font
					(size 1.27 1.27)
				)
			)
		)
		(property "Footprint" ""
			(at 138.43 105.41 0)
			(effects
				(font
					(size 1.27 1.27)
				)
				(hide yes)
			)
		)
		(property "Datasheet" ""
			(at 138.43 105.41 0)
			(effects
				(font
					(size 1.27 1.27)
				)
				(hide yes)
			)
		)
		(property "Description" ""
			(at 138.43 105.41 0)
			(effects
				(font
					(size 1.27 1.27)
				)
			)
		)
		(pin "1"
		)
		(instances
			(project "sodimm-ddr5-tester"
				(path ""
					(reference "#FLG0118")
					(unit 1)
				)
			)
		)
	)
	(symbol
		(lib_id "antmicroFixedInductors:L_1u5_17A_Bourns-SRP6050CA")
		(at 80.645 106.68 0)
		(unit 1)
		(exclude_from_sim no)
		(in_bom yes)
		(on_board yes)
		(dnp no)
		(fields_autoplaced yes)
		(property "Reference" "L1"
			(at 83.185 102.614 0)
			(effects
				(font
					(size 1.27 1.27)
					(thickness 0.15)
				)
			)
		)
		(property "Value" "L_1u5_17A_Bourns-SRP6050CA"
			(at 94.615 109.22 0)
			(effects
				(font
					(size 1.27 1.27)
					(thickness 0.15)
				)
				(justify left bottom)
				(hide yes)
			)
		)
		(property "Footprint" "antmicro-footprints:L_Bourns-SRP6050CA"
			(at 94.615 114.3 0)
			(effects
				(font
					(size 1.27 1.27)
					(thickness 0.15)
				)
				(justify left bottom)
				(hide yes)
			)
		)
		(property "Datasheet" "https://www.bourns.com/docs/Product-Datasheets/SRP6050CA.pdf"
			(at 94.615 116.84 0)
			(effects
				(font
					(size 1.27 1.27)
					(thickness 0.15)
				)
				(justify left bottom)
				(hide yes)
			)
		)
		(property "Description" ""
			(at 80.645 106.68 0)
			(effects
				(font
					(size 1.27 1.27)
				)
			)
		)
		(property "Val" "1u5/17A"
			(at 83.185 105.1377 0)
			(effects
				(font
					(size 1.27 1.27)
					(thickness 0.15)
				)
			)
		)
		(property "Manufacturer" "Bourns"
			(at 94.615 119.38 0)
			(effects
				(font
					(size 1.27 1.27)
					(thickness 0.15)
				)
				(justify left bottom)
				(hide yes)
			)
		)
		(property "MPN" "SRP6050CA-1R5M"
			(at 94.615 121.92 0)
			(effects
				(font
					(size 1.27 1.27)
					(thickness 0.15)
				)
				(justify left bottom)
				(hide yes)
			)
		)
		(property "ISat" "19.5 A"
			(at 94.615 123.19 0)
			(effects
				(font
					(size 1.27 1.27)
				)
				(justify left)
				(hide yes)
			)
		)
		(property "IMax" "17 A"
			(at 94.615 127 0)
			(effects
				(font
					(size 1.27 1.27)
					(thickness 0.15)
				)
				(justify left bottom)
				(hide yes)
			)
		)
		(property "Size" "6.6x6.6"
			(at 94.615 129.54 0)
			(effects
				(font
					(size 1.27 1.27)
					(thickness 0.15)
				)
				(justify left bottom)
				(hide yes)
			)
		)
		(property "Author" "Antmicro"
			(at 94.615 132.08 0)
			(effects
				(font
					(size 1.27 1.27)
					(thickness 0.15)
				)
				(justify left bottom)
				(hide yes)
			)
		)
		(property "License" "Apache-2.0"
			(at 94.615 134.62 0)
			(effects
				(font
					(size 1.27 1.27)
					(thickness 0.15)
				)
				(justify left bottom)
				(hide yes)
			)
		)
		(pin "1"
		)
		(pin "2"
		)
		(instances
			(project "sodimm-ddr5-tester"
				(path ""
					(reference "L1")
					(unit 1)
				)
			)
		)
	)
	(symbol
		(lib_id "antmicropower:PWR_FLAG")
		(at 85.725 246.38 0)
		(unit 1)
		(exclude_from_sim no)
		(in_bom yes)
		(on_board yes)
		(dnp no)
		(fields_autoplaced yes)
		(property "Reference" "#FLG0117"
			(at 85.725 244.475 0)
			(effects
				(font
					(size 1.27 1.27)
				)
				(hide yes)
			)
		)
		(property "Value" "PWR_FLAG"
			(at 85.725 242.8042 0)
			(effects
				(font
					(size 1.27 1.27)
				)
			)
		)
		(property "Footprint" ""
			(at 85.725 246.38 0)
			(effects
				(font
					(size 1.27 1.27)
				)
				(hide yes)
			)
		)
		(property "Datasheet" ""
			(at 85.725 246.38 0)
			(effects
				(font
					(size 1.27 1.27)
				)
				(hide yes)
			)
		)
		(property "Description" ""
			(at 85.725 246.38 0)
			(effects
				(font
					(size 1.27 1.27)
				)
			)
		)
		(pin "1"
		)
		(instances
			(project "sodimm-ddr5-tester"
				(path ""
					(reference "#FLG0117")
					(unit 1)
				)
			)
		)
	)
	(symbol
		(lib_id "antmicroTestPoints:TP_1mm_SMD")
		(at 142.24 278.13 270)
		(unit 1)
		(exclude_from_sim no)
		(in_bom yes)
		(on_board yes)
		(dnp no)
		(property "Reference" "TP30"
			(at 142.24 283.1028 90)
			(effects
				(font
					(size 1.27 1.27)
				)
			)
		)
		(property "Value" "TP_1mm_SMD"
			(at 134.62 293.37 0)
			(effects
				(font
					(size 1.27 1.27)
					(thickness 0.15)
				)
				(justify left bottom)
				(hide yes)
			)
		)
		(property "Footprint" "antmicro-footprints:TP_SMD_1mm"
			(at 132.08 293.37 0)
			(effects
				(font
					(size 1.27 1.27)
					(thickness 0.15)
				)
				(justify left bottom)
				(hide yes)
			)
		)
		(property "Datasheet" ""
			(at 129.54 293.37 0)
			(effects
				(font
					(size 1.27 1.27)
					(thickness 0.15)
				)
				(justify left bottom)
				(hide yes)
			)
		)
		(property "Description" ""
			(at 142.24 278.13 0)
			(effects
				(font
					(size 1.27 1.27)
				)
			)
		)
		(property "MPN" ""
			(at 142.24 278.13 0)
			(effects
				(font
					(size 1.27 1.27)
				)
				(hide yes)
			)
		)
		(property "Manufacturer" ""
			(at 142.24 278.13 0)
			(effects
				(font
					(size 1.27 1.27)
				)
				(hide yes)
			)
		)
		(property "Author" "Antmicro"
			(at 127 293.37 0)
			(effects
				(font
					(size 1.27 1.27)
					(thickness 0.15)
				)
				(justify left bottom)
				(hide yes)
			)
		)
		(property "License" "Apache-2.0"
			(at 124.46 293.37 0)
			(effects
				(font
					(size 1.27 1.27)
					(thickness 0.15)
				)
				(justify left bottom)
				(hide yes)
			)
		)
		(pin "1"
		)
		(instances
			(project "sodimm-ddr5-tester"
				(path ""
					(reference "TP30")
					(unit 1)
				)
			)
		)
	)
	(symbol
		(lib_id "antmicroResistors0402:R_0R_0402")
		(at 190.5 201.93 90)
		(unit 1)
		(exclude_from_sim no)
		(in_bom yes)
		(on_board yes)
		(dnp no)
		(fields_autoplaced yes)
		(property "Reference" "R164"
			(at 192.405 198.1199 90)
			(effects
				(font
					(size 1.27 1.27)
				)
				(justify right)
			)
		)
		(property "Value" "R_0R_0402"
			(at 203.2 181.61 0)
			(effects
				(font
					(size 1.27 1.27)
					(thickness 0.15)
				)
				(justify left bottom)
				(hide yes)
			)
		)
		(property "Footprint" "antmicro-footprints:R_0402_1005Metric"
			(at 205.74 181.61 0)
			(effects
				(font
					(size 1.27 1.27)
					(thickness 0.15)
				)
				(justify left bottom)
				(hide yes)
			)
		)
		(property "Datasheet" "https://industrial.panasonic.com/cdbs/www-data/pdf/RDA0000/AOA0000C301.pdf"
			(at 208.28 181.61 0)
			(effects
				(font
					(size 1.27 1.27)
					(thickness 0.15)
				)
				(justify left bottom)
				(hide yes)
			)
		)
		(property "Description" ""
			(at 190.5 201.93 0)
			(effects
				(font
					(size 1.27 1.27)
				)
			)
		)
		(property "Manufacturer" "Panasonic"
			(at 213.36 181.61 0)
			(effects
				(font
					(size 1.27 1.27)
					(thickness 0.15)
				)
				(justify left bottom)
				(hide yes)
			)
		)
		(property "MPN" "ERJ2GE0R00X"
			(at 210.82 181.61 0)
			(effects
				(font
					(size 1.27 1.27)
					(thickness 0.15)
				)
				(justify left bottom)
				(hide yes)
			)
		)
		(property "Val" "0R"
			(at 192.405 200.6599 90)
			(effects
				(font
					(size 1.27 1.27)
					(thickness 0.15)
				)
				(justify right)
			)
		)
		(property "License" "Apache-2.0"
			(at 215.9 181.61 0)
			(effects
				(font
					(size 1.27 1.27)
					(thickness 0.15)
				)
				(justify left bottom)
				(hide yes)
			)
		)
		(property "Author" "Antmicro"
			(at 218.44 181.61 0)
			(effects
				(font
					(size 1.27 1.27)
					(thickness 0.15)
				)
				(justify left bottom)
				(hide yes)
			)
		)
		(property "Tolerance" "~"
			(at 200.66 181.61 0)
			(effects
				(font
					(size 1.27 1.27)
				)
				(justify left bottom)
				(hide yes)
			)
		)
		(property "Current" "1A"
			(at 192.405 201.9299 90)
			(effects
				(font
					(size 1.27 1.27)
					(thickness 0.15)
				)
				(justify right)
				(hide yes)
			)
		)
		(pin "1"
		)
		(pin "2"
		)
		(instances
			(project "sodimm-ddr5-tester"
				(path ""
					(reference "R164")
					(unit 1)
				)
			)
		)
	)
	(symbol
		(lib_id "antmicropower:GND")
		(at 66.675 43.815 0)
		(unit 1)
		(exclude_from_sim no)
		(in_bom yes)
		(on_board yes)
		(dnp no)
		(fields_autoplaced yes)
		(property "Reference" "#PWR0292"
			(at 66.675 50.165 0)
			(effects
				(font
					(size 1.27 1.27)
				)
				(hide yes)
			)
		)
		(property "Value" "GND"
			(at 68.58 45.085 0)
			(effects
				(font
					(size 1.27 1.27)
					(thickness 0.15)
				)
				(justify left)
			)
		)
		(property "Footprint" ""
			(at 75.565 51.435 0)
			(effects
				(font
					(size 1.27 1.27)
					(thickness 0.15)
				)
				(justify left bottom)
				(hide yes)
			)
		)
		(property "Datasheet" ""
			(at 75.565 56.515 0)
			(effects
				(font
					(size 1.27 1.27)
					(thickness 0.15)
				)
				(justify left bottom)
				(hide yes)
			)
		)
		(property "Description" ""
			(at 75.565 59.055 0)
			(effects
				(font
					(size 1.27 1.27)
				)
				(justify left bottom)
				(hide yes)
			)
		)
		(property "Author" "Antmicro"
			(at 75.565 51.435 0)
			(effects
				(font
					(size 1.27 1.27)
					(thickness 0.15)
				)
				(justify left bottom)
				(hide yes)
			)
		)
		(property "License" "Apache-2.0"
			(at 75.565 53.975 0)
			(effects
				(font
					(size 1.27 1.27)
					(thickness 0.15)
				)
				(justify left bottom)
				(hide yes)
			)
		)
		(pin "1"
		)
		(instances
			(project "sodimm-ddr5-tester"
				(path ""
					(reference "#PWR0292")
					(unit 1)
				)
			)
		)
	)
	(symbol
		(lib_id "antmicroResistors0402:R_0R_0402")
		(at 160.02 212.09 90)
		(unit 1)
		(exclude_from_sim no)
		(in_bom no)
		(on_board yes)
		(dnp yes)
		(property "Reference" "R154"
			(at 161.925 208.28 90)
			(effects
				(font
					(size 1.27 1.27)
				)
				(justify right)
			)
		)
		(property "Value" "R_0R_0402"
			(at 172.72 191.77 0)
			(effects
				(font
					(size 1.27 1.27)
					(thickness 0.15)
				)
				(justify left bottom)
				(hide yes)
			)
		)
		(property "Footprint" "antmicro-footprints:R_0402_1005Metric"
			(at 175.26 191.77 0)
			(effects
				(font
					(size 1.27 1.27)
					(thickness 0.15)
				)
				(justify left bottom)
				(hide yes)
			)
		)
		(property "Datasheet" "https://industrial.panasonic.com/cdbs/www-data/pdf/RDA0000/AOA0000C301.pdf"
			(at 177.8 191.77 0)
			(effects
				(font
					(size 1.27 1.27)
					(thickness 0.15)
				)
				(justify left bottom)
				(hide yes)
			)
		)
		(property "Description" ""
			(at 160.02 212.09 0)
			(effects
				(font
					(size 1.27 1.27)
				)
			)
		)
		(property "Manufacturer" "Panasonic"
			(at 182.88 191.77 0)
			(effects
				(font
					(size 1.27 1.27)
					(thickness 0.15)
				)
				(justify left bottom)
				(hide yes)
			)
		)
		(property "MPN" "ERJ2GE0R00X"
			(at 180.34 191.77 0)
			(effects
				(font
					(size 1.27 1.27)
					(thickness 0.15)
				)
				(justify left bottom)
				(hide yes)
			)
		)
		(property "Val" "0R"
			(at 161.925 210.82 90)
			(effects
				(font
					(size 1.27 1.27)
					(thickness 0.15)
				)
				(justify right)
			)
		)
		(property "License" "Apache-2.0"
			(at 185.42 191.77 0)
			(effects
				(font
					(size 1.27 1.27)
					(thickness 0.15)
				)
				(justify left bottom)
				(hide yes)
			)
		)
		(property "Author" "Antmicro"
			(at 187.96 191.77 0)
			(effects
				(font
					(size 1.27 1.27)
					(thickness 0.15)
				)
				(justify left bottom)
				(hide yes)
			)
		)
		(property "Tolerance" "~"
			(at 170.18 191.77 0)
			(effects
				(font
					(size 1.27 1.27)
				)
				(justify left bottom)
				(hide yes)
			)
		)
		(property "Current" "1A"
			(at 161.925 213.3599 90)
			(effects
				(font
					(size 1.27 1.27)
					(thickness 0.15)
				)
				(justify right)
				(hide yes)
			)
		)
		(pin "1"
		)
		(pin "2"
		)
		(instances
			(project "sodimm-ddr5-tester"
				(path ""
					(reference "R154")
					(unit 1)
				)
			)
		)
	)
	(symbol
		(lib_id "antmicroCapacitors0402:C_22p_0402")
		(at 135.255 124.46 90)
		(unit 1)
		(exclude_from_sim no)
		(in_bom yes)
		(on_board yes)
		(dnp no)
		(property "Reference" "C221"
			(at 135.89 120.015 90)
			(effects
				(font
					(size 1.27 1.27)
				)
				(justify right)
			)
		)
		(property "Value" "C_22p_0402"
			(at 145.415 104.14 0)
			(effects
				(font
					(size 1.27 1.27)
					(thickness 0.15)
				)
				(justify left bottom)
				(hide yes)
			)
		)
		(property "Footprint" "antmicro-footprints:C_0402_1005Metric"
			(at 147.955 104.14 0)
			(effects
				(font
					(size 1.27 1.27)
					(thickness 0.15)
				)
				(justify left bottom)
				(hide yes)
			)
		)
		(property "Datasheet" "https://www.yageo.com/en/Chart/Download/pdf/CC0402JRNPO9BN220"
			(at 150.495 104.14 0)
			(effects
				(font
					(size 1.27 1.27)
					(thickness 0.15)
				)
				(justify left bottom)
				(hide yes)
			)
		)
		(property "Description" ""
			(at 135.255 124.46 0)
			(effects
				(font
					(size 1.27 1.27)
				)
			)
		)
		(property "Manufacturer" "YAGEO"
			(at 155.575 104.14 0)
			(effects
				(font
					(size 1.27 1.27)
					(thickness 0.15)
				)
				(justify left bottom)
				(hide yes)
			)
		)
		(property "MPN" "CC0402JRNPO9BN220"
			(at 153.035 104.14 0)
			(effects
				(font
					(size 1.27 1.27)
					(thickness 0.15)
				)
				(justify left bottom)
				(hide yes)
			)
		)
		(property "Val" "22p"
			(at 135.89 123.825 90)
			(effects
				(font
					(size 1.27 1.27)
					(thickness 0.15)
				)
				(justify right)
			)
		)
		(property "License" "Apache-2.0"
			(at 158.115 104.14 0)
			(effects
				(font
					(size 1.27 1.27)
					(thickness 0.15)
				)
				(justify left bottom)
				(hide yes)
			)
		)
		(property "Author" "Antmicro"
			(at 160.655 104.14 0)
			(effects
				(font
					(size 1.27 1.27)
					(thickness 0.15)
				)
				(justify left bottom)
				(hide yes)
			)
		)
		(property "Voltage" ""
			(at 163.195 104.14 0)
			(effects
				(font
					(size 1.27 1.27)
				)
				(justify left bottom)
				(hide yes)
			)
		)
		(property "Dielectric" ""
			(at 165.735 104.14 0)
			(effects
				(font
					(size 1.27 1.27)
				)
				(justify left bottom)
				(hide yes)
			)
		)
		(pin "1"
		)
		(pin "2"
		)
		(instances
			(project "sodimm-ddr5-tester"
				(path ""
					(reference "C221")
					(unit 1)
				)
			)
		)
	)
	(symbol
		(lib_id "antmicroResistors0402:R_0R_0402")
		(at 283.21 261.62 0)
		(unit 1)
		(exclude_from_sim no)
		(in_bom yes)
		(on_board yes)
		(dnp no)
		(property "Reference" "R138"
			(at 290.83 260.35 0)
			(effects
				(font
					(size 1.27 1.27)
					(thickness 0.15)
				)
			)
		)
		(property "Value" "R_0R_0402"
			(at 303.53 274.32 0)
			(effects
				(font
					(size 1.27 1.27)
					(thickness 0.15)
				)
				(justify left bottom)
				(hide yes)
			)
		)
		(property "Footprint" "antmicro-footprints:R_0402_1005Metric"
			(at 303.53 276.86 0)
			(effects
				(font
					(size 1.27 1.27)
					(thickness 0.15)
				)
				(justify left bottom)
				(hide yes)
			)
		)
		(property "Datasheet" "https://industrial.panasonic.com/cdbs/www-data/pdf/RDA0000/AOA0000C301.pdf"
			(at 303.53 279.4 0)
			(effects
				(font
					(size 1.27 1.27)
					(thickness 0.15)
				)
				(justify left bottom)
				(hide yes)
			)
		)
		(property "Description" ""
			(at 283.21 261.62 0)
			(effects
				(font
					(size 1.27 1.27)
				)
			)
		)
		(property "MPN" "ERJ2GE0R00X"
			(at 303.53 281.94 0)
			(effects
				(font
					(size 1.27 1.27)
					(thickness 0.15)
				)
				(justify left bottom)
				(hide yes)
			)
		)
		(property "Manufacturer" "Panasonic"
			(at 303.53 284.48 0)
			(effects
				(font
					(size 1.27 1.27)
					(thickness 0.15)
				)
				(justify left bottom)
				(hide yes)
			)
		)
		(property "License" "Apache-2.0"
			(at 303.53 287.02 0)
			(effects
				(font
					(size 1.27 1.27)
					(thickness 0.15)
				)
				(justify left bottom)
				(hide yes)
			)
		)
		(property "Author" "Antmicro"
			(at 303.53 289.56 0)
			(effects
				(font
					(size 1.27 1.27)
					(thickness 0.15)
				)
				(justify left bottom)
				(hide yes)
			)
		)
		(property "Val" "0R"
			(at 281.94 260.35 0)
			(effects
				(font
					(size 1.27 1.27)
					(thickness 0.15)
				)
			)
		)
		(property "Tolerance" "~"
			(at 303.53 271.78 0)
			(effects
				(font
					(size 1.27 1.27)
				)
				(justify left bottom)
				(hide yes)
			)
		)
		(property "Current" "1A"
			(at 303.53 292.1 0)
			(effects
				(font
					(size 1.27 1.27)
					(thickness 0.15)
				)
				(justify left bottom)
				(hide yes)
			)
		)
		(pin "1"
		)
		(pin "2"
		)
		(instances
			(project "sodimm-ddr5-tester"
				(path ""
					(reference "R138")
					(unit 1)
				)
			)
		)
	)
	(symbol
		(lib_id "antmicroCapacitors0402:C_1u_0402")
		(at 238.76 250.19 90)
		(unit 1)
		(exclude_from_sim no)
		(in_bom yes)
		(on_board yes)
		(dnp no)
		(property "Reference" "C198"
			(at 239.395 245.745 90)
			(effects
				(font
					(size 1.27 1.27)
				)
				(justify right)
			)
		)
		(property "Value" "C_1u_0402"
			(at 248.92 229.87 0)
			(effects
				(font
					(size 1.27 1.27)
					(thickness 0.15)
				)
				(justify left bottom)
				(hide yes)
			)
		)
		(property "Footprint" "antmicro-footprints:C_0402_1005Metric"
			(at 251.46 229.87 0)
			(effects
				(font
					(size 1.27 1.27)
					(thickness 0.15)
				)
				(justify left bottom)
				(hide yes)
			)
		)
		(property "Datasheet" "https://product.tdk.com/en/search/capacitor/ceramic/mlcc/info?part_no=C1005X6S1A105K050BC"
			(at 254 229.87 0)
			(effects
				(font
					(size 1.27 1.27)
					(thickness 0.15)
				)
				(justify left bottom)
				(hide yes)
			)
		)
		(property "Description" ""
			(at 238.76 250.19 0)
			(effects
				(font
					(size 1.27 1.27)
				)
			)
		)
		(property "Manufacturer" "TDK"
			(at 259.08 229.87 0)
			(effects
				(font
					(size 1.27 1.27)
					(thickness 0.15)
				)
				(justify left bottom)
				(hide yes)
			)
		)
		(property "MPN" "C1005X6S1A105K050BC"
			(at 256.54 229.87 0)
			(effects
				(font
					(size 1.27 1.27)
					(thickness 0.15)
				)
				(justify left bottom)
				(hide yes)
			)
		)
		(property "Val" "1u"
			(at 239.395 249.555 90)
			(effects
				(font
					(size 1.27 1.27)
					(thickness 0.15)
				)
				(justify right)
			)
		)
		(property "License" "Apache-2.0"
			(at 261.62 229.87 0)
			(effects
				(font
					(size 1.27 1.27)
					(thickness 0.15)
				)
				(justify left bottom)
				(hide yes)
			)
		)
		(property "Author" "Antmicro"
			(at 264.16 229.87 0)
			(effects
				(font
					(size 1.27 1.27)
					(thickness 0.15)
				)
				(justify left bottom)
				(hide yes)
			)
		)
		(property "Voltage" ""
			(at 266.7 229.87 0)
			(effects
				(font
					(size 1.27 1.27)
				)
				(justify left bottom)
				(hide yes)
			)
		)
		(property "Dielectric" ""
			(at 269.24 229.87 0)
			(effects
				(font
					(size 1.27 1.27)
				)
				(justify left bottom)
				(hide yes)
			)
		)
		(pin "1"
		)
		(pin "2"
		)
		(instances
			(project "sodimm-ddr5-tester"
				(path ""
					(reference "C198")
					(unit 1)
				)
			)
		)
	)
	(symbol
		(lib_id "antmicropower:GND")
		(at 285.75 191.135 0)
		(unit 1)
		(exclude_from_sim no)
		(in_bom yes)
		(on_board yes)
		(dnp no)
		(fields_autoplaced yes)
		(property "Reference" "#PWR0309"
			(at 285.75 197.485 0)
			(effects
				(font
					(size 1.27 1.27)
				)
				(hide yes)
			)
		)
		(property "Value" "GND"
			(at 288.29 192.405 0)
			(effects
				(font
					(size 1.27 1.27)
					(thickness 0.15)
				)
				(justify left)
			)
		)
		(property "Footprint" ""
			(at 294.64 198.755 0)
			(effects
				(font
					(size 1.27 1.27)
					(thickness 0.15)
				)
				(justify left bottom)
				(hide yes)
			)
		)
		(property "Datasheet" ""
			(at 294.64 203.835 0)
			(effects
				(font
					(size 1.27 1.27)
					(thickness 0.15)
				)
				(justify left bottom)
				(hide yes)
			)
		)
		(property "Description" ""
			(at 294.64 206.375 0)
			(effects
				(font
					(size 1.27 1.27)
				)
				(justify left bottom)
				(hide yes)
			)
		)
		(property "Author" "Antmicro"
			(at 294.64 198.755 0)
			(effects
				(font
					(size 1.27 1.27)
					(thickness 0.15)
				)
				(justify left bottom)
				(hide yes)
			)
		)
		(property "License" "Apache-2.0"
			(at 294.64 201.295 0)
			(effects
				(font
					(size 1.27 1.27)
					(thickness 0.15)
				)
				(justify left bottom)
				(hide yes)
			)
		)
		(pin "1"
		)
		(instances
			(project "sodimm-ddr5-tester"
				(path ""
					(reference "#PWR0309")
					(unit 1)
				)
			)
		)
	)
	(symbol
		(lib_id "antmicroShuntsJumpers:Net-Tie_P0.127mm")
		(at 313.055 184.15 90)
		(unit 1)
		(exclude_from_sim no)
		(in_bom no)
		(on_board yes)
		(dnp no)
		(fields_autoplaced yes)
		(property "Reference" "NT14"
			(at 311.785 184.15 0)
			(effects
				(font
					(size 1.27 1.27)
				)
				(hide yes)
			)
		)
		(property "Value" "Net-Tie_P0.127mm"
			(at 320.675 162.56 0)
			(effects
				(font
					(size 1.27 1.27)
					(thickness 0.15)
				)
				(justify left bottom)
				(hide yes)
			)
		)
		(property "Footprint" "antmicro-footprints:NetTie-2_SMD_Pad0.127mm"
			(at 325.755 162.56 0)
			(effects
				(font
					(size 1.27 1.27)
					(thickness 0.15)
				)
				(justify left bottom)
				(hide yes)
			)
		)
		(property "Datasheet" ""
			(at 328.295 162.56 0)
			(effects
				(font
					(size 1.27 1.27)
					(thickness 0.15)
				)
				(justify left bottom)
				(hide yes)
			)
		)
		(property "Description" ""
			(at 313.055 184.15 0)
			(effects
				(font
					(size 1.27 1.27)
				)
			)
		)
		(property "MPN" ""
			(at 323.215 162.56 0)
			(effects
				(font
					(size 1.27 1.27)
					(thickness 0.15)
				)
				(justify left bottom)
			)
		)
		(property "Manufacturer" ""
			(at 330.835 162.56 0)
			(effects
				(font
					(size 1.27 1.27)
					(thickness 0.15)
				)
				(justify left bottom)
				(hide yes)
			)
		)
		(property "Author" "Antmicro"
			(at 333.375 162.56 0)
			(effects
				(font
					(size 1.27 1.27)
					(thickness 0.15)
				)
				(justify left bottom)
				(hide yes)
			)
		)
		(property "License" "Apache-2.0"
			(at 335.915 162.56 0)
			(effects
				(font
					(size 1.27 1.27)
					(thickness 0.15)
				)
				(justify left bottom)
				(hide yes)
			)
		)
		(pin "1"
		)
		(pin "2"
		)
		(instances
			(project "sodimm-ddr5-tester"
				(path ""
					(reference "NT14")
					(unit 1)
				)
			)
		)
	)
	(symbol
		(lib_id "antmicroResistors0402:R_47k_0402")
		(at 278.765 255.27 90)
		(unit 1)
		(exclude_from_sim no)
		(in_bom yes)
		(on_board yes)
		(dnp no)
		(property "Reference" "R135"
			(at 277.495 251.46 90)
			(effects
				(font
					(size 1.27 1.27)
				)
				(justify left)
			)
		)
		(property "Value" "R_47k_0402"
			(at 291.465 234.95 0)
			(effects
				(font
					(size 1.27 1.27)
					(thickness 0.15)
				)
				(justify left bottom)
				(hide yes)
			)
		)
		(property "Footprint" "antmicro-footprints:R_0402_1005Metric"
			(at 294.005 234.95 0)
			(effects
				(font
					(size 1.27 1.27)
					(thickness 0.15)
				)
				(justify left bottom)
				(hide yes)
			)
		)
		(property "Datasheet" "https://www.bourns.com/docs/product-datasheets/cr.pdf"
			(at 296.545 234.95 0)
			(effects
				(font
					(size 1.27 1.27)
					(thickness 0.15)
				)
				(justify left bottom)
				(hide yes)
			)
		)
		(property "Description" ""
			(at 278.765 255.27 0)
			(effects
				(font
					(size 1.27 1.27)
				)
			)
		)
		(property "Manufacturer" "Bourns"
			(at 301.625 234.95 0)
			(effects
				(font
					(size 1.27 1.27)
					(thickness 0.15)
				)
				(justify left bottom)
				(hide yes)
			)
		)
		(property "MPN" "CR0402-FX-4702GLF"
			(at 299.085 234.95 0)
			(effects
				(font
					(size 1.27 1.27)
					(thickness 0.15)
				)
				(justify left bottom)
				(hide yes)
			)
		)
		(property "Val" "47k"
			(at 277.495 254 90)
			(effects
				(font
					(size 1.27 1.27)
					(thickness 0.15)
				)
				(justify left)
			)
		)
		(property "License" "Apache-2.0"
			(at 304.165 234.95 0)
			(effects
				(font
					(size 1.27 1.27)
					(thickness 0.15)
				)
				(justify left bottom)
				(hide yes)
			)
		)
		(property "Author" "Antmicro"
			(at 306.705 234.95 0)
			(effects
				(font
					(size 1.27 1.27)
					(thickness 0.15)
				)
				(justify left bottom)
				(hide yes)
			)
		)
		(property "Tolerance" "1%"
			(at 288.925 234.95 0)
			(effects
				(font
					(size 1.27 1.27)
				)
				(justify left bottom)
				(hide yes)
			)
		)
		(pin "1"
		)
		(pin "2"
		)
		(instances
			(project "sodimm-ddr5-tester"
				(path ""
					(reference "R135")
					(unit 1)
				)
			)
		)
	)
	(symbol
		(lib_id "antmicropower:GND")
		(at 17.145 124.46 0)
		(unit 1)
		(exclude_from_sim no)
		(in_bom yes)
		(on_board yes)
		(dnp no)
		(fields_autoplaced yes)
		(property "Reference" "#PWR0364"
			(at 17.145 130.81 0)
			(effects
				(font
					(size 1.27 1.27)
				)
				(hide yes)
			)
		)
		(property "Value" "GND"
			(at 19.05 125.73 0)
			(effects
				(font
					(size 1.27 1.27)
					(thickness 0.15)
				)
				(justify left)
			)
		)
		(property "Footprint" ""
			(at 26.035 132.08 0)
			(effects
				(font
					(size 1.27 1.27)
					(thickness 0.15)
				)
				(justify left bottom)
				(hide yes)
			)
		)
		(property "Datasheet" ""
			(at 26.035 137.16 0)
			(effects
				(font
					(size 1.27 1.27)
					(thickness 0.15)
				)
				(justify left bottom)
				(hide yes)
			)
		)
		(property "Description" ""
			(at 26.035 139.7 0)
			(effects
				(font
					(size 1.27 1.27)
				)
				(justify left bottom)
				(hide yes)
			)
		)
		(property "Author" "Antmicro"
			(at 26.035 132.08 0)
			(effects
				(font
					(size 1.27 1.27)
					(thickness 0.15)
				)
				(justify left bottom)
				(hide yes)
			)
		)
		(property "License" "Apache-2.0"
			(at 26.035 134.62 0)
			(effects
				(font
					(size 1.27 1.27)
					(thickness 0.15)
				)
				(justify left bottom)
				(hide yes)
			)
		)
		(pin "1"
		)
		(instances
			(project "sodimm-ddr5-tester"
				(path ""
					(reference "#PWR0364")
					(unit 1)
				)
			)
		)
	)
	(symbol
		(lib_id "antmicroPMICORControllersIdealDiodes:LTC4412IS6")
		(at 67.945 65.405 0)
		(unit 1)
		(exclude_from_sim no)
		(in_bom yes)
		(on_board yes)
		(dnp no)
		(property "Reference" "U18"
			(at 76.835 59.055 0)
			(effects
				(font
					(size 1.27 1.27)
				)
			)
		)
		(property "Value" "LTC4412IS6"
			(at 76.835 61.595 0)
			(effects
				(font
					(size 1.27 1.27)
					(thickness 0.15)
				)
			)
		)
		(property "Footprint" "antmicro-footprints:SOT-23-6"
			(at 99.695 73.025 0)
			(effects
				(font
					(size 1.27 1.27)
					(thickness 0.15)
				)
				(justify left bottom)
				(hide yes)
			)
		)
		(property "Datasheet" "https://www.mouser.com/datasheet/2/308/NCV8187_D-1813214.pdf"
			(at 99.695 75.565 0)
			(effects
				(font
					(size 1.27 1.27)
					(thickness 0.15)
				)
				(justify left bottom)
				(hide yes)
			)
		)
		(property "Description" ""
			(at 67.945 65.405 0)
			(effects
				(font
					(size 1.27 1.27)
				)
			)
		)
		(property "MPN" "LTC4412IS6#TRMPBF"
			(at 99.695 78.105 0)
			(effects
				(font
					(size 1.27 1.27)
					(thickness 0.15)
				)
				(justify left bottom)
				(hide yes)
			)
		)
		(property "Manufacturer" "Analog Devices"
			(at 99.695 80.645 0)
			(effects
				(font
					(size 1.27 1.27)
					(thickness 0.15)
				)
				(justify left bottom)
				(hide yes)
			)
		)
		(property "Author" "Antmicro"
			(at 99.695 83.185 0)
			(effects
				(font
					(size 1.27 1.27)
					(thickness 0.15)
				)
				(justify left bottom)
				(hide yes)
			)
		)
		(property "License" "Apache-2.0"
			(at 99.695 85.725 0)
			(effects
				(font
					(size 1.27 1.27)
					(thickness 0.15)
				)
				(justify left bottom)
				(hide yes)
			)
		)
		(pin "1"
		)
		(pin "2"
		)
		(pin "3"
		)
		(pin "4"
		)
		(pin "5"
		)
		(pin "6"
		)
		(instances
			(project "sodimm-ddr5-tester"
				(path ""
					(reference "U18")
					(unit 1)
				)
			)
		)
	)
	(symbol
		(lib_id "antmicropower:GND")
		(at 256.54 61.595 0)
		(unit 1)
		(exclude_from_sim no)
		(in_bom yes)
		(on_board yes)
		(dnp no)
		(fields_autoplaced yes)
		(property "Reference" "#PWR0351"
			(at 256.54 67.945 0)
			(effects
				(font
					(size 1.27 1.27)
				)
				(hide yes)
			)
		)
		(property "Value" "GND"
			(at 259.08 62.865 0)
			(effects
				(font
					(size 1.27 1.27)
					(thickness 0.15)
				)
				(justify left)
			)
		)
		(property "Footprint" ""
			(at 265.43 69.215 0)
			(effects
				(font
					(size 1.27 1.27)
					(thickness 0.15)
				)
				(justify left bottom)
				(hide yes)
			)
		)
		(property "Datasheet" ""
			(at 265.43 74.295 0)
			(effects
				(font
					(size 1.27 1.27)
					(thickness 0.15)
				)
				(justify left bottom)
				(hide yes)
			)
		)
		(property "Description" ""
			(at 265.43 76.835 0)
			(effects
				(font
					(size 1.27 1.27)
				)
				(justify left bottom)
				(hide yes)
			)
		)
		(property "Author" "Antmicro"
			(at 265.43 69.215 0)
			(effects
				(font
					(size 1.27 1.27)
					(thickness 0.15)
				)
				(justify left bottom)
				(hide yes)
			)
		)
		(property "License" "Apache-2.0"
			(at 265.43 71.755 0)
			(effects
				(font
					(size 1.27 1.27)
					(thickness 0.15)
				)
				(justify left bottom)
				(hide yes)
			)
		)
		(pin "1"
		)
		(instances
			(project "sodimm-ddr5-tester"
				(path ""
					(reference "#PWR0351")
					(unit 1)
				)
			)
		)
	)
	(symbol
		(lib_id "antmicroResistors0402:R_0R_0402")
		(at 189.865 173.99 90)
		(unit 1)
		(exclude_from_sim no)
		(in_bom yes)
		(on_board yes)
		(dnp no)
		(fields_autoplaced yes)
		(property "Reference" "R162"
			(at 192.405 170.1799 90)
			(effects
				(font
					(size 1.27 1.27)
				)
				(justify right)
			)
		)
		(property "Value" "R_0R_0402"
			(at 202.565 153.67 0)
			(effects
				(font
					(size 1.27 1.27)
					(thickness 0.15)
				)
				(justify left bottom)
				(hide yes)
			)
		)
		(property "Footprint" "antmicro-footprints:R_0402_1005Metric"
			(at 205.105 153.67 0)
			(effects
				(font
					(size 1.27 1.27)
					(thickness 0.15)
				)
				(justify left bottom)
				(hide yes)
			)
		)
		(property "Datasheet" "https://industrial.panasonic.com/cdbs/www-data/pdf/RDA0000/AOA0000C301.pdf"
			(at 207.645 153.67 0)
			(effects
				(font
					(size 1.27 1.27)
					(thickness 0.15)
				)
				(justify left bottom)
				(hide yes)
			)
		)
		(property "Description" ""
			(at 189.865 173.99 0)
			(effects
				(font
					(size 1.27 1.27)
				)
			)
		)
		(property "Manufacturer" "Panasonic"
			(at 212.725 153.67 0)
			(effects
				(font
					(size 1.27 1.27)
					(thickness 0.15)
				)
				(justify left bottom)
				(hide yes)
			)
		)
		(property "MPN" "ERJ2GE0R00X"
			(at 210.185 153.67 0)
			(effects
				(font
					(size 1.27 1.27)
					(thickness 0.15)
				)
				(justify left bottom)
				(hide yes)
			)
		)
		(property "Val" "0R"
			(at 192.405 172.7199 90)
			(effects
				(font
					(size 1.27 1.27)
					(thickness 0.15)
				)
				(justify right)
			)
		)
		(property "License" "Apache-2.0"
			(at 215.265 153.67 0)
			(effects
				(font
					(size 1.27 1.27)
					(thickness 0.15)
				)
				(justify left bottom)
				(hide yes)
			)
		)
		(property "Author" "Antmicro"
			(at 217.805 153.67 0)
			(effects
				(font
					(size 1.27 1.27)
					(thickness 0.15)
				)
				(justify left bottom)
				(hide yes)
			)
		)
		(property "Tolerance" "~"
			(at 200.025 153.67 0)
			(effects
				(font
					(size 1.27 1.27)
				)
				(justify left bottom)
				(hide yes)
			)
		)
		(property "Current" "1A"
			(at 192.405 173.9899 90)
			(effects
				(font
					(size 1.27 1.27)
					(thickness 0.15)
				)
				(justify right)
				(hide yes)
			)
		)
		(pin "1"
		)
		(pin "2"
		)
		(instances
			(project "sodimm-ddr5-tester"
				(path ""
					(reference "R162")
					(unit 1)
				)
			)
		)
	)
	(symbol
		(lib_id "antmicroCapacitors0603:C_1u_25V_0603")
		(at 95.885 73.025 90)
		(unit 1)
		(exclude_from_sim no)
		(in_bom yes)
		(on_board yes)
		(dnp no)
		(property "Reference" "C180"
			(at 86.36 71.12 90)
			(effects
				(font
					(size 1.27 1.27)
				)
				(justify right)
			)
		)
		(property "Value" "C_1u_25V_0603"
			(at 106.045 52.705 0)
			(effects
				(font
					(size 1.27 1.27)
					(thickness 0.15)
				)
				(justify left bottom)
				(hide yes)
			)
		)
		(property "Footprint" "antmicro-footprints:C_0603_1608Metric"
			(at 108.585 52.705 0)
			(effects
				(font
					(size 1.27 1.27)
					(thickness 0.15)
				)
				(justify left bottom)
				(hide yes)
			)
		)
		(property "Datasheet" "https://product.samsungsem.com/mlcc/CL10A105KA8NNN.do"
			(at 111.125 52.705 0)
			(effects
				(font
					(size 1.27 1.27)
					(thickness 0.15)
				)
				(justify left bottom)
				(hide yes)
			)
		)
		(property "Description" ""
			(at 95.885 73.025 0)
			(effects
				(font
					(size 1.27 1.27)
				)
			)
		)
		(property "Manufacturer" "Samsung Electro-Mechanics"
			(at 116.205 52.705 0)
			(effects
				(font
					(size 1.27 1.27)
					(thickness 0.15)
				)
				(justify left bottom)
				(hide yes)
			)
		)
		(property "MPN" "CL10A105KA8NNNC"
			(at 113.665 52.705 0)
			(effects
				(font
					(size 1.27 1.27)
					(thickness 0.15)
				)
				(justify left bottom)
				(hide yes)
			)
		)
		(property "Val" "1u/25V"
			(at 86.36 73.66 90)
			(effects
				(font
					(size 1.27 1.27)
					(thickness 0.15)
				)
				(justify right)
			)
		)
		(property "License" "Apache-2.0"
			(at 118.745 52.705 0)
			(effects
				(font
					(size 1.27 1.27)
					(thickness 0.15)
				)
				(justify left bottom)
				(hide yes)
			)
		)
		(property "Author" "Antmicro"
			(at 121.285 52.705 0)
			(effects
				(font
					(size 1.27 1.27)
					(thickness 0.15)
				)
				(justify left bottom)
				(hide yes)
			)
		)
		(property "Voltage" ""
			(at 123.825 52.705 0)
			(effects
				(font
					(size 1.27 1.27)
				)
				(justify left bottom)
				(hide yes)
			)
		)
		(property "Dielectric" ""
			(at 126.365 52.705 0)
			(effects
				(font
					(size 1.27 1.27)
				)
				(justify left bottom)
				(hide yes)
			)
		)
		(pin "1"
		)
		(pin "2"
		)
		(instances
			(project "sodimm-ddr5-tester"
				(path ""
					(reference "C180")
					(unit 1)
				)
			)
		)
	)
	(symbol
		(lib_id "antmicropower:GND")
		(at 66.675 76.835 0)
		(unit 1)
		(exclude_from_sim no)
		(in_bom yes)
		(on_board yes)
		(dnp no)
		(fields_autoplaced yes)
		(property "Reference" "#PWR0293"
			(at 66.675 83.185 0)
			(effects
				(font
					(size 1.27 1.27)
				)
				(hide yes)
			)
		)
		(property "Value" "GND"
			(at 68.58 78.105 0)
			(effects
				(font
					(size 1.27 1.27)
					(thickness 0.15)
				)
				(justify left)
			)
		)
		(property "Footprint" ""
			(at 75.565 84.455 0)
			(effects
				(font
					(size 1.27 1.27)
					(thickness 0.15)
				)
				(justify left bottom)
				(hide yes)
			)
		)
		(property "Datasheet" ""
			(at 75.565 89.535 0)
			(effects
				(font
					(size 1.27 1.27)
					(thickness 0.15)
				)
				(justify left bottom)
				(hide yes)
			)
		)
		(property "Description" ""
			(at 75.565 92.075 0)
			(effects
				(font
					(size 1.27 1.27)
				)
				(justify left bottom)
				(hide yes)
			)
		)
		(property "Author" "Antmicro"
			(at 75.565 84.455 0)
			(effects
				(font
					(size 1.27 1.27)
					(thickness 0.15)
				)
				(justify left bottom)
				(hide yes)
			)
		)
		(property "License" "Apache-2.0"
			(at 75.565 86.995 0)
			(effects
				(font
					(size 1.27 1.27)
					(thickness 0.15)
				)
				(justify left bottom)
				(hide yes)
			)
		)
		(pin "1"
		)
		(instances
			(project "sodimm-ddr5-tester"
				(path ""
					(reference "#PWR0293")
					(unit 1)
				)
			)
		)
	)
	(symbol
		(lib_id "antmicroResistors0603:R_0R_22.4A_0603")
		(at 125.73 106.68 0)
		(unit 1)
		(exclude_from_sim no)
		(in_bom yes)
		(on_board yes)
		(dnp no)
		(property "Reference" "R189"
			(at 128.27 104.775 0)
			(effects
				(font
					(size 1.27 1.27)
				)
			)
		)
		(property "Value" "R_0R_22.4A_0603"
			(at 128.27 99.5823 0)
			(effects
				(font
					(size 1.27 1.27)
					(thickness 0.15)
				)
				(hide yes)
			)
		)
		(property "Footprint" "antmicro-footprints:R_0603_1608Metric"
			(at 148.59 119.38 0)
			(effects
				(font
					(size 1.27 1.27)
					(thickness 0.15)
				)
				(justify left bottom)
				(hide yes)
			)
		)
		(property "Datasheet" "https://fscdn.rohm.com/en/products/databook/datasheet/passive/resistor/chip_resistor/pmr-jpw-e.pdf"
			(at 148.59 121.92 0)
			(effects
				(font
					(size 1.27 1.27)
					(thickness 0.15)
				)
				(justify left bottom)
				(hide yes)
			)
		)
		(property "Description" ""
			(at 125.73 106.68 0)
			(effects
				(font
					(size 1.27 1.27)
				)
			)
		)
		(property "Manufacturer" "ROHM Semiconductor"
			(at 148.59 124.46 0)
			(effects
				(font
					(size 1.27 1.27)
					(thickness 0.15)
				)
				(justify left bottom)
				(hide yes)
			)
		)
		(property "MPN" "PMR03EZPJ000"
			(at 148.59 127 0)
			(effects
				(font
					(size 1.27 1.27)
					(thickness 0.15)
				)
				(justify left bottom)
				(hide yes)
			)
		)
		(property "Val" "0R"
			(at 128.27 109.22 0)
			(effects
				(font
					(size 1.27 1.27)
					(thickness 0.15)
				)
			)
		)
		(property "Author" "Antmicro"
			(at 148.59 129.54 0)
			(effects
				(font
					(size 1.27 1.27)
					(thickness 0.15)
				)
				(justify left bottom)
				(hide yes)
			)
		)
		(property "License" "Apache-2.0"
			(at 148.59 132.08 0)
			(effects
				(font
					(size 1.27 1.27)
					(thickness 0.15)
				)
				(justify left bottom)
				(hide yes)
			)
		)
		(property "Max. Curr." "22.4A"
			(at 128.27 111.7437 0)
			(effects
				(font
					(size 1.27 1.27)
					(thickness 0.15)
				)
			)
		)
		(pin "1"
		)
		(pin "2"
		)
		(instances
			(project "sodimm-ddr5-tester"
				(path ""
					(reference "R189")
					(unit 1)
				)
			)
		)
	)
	(symbol
		(lib_id "antmicropower:+1V0_MGTAVCC")
		(at 130.81 276.86 0)
		(unit 1)
		(exclude_from_sim no)
		(in_bom yes)
		(on_board yes)
		(dnp no)
		(fields_autoplaced yes)
		(property "Reference" "#PWR024"
			(at 130.81 280.67 0)
			(effects
				(font
					(size 1.27 1.27)
				)
				(hide yes)
			)
		)
		(property "Value" "+1V0_MGTAVCC"
			(at 130.81 273.05 0)
			(effects
				(font
					(size 1.27 1.27)
				)
			)
		)
		(property "Footprint" ""
			(at 130.81 276.86 0)
			(effects
				(font
					(size 1.27 1.27)
				)
				(hide yes)
			)
		)
		(property "Datasheet" ""
			(at 130.81 276.86 0)
			(effects
				(font
					(size 1.27 1.27)
				)
				(hide yes)
			)
		)
		(property "Description" ""
			(at 130.81 276.86 0)
			(effects
				(font
					(size 1.27 1.27)
				)
			)
		)
		(pin "1"
		)
		(instances
			(project "sodimm-ddr5-tester"
				(path ""
					(reference "#PWR024")
					(unit 1)
				)
			)
		)
	)
	(symbol
		(lib_id "antmicropower:GND")
		(at 61.595 258.445 0)
		(unit 1)
		(exclude_from_sim no)
		(in_bom yes)
		(on_board yes)
		(dnp no)
		(fields_autoplaced yes)
		(property "Reference" "#PWR0381"
			(at 61.595 264.795 0)
			(effects
				(font
					(size 1.27 1.27)
				)
				(hide yes)
			)
		)
		(property "Value" "GND"
			(at 63.5 259.715 0)
			(effects
				(font
					(size 1.27 1.27)
					(thickness 0.15)
				)
				(justify left)
			)
		)
		(property "Footprint" ""
			(at 70.485 266.065 0)
			(effects
				(font
					(size 1.27 1.27)
					(thickness 0.15)
				)
				(justify left bottom)
				(hide yes)
			)
		)
		(property "Datasheet" ""
			(at 70.485 271.145 0)
			(effects
				(font
					(size 1.27 1.27)
					(thickness 0.15)
				)
				(justify left bottom)
				(hide yes)
			)
		)
		(property "Description" ""
			(at 70.485 273.685 0)
			(effects
				(font
					(size 1.27 1.27)
				)
				(justify left bottom)
				(hide yes)
			)
		)
		(property "Author" "Antmicro"
			(at 70.485 266.065 0)
			(effects
				(font
					(size 1.27 1.27)
					(thickness 0.15)
				)
				(justify left bottom)
				(hide yes)
			)
		)
		(property "License" "Apache-2.0"
			(at 70.485 268.605 0)
			(effects
				(font
					(size 1.27 1.27)
					(thickness 0.15)
				)
				(justify left bottom)
				(hide yes)
			)
		)
		(pin "1"
		)
		(instances
			(project "sodimm-ddr5-tester"
				(path ""
					(reference "#PWR0381")
					(unit 1)
				)
			)
		)
	)
	(symbol
		(lib_id "antmicroTestPoints:TP_1mm_SMD")
		(at 229.87 281.94 0)
		(unit 1)
		(exclude_from_sim no)
		(in_bom yes)
		(on_board yes)
		(dnp no)
		(property "Reference" "TP58"
			(at 236.728 281.94 0)
			(effects
				(font
					(size 1.27 1.27)
				)
			)
		)
		(property "Value" "TP_1mm_SMD"
			(at 245.11 289.56 0)
			(effects
				(font
					(size 1.27 1.27)
					(thickness 0.15)
				)
				(justify left bottom)
				(hide yes)
			)
		)
		(property "Footprint" "antmicro-footprints:TP_SMD_1mm"
			(at 245.11 292.1 0)
			(effects
				(font
					(size 1.27 1.27)
					(thickness 0.15)
				)
				(justify left bottom)
				(hide yes)
			)
		)
		(property "Datasheet" ""
			(at 245.11 294.64 0)
			(effects
				(font
					(size 1.27 1.27)
					(thickness 0.15)
				)
				(justify left bottom)
				(hide yes)
			)
		)
		(property "Description" ""
			(at 229.87 281.94 0)
			(effects
				(font
					(size 1.27 1.27)
				)
			)
		)
		(property "MPN" ""
			(at 229.87 281.94 0)
			(effects
				(font
					(size 1.27 1.27)
				)
				(hide yes)
			)
		)
		(property "Manufacturer" ""
			(at 229.87 281.94 0)
			(effects
				(font
					(size 1.27 1.27)
				)
				(hide yes)
			)
		)
		(property "Author" "Antmicro"
			(at 245.11 297.18 0)
			(effects
				(font
					(size 1.27 1.27)
					(thickness 0.15)
				)
				(justify left bottom)
				(hide yes)
			)
		)
		(property "License" "Apache-2.0"
			(at 245.11 299.72 0)
			(effects
				(font
					(size 1.27 1.27)
					(thickness 0.15)
				)
				(justify left bottom)
				(hide yes)
			)
		)
		(pin "1"
		)
		(instances
			(project "sodimm-ddr5-tester"
				(path ""
					(reference "TP58")
					(unit 1)
				)
			)
		)
	)
	(symbol
		(lib_id "antmicropower:+1V2")
		(at 148.59 276.86 0)
		(unit 1)
		(exclude_from_sim no)
		(in_bom yes)
		(on_board yes)
		(dnp no)
		(property "Reference" "#PWR027"
			(at 148.59 280.67 0)
			(effects
				(font
					(size 1.27 1.27)
				)
				(hide yes)
			)
		)
		(property "Value" "+1V2"
			(at 148.59 273.304 0)
			(effects
				(font
					(size 1.27 1.27)
				)
			)
		)
		(property "Footprint" ""
			(at 148.59 276.86 0)
			(effects
				(font
					(size 1.27 1.27)
				)
				(hide yes)
			)
		)
		(property "Datasheet" ""
			(at 148.59 276.86 0)
			(effects
				(font
					(size 1.27 1.27)
				)
				(hide yes)
			)
		)
		(property "Description" ""
			(at 148.59 276.86 0)
			(effects
				(font
					(size 1.27 1.27)
				)
			)
		)
		(pin "1"
		)
		(instances
			(project "sodimm-ddr5-tester"
				(path ""
					(reference "#PWR027")
					(unit 1)
				)
			)
		)
	)
	(symbol
		(lib_id "antmicropower:+5V")
		(at 238.76 242.57 0)
		(unit 1)
		(exclude_from_sim no)
		(in_bom yes)
		(on_board yes)
		(dnp no)
		(fields_autoplaced yes)
		(property "Reference" "#PWR0356"
			(at 238.76 246.38 0)
			(effects
				(font
					(size 1.27 1.27)
				)
				(hide yes)
			)
		)
		(property "Value" "+5V"
			(at 238.76 238.9956 0)
			(effects
				(font
					(size 1.27 1.27)
					(thickness 0.15)
				)
			)
		)
		(property "Footprint" ""
			(at 254 250.19 0)
			(effects
				(font
					(size 1.27 1.27)
					(thickness 0.15)
				)
				(justify left bottom)
				(hide yes)
			)
		)
		(property "Datasheet" ""
			(at 254 252.73 0)
			(effects
				(font
					(size 1.27 1.27)
					(thickness 0.15)
				)
				(justify left bottom)
				(hide yes)
			)
		)
		(property "Description" ""
			(at 238.76 242.57 0)
			(effects
				(font
					(size 1.27 1.27)
				)
			)
		)
		(property "Author" "Antmicro"
			(at 254 250.19 0)
			(effects
				(font
					(size 1.27 1.27)
					(thickness 0.15)
				)
				(justify left bottom)
				(hide yes)
			)
		)
		(property "License" "Apache-2.0"
			(at 254 252.73 0)
			(effects
				(font
					(size 1.27 1.27)
					(thickness 0.15)
				)
				(justify left bottom)
				(hide yes)
			)
		)
		(pin "1"
		)
		(instances
			(project "sodimm-ddr5-tester"
				(path ""
					(reference "#PWR0356")
					(unit 1)
				)
			)
		)
	)
	(symbol
		(lib_id "antmicroTestPoints:TP_1mm_SMD")
		(at 200.66 278.13 0)
		(unit 1)
		(exclude_from_sim no)
		(in_bom yes)
		(on_board yes)
		(dnp no)
		(property "Reference" "TP56"
			(at 207.264 278.13 0)
			(effects
				(font
					(size 1.27 1.27)
				)
			)
		)
		(property "Value" "TP_1mm_SMD"
			(at 215.9 285.75 0)
			(effects
				(font
					(size 1.27 1.27)
					(thickness 0.15)
				)
				(justify left bottom)
				(hide yes)
			)
		)
		(property "Footprint" "antmicro-footprints:TP_SMD_1mm"
			(at 215.9 288.29 0)
			(effects
				(font
					(size 1.27 1.27)
					(thickness 0.15)
				)
				(justify left bottom)
				(hide yes)
			)
		)
		(property "Datasheet" ""
			(at 215.9 290.83 0)
			(effects
				(font
					(size 1.27 1.27)
					(thickness 0.15)
				)
				(justify left bottom)
				(hide yes)
			)
		)
		(property "Description" ""
			(at 200.66 278.13 0)
			(effects
				(font
					(size 1.27 1.27)
				)
			)
		)
		(property "MPN" ""
			(at 200.66 278.13 0)
			(effects
				(font
					(size 1.27 1.27)
				)
				(hide yes)
			)
		)
		(property "Manufacturer" ""
			(at 200.66 278.13 0)
			(effects
				(font
					(size 1.27 1.27)
				)
				(hide yes)
			)
		)
		(property "Author" "Antmicro"
			(at 215.9 293.37 0)
			(effects
				(font
					(size 1.27 1.27)
					(thickness 0.15)
				)
				(justify left bottom)
				(hide yes)
			)
		)
		(property "License" "Apache-2.0"
			(at 215.9 295.91 0)
			(effects
				(font
					(size 1.27 1.27)
					(thickness 0.15)
				)
				(justify left bottom)
				(hide yes)
			)
		)
		(pin "1"
		)
		(instances
			(project "sodimm-ddr5-tester"
				(path ""
					(reference "TP56")
					(unit 1)
				)
			)
		)
	)
	(symbol
		(lib_id "antmicroResistors0402:R_0R_0402")
		(at 355.6 172.085 90)
		(unit 1)
		(exclude_from_sim no)
		(in_bom yes)
		(on_board yes)
		(dnp no)
		(fields_autoplaced yes)
		(property "Reference" "R155"
			(at 358.14 168.2749 90)
			(effects
				(font
					(size 1.27 1.27)
				)
				(justify right)
			)
		)
		(property "Value" "R_0R_0402"
			(at 368.3 151.765 0)
			(effects
				(font
					(size 1.27 1.27)
					(thickness 0.15)
				)
				(justify left bottom)
				(hide yes)
			)
		)
		(property "Footprint" "antmicro-footprints:R_0402_1005Metric"
			(at 370.84 151.765 0)
			(effects
				(font
					(size 1.27 1.27)
					(thickness 0.15)
				)
				(justify left bottom)
				(hide yes)
			)
		)
		(property "Datasheet" "https://industrial.panasonic.com/cdbs/www-data/pdf/RDA0000/AOA0000C301.pdf"
			(at 373.38 151.765 0)
			(effects
				(font
					(size 1.27 1.27)
					(thickness 0.15)
				)
				(justify left bottom)
				(hide yes)
			)
		)
		(property "Description" ""
			(at 355.6 172.085 0)
			(effects
				(font
					(size 1.27 1.27)
				)
			)
		)
		(property "Manufacturer" "Panasonic"
			(at 378.46 151.765 0)
			(effects
				(font
					(size 1.27 1.27)
					(thickness 0.15)
				)
				(justify left bottom)
				(hide yes)
			)
		)
		(property "MPN" "ERJ2GE0R00X"
			(at 375.92 151.765 0)
			(effects
				(font
					(size 1.27 1.27)
					(thickness 0.15)
				)
				(justify left bottom)
				(hide yes)
			)
		)
		(property "Val" "0R"
			(at 358.14 170.8149 90)
			(effects
				(font
					(size 1.27 1.27)
					(thickness 0.15)
				)
				(justify right)
			)
		)
		(property "License" "Apache-2.0"
			(at 381 151.765 0)
			(effects
				(font
					(size 1.27 1.27)
					(thickness 0.15)
				)
				(justify left bottom)
				(hide yes)
			)
		)
		(property "Author" "Antmicro"
			(at 383.54 151.765 0)
			(effects
				(font
					(size 1.27 1.27)
					(thickness 0.15)
				)
				(justify left bottom)
				(hide yes)
			)
		)
		(property "Tolerance" "~"
			(at 365.76 151.765 0)
			(effects
				(font
					(size 1.27 1.27)
				)
				(justify left bottom)
				(hide yes)
			)
		)
		(property "Current" "1A"
			(at 358.14 172.0849 90)
			(effects
				(font
					(size 1.27 1.27)
					(thickness 0.15)
				)
				(justify right)
				(hide yes)
			)
		)
		(pin "1"
		)
		(pin "2"
		)
		(instances
			(project "sodimm-ddr5-tester"
				(path ""
					(reference "R155")
					(unit 1)
				)
			)
		)
	)
	(symbol
		(lib_id "antmicroShuntsJumpers:Net-Tie_P0.127mm")
		(at 118.745 220.98 90)
		(unit 1)
		(exclude_from_sim no)
		(in_bom no)
		(on_board yes)
		(dnp no)
		(fields_autoplaced yes)
		(property "Reference" "NT12"
			(at 117.475 220.98 0)
			(effects
				(font
					(size 1.27 1.27)
				)
				(hide yes)
			)
		)
		(property "Value" "Net-Tie_P0.127mm"
			(at 126.365 199.39 0)
			(effects
				(font
					(size 1.27 1.27)
					(thickness 0.15)
				)
				(justify left bottom)
				(hide yes)
			)
		)
		(property "Footprint" "antmicro-footprints:NetTie-2_SMD_Pad0.127mm"
			(at 131.445 199.39 0)
			(effects
				(font
					(size 1.27 1.27)
					(thickness 0.15)
				)
				(justify left bottom)
				(hide yes)
			)
		)
		(property "Datasheet" ""
			(at 133.985 199.39 0)
			(effects
				(font
					(size 1.27 1.27)
					(thickness 0.15)
				)
				(justify left bottom)
				(hide yes)
			)
		)
		(property "Description" ""
			(at 118.745 220.98 0)
			(effects
				(font
					(size 1.27 1.27)
				)
			)
		)
		(property "MPN" ""
			(at 128.905 199.39 0)
			(effects
				(font
					(size 1.27 1.27)
					(thickness 0.15)
				)
				(justify left bottom)
			)
		)
		(property "Manufacturer" ""
			(at 136.525 199.39 0)
			(effects
				(font
					(size 1.27 1.27)
					(thickness 0.15)
				)
				(justify left bottom)
				(hide yes)
			)
		)
		(property "Author" "Antmicro"
			(at 139.065 199.39 0)
			(effects
				(font
					(size 1.27 1.27)
					(thickness 0.15)
				)
				(justify left bottom)
				(hide yes)
			)
		)
		(property "License" "Apache-2.0"
			(at 141.605 199.39 0)
			(effects
				(font
					(size 1.27 1.27)
					(thickness 0.15)
				)
				(justify left bottom)
				(hide yes)
			)
		)
		(pin "1"
		)
		(pin "2"
		)
		(instances
			(project "sodimm-ddr5-tester"
				(path ""
					(reference "NT12")
					(unit 1)
				)
			)
		)
	)
	(symbol
		(lib_id "antmicropower:+3V3_AON")
		(at 286.893 31.115 0)
		(mirror y)
		(unit 1)
		(exclude_from_sim no)
		(in_bom yes)
		(on_board yes)
		(dnp no)
		(property "Reference" "#PWR0368"
			(at 286.893 34.925 0)
			(effects
				(font
					(size 1.27 1.27)
				)
				(hide yes)
			)
		)
		(property "Value" "+3V3_AON"
			(at 286.893 27.305 0)
			(effects
				(font
					(size 1.27 1.27)
				)
			)
		)
		(property "Footprint" ""
			(at 286.893 31.115 0)
			(effects
				(font
					(size 1.27 1.27)
				)
				(hide yes)
			)
		)
		(property "Datasheet" ""
			(at 286.893 31.115 0)
			(effects
				(font
					(size 1.27 1.27)
				)
				(hide yes)
			)
		)
		(property "Description" ""
			(at 286.893 31.115 0)
			(effects
				(font
					(size 1.27 1.27)
				)
			)
		)
		(pin "1"
		)
		(instances
			(project "sodimm-ddr5-tester"
				(path ""
					(reference "#PWR0368")
					(unit 1)
				)
			)
		)
	)
	(symbol
		(lib_id "antmicropower:GND")
		(at 86.995 191.135 0)
		(unit 1)
		(exclude_from_sim no)
		(in_bom yes)
		(on_board yes)
		(dnp no)
		(fields_autoplaced yes)
		(property "Reference" "#PWR0305"
			(at 86.995 197.485 0)
			(effects
				(font
					(size 1.27 1.27)
				)
				(hide yes)
			)
		)
		(property "Value" "GND"
			(at 88.9 192.405 0)
			(effects
				(font
					(size 1.27 1.27)
					(thickness 0.15)
				)
				(justify left)
			)
		)
		(property "Footprint" ""
			(at 95.885 198.755 0)
			(effects
				(font
					(size 1.27 1.27)
					(thickness 0.15)
				)
				(justify left bottom)
				(hide yes)
			)
		)
		(property "Datasheet" ""
			(at 95.885 203.835 0)
			(effects
				(font
					(size 1.27 1.27)
					(thickness 0.15)
				)
				(justify left bottom)
				(hide yes)
			)
		)
		(property "Description" ""
			(at 95.885 206.375 0)
			(effects
				(font
					(size 1.27 1.27)
				)
				(justify left bottom)
				(hide yes)
			)
		)
		(property "Author" "Antmicro"
			(at 95.885 198.755 0)
			(effects
				(font
					(size 1.27 1.27)
					(thickness 0.15)
				)
				(justify left bottom)
				(hide yes)
			)
		)
		(property "License" "Apache-2.0"
			(at 95.885 201.295 0)
			(effects
				(font
					(size 1.27 1.27)
					(thickness 0.15)
				)
				(justify left bottom)
				(hide yes)
			)
		)
		(pin "1"
		)
		(instances
			(project "sodimm-ddr5-tester"
				(path ""
					(reference "#PWR0305")
					(unit 1)
				)
			)
		)
	)
	(symbol
		(lib_id "antmicroPMICVoltageRegulatorsLinear:XC6230H001ER-G")
		(at 41.275 247.015 0)
		(unit 1)
		(exclude_from_sim no)
		(in_bom yes)
		(on_board yes)
		(dnp no)
		(property "Reference" "U28"
			(at 48.895 240.665 0)
			(effects
				(font
					(size 1.27 1.27)
				)
			)
		)
		(property "Value" "XC6230H001ER-G"
			(at 48.895 243.205 0)
			(effects
				(font
					(size 1.27 1.27)
					(thickness 0.15)
				)
			)
		)
		(property "Footprint" "antmicro-footprints:Torex_USP-6C"
			(at 71.755 254.635 0)
			(effects
				(font
					(size 1.27 1.27)
					(thickness 0.15)
				)
				(justify left bottom)
				(hide yes)
			)
		)
		(property "Datasheet" "https://www.torexsemi.com/file/xc6230/XC6230.pdf"
			(at 71.755 257.175 0)
			(effects
				(font
					(size 1.27 1.27)
					(thickness 0.15)
				)
				(justify left bottom)
				(hide yes)
			)
		)
		(property "Description" ""
			(at 41.275 247.015 0)
			(effects
				(font
					(size 1.27 1.27)
				)
			)
		)
		(property "MPN" "XC6230H001ER-G"
			(at 71.755 259.715 0)
			(effects
				(font
					(size 1.27 1.27)
					(thickness 0.15)
				)
				(justify left bottom)
				(hide yes)
			)
		)
		(property "Manufacturer" "Torex Semiconductor"
			(at 71.755 262.255 0)
			(effects
				(font
					(size 1.27 1.27)
					(thickness 0.15)
				)
				(justify left bottom)
				(hide yes)
			)
		)
		(property "Author" "Antmicro"
			(at 71.755 264.795 0)
			(effects
				(font
					(size 1.27 1.27)
					(thickness 0.15)
				)
				(justify left bottom)
				(hide yes)
			)
		)
		(property "License" "Apache-2.0"
			(at 71.755 267.335 0)
			(effects
				(font
					(size 1.27 1.27)
					(thickness 0.15)
				)
				(justify left bottom)
				(hide yes)
			)
		)
		(pin "1"
		)
		(pin "2"
		)
		(pin "3"
		)
		(pin "4"
		)
		(pin "5"
		)
		(pin "6"
		)
		(pin "7"
		)
		(instances
			(project "sodimm-ddr5-tester"
				(path ""
					(reference "U28")
					(unit 1)
				)
			)
		)
	)
	(symbol
		(lib_id "antmicropower:+3V3_AON")
		(at 204.47 96.52 0)
		(mirror y)
		(unit 1)
		(exclude_from_sim no)
		(in_bom yes)
		(on_board yes)
		(dnp no)
		(property "Reference" "#PWR0294"
			(at 204.47 100.33 0)
			(effects
				(font
					(size 1.27 1.27)
				)
				(hide yes)
			)
		)
		(property "Value" "+3V3_AON"
			(at 198.12 93.98 0)
			(effects
				(font
					(size 1.27 1.27)
				)
			)
		)
		(property "Footprint" ""
			(at 204.47 96.52 0)
			(effects
				(font
					(size 1.27 1.27)
				)
				(hide yes)
			)
		)
		(property "Datasheet" ""
			(at 204.47 96.52 0)
			(effects
				(font
					(size 1.27 1.27)
				)
				(hide yes)
			)
		)
		(property "Description" ""
			(at 204.47 96.52 0)
			(effects
				(font
					(size 1.27 1.27)
				)
			)
		)
		(pin "1"
		)
		(instances
			(project "sodimm-ddr5-tester"
				(path ""
					(reference "#PWR0294")
					(unit 1)
				)
			)
		)
	)
	(symbol
		(lib_id "antmicroCapacitors0402:C_470n_0402")
		(at 17.145 121.92 90)
		(unit 1)
		(exclude_from_sim no)
		(in_bom yes)
		(on_board yes)
		(dnp no)
		(fields_autoplaced yes)
		(property "Reference" "C201"
			(at 20.32 118.1035 90)
			(effects
				(font
					(size 1.27 1.27)
				)
				(justify right)
			)
		)
		(property "Value" "C_470n_0402"
			(at 27.305 101.6 0)
			(effects
				(font
					(size 1.27 1.27)
					(thickness 0.15)
				)
				(justify left bottom)
				(hide yes)
			)
		)
		(property "Footprint" "antmicro-footprints:C_0402_1005Metric"
			(at 29.845 101.6 0)
			(effects
				(font
					(size 1.27 1.27)
					(thickness 0.15)
				)
				(justify left bottom)
				(hide yes)
			)
		)
		(property "Datasheet" "https://product.tdk.com/en/search/capacitor/ceramic/mlcc/info?part_no=C1005X5R1E474M050BB"
			(at 32.385 101.6 0)
			(effects
				(font
					(size 1.27 1.27)
					(thickness 0.15)
				)
				(justify left bottom)
				(hide yes)
			)
		)
		(property "Description" ""
			(at 17.145 121.92 0)
			(effects
				(font
					(size 1.27 1.27)
				)
			)
		)
		(property "Manufacturer" "TDK"
			(at 37.465 101.6 0)
			(effects
				(font
					(size 1.27 1.27)
					(thickness 0.15)
				)
				(justify left bottom)
				(hide yes)
			)
		)
		(property "MPN" "C1005X5R1E474M050BB"
			(at 34.925 101.6 0)
			(effects
				(font
					(size 1.27 1.27)
					(thickness 0.15)
				)
				(justify left bottom)
				(hide yes)
			)
		)
		(property "Val" "470n"
			(at 20.32 120.6435 90)
			(effects
				(font
					(size 1.27 1.27)
					(thickness 0.15)
				)
				(justify right)
			)
		)
		(property "License" "Apache-2.0"
			(at 40.005 101.6 0)
			(effects
				(font
					(size 1.27 1.27)
					(thickness 0.15)
				)
				(justify left bottom)
				(hide yes)
			)
		)
		(property "Author" "Antmicro"
			(at 42.545 101.6 0)
			(effects
				(font
					(size 1.27 1.27)
					(thickness 0.15)
				)
				(justify left bottom)
				(hide yes)
			)
		)
		(property "Voltage" ""
			(at 45.085 101.6 0)
			(effects
				(font
					(size 1.27 1.27)
				)
				(justify left bottom)
				(hide yes)
			)
		)
		(property "Dielectric" ""
			(at 47.625 101.6 0)
			(effects
				(font
					(size 1.27 1.27)
				)
				(justify left bottom)
				(hide yes)
			)
		)
		(pin "1"
		)
		(pin "2"
		)
		(instances
			(project "sodimm-ddr5-tester"
				(path ""
					(reference "C201")
					(unit 1)
				)
			)
		)
	)
	(symbol
		(lib_id "antmicropower:GND")
		(at 160.02 214.63 0)
		(unit 1)
		(exclude_from_sim no)
		(in_bom yes)
		(on_board yes)
		(dnp no)
		(fields_autoplaced yes)
		(property "Reference" "#PWR0336"
			(at 160.02 220.98 0)
			(effects
				(font
					(size 1.27 1.27)
				)
				(hide yes)
			)
		)
		(property "Value" "GND"
			(at 162.56 215.9 0)
			(effects
				(font
					(size 1.27 1.27)
					(thickness 0.15)
				)
				(justify left)
			)
		)
		(property "Footprint" ""
			(at 168.91 222.25 0)
			(effects
				(font
					(size 1.27 1.27)
					(thickness 0.15)
				)
				(justify left bottom)
				(hide yes)
			)
		)
		(property "Datasheet" ""
			(at 168.91 227.33 0)
			(effects
				(font
					(size 1.27 1.27)
					(thickness 0.15)
				)
				(justify left bottom)
				(hide yes)
			)
		)
		(property "Description" ""
			(at 168.91 229.87 0)
			(effects
				(font
					(size 1.27 1.27)
				)
				(justify left bottom)
				(hide yes)
			)
		)
		(property "Author" "Antmicro"
			(at 168.91 222.25 0)
			(effects
				(font
					(size 1.27 1.27)
					(thickness 0.15)
				)
				(justify left bottom)
				(hide yes)
			)
		)
		(property "License" "Apache-2.0"
			(at 168.91 224.79 0)
			(effects
				(font
					(size 1.27 1.27)
					(thickness 0.15)
				)
				(justify left bottom)
				(hide yes)
			)
		)
		(pin "1"
		)
		(instances
			(project "sodimm-ddr5-tester"
				(path ""
					(reference "#PWR0336")
					(unit 1)
				)
			)
		)
	)
	(symbol
		(lib_id "antmicropower:GND")
		(at 17.145 106.045 0)
		(unit 1)
		(exclude_from_sim no)
		(in_bom yes)
		(on_board yes)
		(dnp no)
		(fields_autoplaced yes)
		(property "Reference" "#PWR0363"
			(at 17.145 112.395 0)
			(effects
				(font
					(size 1.27 1.27)
				)
				(hide yes)
			)
		)
		(property "Value" "GND"
			(at 19.05 107.315 0)
			(effects
				(font
					(size 1.27 1.27)
					(thickness 0.15)
				)
				(justify left)
			)
		)
		(property "Footprint" ""
			(at 26.035 113.665 0)
			(effects
				(font
					(size 1.27 1.27)
					(thickness 0.15)
				)
				(justify left bottom)
				(hide yes)
			)
		)
		(property "Datasheet" ""
			(at 26.035 118.745 0)
			(effects
				(font
					(size 1.27 1.27)
					(thickness 0.15)
				)
				(justify left bottom)
				(hide yes)
			)
		)
		(property "Description" ""
			(at 26.035 121.285 0)
			(effects
				(font
					(size 1.27 1.27)
				)
				(justify left bottom)
				(hide yes)
			)
		)
		(property "Author" "Antmicro"
			(at 26.035 113.665 0)
			(effects
				(font
					(size 1.27 1.27)
					(thickness 0.15)
				)
				(justify left bottom)
				(hide yes)
			)
		)
		(property "License" "Apache-2.0"
			(at 26.035 116.205 0)
			(effects
				(font
					(size 1.27 1.27)
					(thickness 0.15)
				)
				(justify left bottom)
				(hide yes)
			)
		)
		(pin "1"
		)
		(instances
			(project "sodimm-ddr5-tester"
				(path ""
					(reference "#PWR0363")
					(unit 1)
				)
			)
		)
	)
)
